G04 ================== begin FILE IDENTIFICATION RECORD ==================*
G04 Layout Name:  15105-sa.brd*
G04 Film Name:    BSILK*
G04 File Format:  Gerber RS274X*
G04 File Origin:  Cadence Allegro 16.5-S056*
G04 Origin Date:  Wed Nov 16 02:01:44 2016*
G04 *
G04 Layer:  VIA CLASS/FILMMASKBOTTOM*
G04 Layer:  REF DES/ASSEMBLY_BOTTOM*
G04 Layer:  PACKAGE GEOMETRY/SILKSCREEN_BOTTOM*
G04 Layer:  DRAWING FORMAT/LAYER_PCB_STORY*
G04 Layer:  DRAWING FORMAT/LAYER_SILK_B*
G04 Layer:  BOARD GEOMETRY/SILKSCREEN_BOTTOM*
G04 *
G04 Offset:    (0.00 0.00)*
G04 Mirror:    No*
G04 Mode:      Positive*
G04 Rotation:  0*
G04 FullContactRelief:  No*
G04 UndefLineWidth:     6.00*
G04 ================== end FILE IDENTIFICATION RECORD ====================*
%FSLAX35Y35*MOIN*%
%IR0*IPPOS*OFA0.00000B0.00000*MIA0B0*SFA1.00000B1.00000*%
%ADD10C,.024*%
%ADD11C,.02*%
%ADD12C,.013*%
%ADD13C,.015*%
%ADD14C,.019*%
%ADD15C,.006*%
%ADD16C,.008*%
G75*
%LPD*%
G75*
G36*
G01X1022579Y31810D02*
Y19870D01*
X1018179D01*
Y31810D01*
X1022579D01*
G37*
G54D10*
X48000Y426000D03*
Y422500D03*
Y429500D03*
X59300Y734900D03*
X54300Y729900D03*
X49300Y734900D03*
X54300Y739900D03*
Y734900D03*
X71500Y297900D03*
X77100Y303800D03*
X65400D03*
X65500Y291900D03*
X77500D03*
X140500Y390500D03*
X145500Y385500D03*
X143000Y388000D03*
X264500Y142750D03*
X254500D03*
X259500Y143250D03*
Y147750D03*
Y160750D03*
Y156250D03*
X264397Y160977D03*
X264500Y157250D03*
Y153750D03*
Y150250D03*
Y146250D03*
X259500Y152000D03*
X254500Y161250D03*
Y157250D03*
Y153750D03*
Y150250D03*
Y146250D03*
X259300Y632400D03*
Y639300D03*
Y635900D03*
X560531Y358080D03*
X564100Y358100D03*
X556500Y358000D03*
X597763Y242608D03*
X602763Y240858D03*
X597763Y231608D03*
Y235108D03*
Y239108D03*
X602763Y236608D03*
Y232108D03*
X597763Y246108D03*
Y250108D03*
X602763Y245108D03*
Y249608D03*
X607763Y242608D03*
Y231608D03*
Y235108D03*
Y239108D03*
Y246108D03*
Y250108D03*
X633000Y356600D03*
Y360500D03*
Y353000D03*
X636500Y356500D03*
X629500D03*
X1337000Y263250D03*
X1332000Y261500D03*
Y265000D03*
Y268500D03*
Y272500D03*
Y257500D03*
Y254000D03*
X1342000D03*
Y257500D03*
Y261500D03*
Y265000D03*
Y268500D03*
Y272500D03*
X1337000Y267500D03*
Y272000D03*
Y259000D03*
Y254500D03*
G54D11*
G01X35100Y271300D02*
Y266300D01*
G01X35900Y281000D02*
Y276000D01*
G01X36000Y310800D02*
Y305800D01*
G01X60900Y312600D02*
Y317600D01*
G01X53300Y338500D02*
X48300D01*
G01X127746Y-260199D02*
X95746D01*
G01X82900Y264600D02*
X87900D01*
G01X85976Y293798D02*
Y288798D01*
G01X90061Y321527D02*
X85061D01*
G01X127746Y-276199D02*
Y-356199D01*
G01D02*
X1310146D01*
G01X127746Y-311699D02*
X1310146D01*
G01X123746Y-260199D02*
G02I-12000J0D01*
G01X118596D02*
G02I-6850J0D01*
G01X111746Y-276199D02*
Y-244199D01*
G01X127746Y-276199D02*
X1310146D01*
G01X101820Y304620D02*
Y309620D01*
G01X226000Y146500D02*
X231000D01*
G01X252500Y174500D02*
Y179500D01*
G01Y182500D02*
Y187500D01*
G01X522646Y-276199D02*
Y-356199D01*
G01X579863Y233608D02*
X584863D01*
G01X596563Y254108D02*
Y259108D01*
G01X573863Y256108D02*
Y251108D01*
G01X624800Y359600D02*
Y364600D01*
G01X660146Y-276199D02*
Y-356199D01*
G01X666663Y246908D02*
X671663D01*
G01X690663D02*
X695663D01*
G01X674663D02*
X679663D01*
G01X682663D02*
X687663D01*
G01X707200Y282000D02*
X702200D01*
G01X706100Y242500D02*
X711100D01*
G01X714100D02*
X719100D01*
G01X722100D02*
X727100D01*
G01X730100D02*
X735100D01*
G01X722400Y282000D02*
X717400D01*
G01X714800D02*
X709800D01*
G01X737600D02*
X732600D01*
G01X730000D02*
X725000D01*
G01X775146Y-276199D02*
Y-356199D01*
G01X926500Y269500D02*
Y264500D01*
G01Y277500D02*
Y272500D01*
G01Y285500D02*
Y280500D01*
G01X942646Y-276199D02*
Y-356199D01*
G01X969000Y265000D02*
Y270000D01*
G01Y273000D02*
Y278000D01*
G01Y281000D02*
Y286000D01*
G01X1022579Y33970D02*
X1028679D01*
G01X1112646Y-276199D02*
Y-356199D01*
G01X1239500Y218000D02*
X1244500D01*
G01X1231500D02*
X1236500D01*
G01X1239000Y270000D02*
X1234000D01*
G01X1231000D02*
X1226000D01*
G01X1247000D02*
X1242000D01*
G01X1247500Y218000D02*
X1252500D01*
G01X1256000D02*
X1261000D01*
G01X1255000Y270000D02*
X1250000D01*
G01X1263000D02*
X1258000D01*
G01X1310146Y-276199D02*
Y-356199D01*
G01X1342146Y-260199D02*
X1310146D01*
G01X1338146D02*
G02I-12000J0D01*
G01X1332996D02*
G02I-6850J0D01*
G01X1326146Y-276199D02*
Y-244199D01*
G01X1342500Y242500D02*
Y237500D01*
G01Y250500D02*
Y245500D01*
G01X1366000Y264000D02*
X1361000D01*
G54D12*
G01X273122Y753569D02*
X270272D01*
Y750869D01*
G01X290400Y753600D02*
X287550D01*
Y750900D01*
G01X306400Y753600D02*
X303550D01*
Y750900D01*
G01X322400Y753600D02*
X319550D01*
Y750900D01*
G01X486622Y805569D02*
X483772D01*
Y802869D01*
G01X503400Y805600D02*
X500550D01*
Y802900D01*
G01X535400Y805600D02*
X532550D01*
Y802900D01*
G01X519400Y805600D02*
X516550D01*
Y802900D01*
G01X873100Y33500D02*
X875950D01*
Y36200D01*
G01X862900Y782600D02*
X860050D01*
Y779900D01*
G01X846622Y783069D02*
X843772D01*
Y780369D01*
G01X892900Y782600D02*
X890050D01*
Y779900D01*
G01X876900Y782600D02*
X874050D01*
Y779900D01*
G01X1307622Y710569D02*
X1304772D01*
Y707869D01*
G01X1341622Y711069D02*
X1338772D01*
Y708369D01*
G01X1325122Y711069D02*
X1322272D01*
Y708369D01*
G01X1376774Y171895D02*
X1379624D01*
Y174595D01*
G54D13*
G01X0Y212205D02*
Y237402D01*
G01Y212205D02*
Y237402D01*
G01Y431890D02*
Y406693D01*
G01Y431890D02*
Y406693D01*
G01Y601181D02*
Y626378D01*
G01Y601181D02*
Y626378D01*
G01Y795669D02*
Y820866D01*
G01Y795669D02*
Y820866D01*
G01X123622Y102402D02*
X98425D01*
G01X123622D02*
X98425D01*
G01X232077Y0D02*
X257274D01*
G01X232077D02*
X257274D01*
G01X204528Y29961D02*
Y55157D01*
G01Y29961D02*
Y55157D01*
G01X459636Y0D02*
X434439D01*
G01X459636D02*
X434439D01*
G01X707234Y-19685D02*
X732431D01*
G01X707234D02*
X732431D01*
G01X895423D02*
X870226D01*
G01X895423D02*
X870226D01*
G01X1097785D02*
X1072589D01*
G01X1097785D02*
X1072589D01*
G01X1361283Y0D02*
X1336086D01*
G01X1400000Y30709D02*
Y13026D01*
G01Y219685D02*
Y244882D01*
G01Y219685D02*
Y244882D01*
G01Y439370D02*
Y414173D01*
G01Y439370D02*
Y414173D01*
G01Y626378D02*
Y608661D01*
G01Y626378D02*
Y608661D01*
G01Y795669D02*
Y820866D01*
G01Y795669D02*
Y820866D01*
G54D14*
G01X197300Y416600D02*
X193900D01*
G01X205638Y428845D02*
X209038D01*
G01X248400Y458600D02*
Y462000D01*
G54D15*
G01X145579Y-328699D02*
Y-346199D01*
X154313D01*
G01X167446Y-334533D02*
Y-346199D01*
G01Y-329866D02*
X167009Y-329574D01*
Y-328991D01*
X167446Y-328699D01*
X167883Y-328991D01*
Y-329574D01*
X167446Y-329866D01*
G01X181889Y-350574D02*
X183418Y-351741D01*
X185164Y-352032D01*
X186692Y-351741D01*
X188003Y-350283D01*
X188876Y-348241D01*
Y-334533D01*
G01Y-336866D02*
X188003Y-335699D01*
X186692Y-334824D01*
X185164Y-334533D01*
X183418Y-335116D01*
X182326Y-336282D01*
X181452Y-338324D01*
X181016Y-340366D01*
X181234Y-342116D01*
X182108Y-344158D01*
X183418Y-345616D01*
X185164Y-346199D01*
X186474Y-345907D01*
X188003Y-344741D01*
X188876Y-343575D01*
G01X198734Y-346199D02*
Y-328699D01*
G01Y-337157D02*
X199826Y-335699D01*
X200918Y-334824D01*
X202664Y-334533D01*
X203974Y-334824D01*
X205503Y-335991D01*
X206158Y-337741D01*
Y-346199D01*
G01X219946Y-328699D02*
Y-346199D01*
G01X216889Y-334533D02*
X223003D01*
G01X233734Y-346199D02*
Y-334533D01*
G01Y-337449D02*
X234608Y-335991D01*
X235918Y-334824D01*
X237664Y-334533D01*
X239192Y-334824D01*
X240503Y-335991D01*
X241158Y-338032D01*
Y-346199D01*
G01X254946Y-334533D02*
Y-346199D01*
G01Y-329866D02*
X254509Y-329574D01*
Y-328991D01*
X254946Y-328699D01*
X255383Y-328991D01*
Y-329574D01*
X254946Y-329866D01*
G01X268734Y-346199D02*
Y-334533D01*
G01Y-337449D02*
X269608Y-335991D01*
X270918Y-334824D01*
X272664Y-334533D01*
X274192Y-334824D01*
X275503Y-335991D01*
X276158Y-338032D01*
Y-346199D01*
G01X286889Y-350574D02*
X288418Y-351741D01*
X290164Y-352032D01*
X291692Y-351741D01*
X293003Y-350283D01*
X293876Y-348241D01*
Y-334533D01*
G01Y-336866D02*
X293003Y-335699D01*
X291692Y-334824D01*
X290164Y-334533D01*
X288418Y-335116D01*
X287326Y-336282D01*
X286452Y-338324D01*
X286016Y-340366D01*
X286234Y-342116D01*
X287108Y-344158D01*
X288418Y-345616D01*
X290164Y-346199D01*
X291474Y-345907D01*
X293003Y-344741D01*
X293876Y-343575D01*
G01X320579Y-346199D02*
Y-328699D01*
X325819D01*
X327566Y-329574D01*
X328876Y-331616D01*
X329313Y-333949D01*
X328876Y-336282D01*
X327784Y-338032D01*
X325819Y-338908D01*
X320579D01*
G01X346813Y-346199D02*
X338079D01*
Y-328699D01*
X346813D01*
G01X343319Y-337157D02*
X338079D01*
G01X361692Y-336866D02*
X362566Y-335991D01*
X363221Y-334533D01*
X363658Y-332490D01*
X363221Y-330741D01*
X362348Y-329574D01*
X360819Y-328699D01*
X354924D01*
Y-346199D01*
X362129D01*
X363658Y-345033D01*
X364531Y-343282D01*
X364968Y-341241D01*
X364531Y-339199D01*
X363221Y-337449D01*
X361692Y-336866D01*
X354924D01*
G01X390579Y-346199D02*
Y-328699D01*
X395819D01*
X397566Y-329574D01*
X398876Y-331616D01*
X399313Y-333949D01*
X398876Y-336282D01*
X397784Y-338032D01*
X395819Y-338908D01*
X390579D01*
G01X406769Y-346199D02*
Y-328699D01*
X412446Y-343282D01*
X418123Y-328699D01*
Y-346199D01*
G01X434749Y-330158D02*
X433439Y-329282D01*
X431911Y-328699D01*
X430164D01*
X428199Y-329574D01*
X426671Y-331032D01*
X425579Y-332783D01*
X424706Y-335699D01*
X424487Y-338324D01*
X424924Y-340949D01*
X425579Y-342699D01*
X426889Y-344449D01*
X428418Y-345616D01*
X429946Y-346199D01*
X431474D01*
X433003Y-345616D01*
X434313Y-344741D01*
X435405Y-343575D01*
G01X460579Y-346199D02*
Y-328699D01*
X465819D01*
X467566Y-329574D01*
X468876Y-331616D01*
X469313Y-333949D01*
X468876Y-336282D01*
X467784Y-338032D01*
X465819Y-338908D01*
X460579D01*
G01X476987Y-328699D02*
X482446Y-346199D01*
X487905Y-328699D01*
G01X499946D02*
Y-346199D01*
G01X494924Y-328699D02*
X504968D01*
G01X284269Y-301199D02*
Y-283699D01*
X289946Y-298282D01*
X295623Y-283699D01*
Y-301199D01*
G01X307446D02*
X306136Y-300907D01*
X304826Y-299741D01*
X303952Y-297699D01*
X303516Y-295366D01*
X303952Y-293032D01*
X304826Y-290991D01*
X306136Y-289824D01*
X307446Y-289533D01*
X308756Y-289824D01*
X310066Y-290991D01*
X310939Y-293032D01*
X311158Y-295366D01*
X310939Y-297699D01*
X310066Y-299741D01*
X308756Y-300907D01*
X307446Y-301199D01*
G01X328876Y-283699D02*
Y-301199D01*
G01Y-298575D02*
X328003Y-300033D01*
X326692Y-300907D01*
X325164Y-301199D01*
X323418Y-300616D01*
X322108Y-299158D01*
X321234Y-297408D01*
X321016Y-295366D01*
X321234Y-293324D01*
X322108Y-291574D01*
X323418Y-290116D01*
X325164Y-289533D01*
X326692Y-289824D01*
X327784Y-290408D01*
X328876Y-291574D01*
G01X339171Y-293324D02*
X346158D01*
X345503Y-291282D01*
X344411Y-290116D01*
X342883Y-289533D01*
X341354Y-289824D01*
X340044Y-290699D01*
X339171Y-292741D01*
X338734Y-294491D01*
Y-296241D01*
X339171Y-297991D01*
X340263Y-299741D01*
X341573Y-300907D01*
X343101Y-301199D01*
X344629Y-300616D01*
X346158Y-298866D01*
G01X359946Y-301199D02*
Y-283699D01*
G01X556346Y-346199D02*
Y-328699D01*
X553726Y-332199D01*
G01Y-346199D02*
X558966D01*
G01X569043Y-343575D02*
X570352Y-345033D01*
X571881Y-345907D01*
X573846Y-346199D01*
X575811Y-345616D01*
X577339Y-344449D01*
X578431Y-342408D01*
X578649Y-340074D01*
X578213Y-337741D01*
X577121Y-336282D01*
X575592Y-335116D01*
X574064Y-334824D01*
X572536Y-335116D01*
X570571Y-336282D01*
X571226Y-328699D01*
X577121D01*
G01X591346Y-346199D02*
Y-328699D01*
X588726Y-332199D01*
G01Y-346199D02*
X593966D01*
G01X608846Y-328699D02*
X607099Y-329282D01*
X605789Y-330741D01*
X604916Y-332490D01*
X604261Y-334824D01*
X604043Y-337449D01*
X604261Y-340074D01*
X604916Y-342408D01*
X605789Y-344158D01*
X607099Y-345616D01*
X608846Y-346199D01*
X610592Y-345616D01*
X611903Y-344158D01*
X612776Y-342408D01*
X613431Y-340074D01*
X613649Y-337449D01*
X613431Y-334824D01*
X612776Y-332490D01*
X611903Y-330741D01*
X610592Y-329282D01*
X608846Y-328699D01*
G01X621543Y-343575D02*
X622852Y-345033D01*
X624381Y-345907D01*
X626346Y-346199D01*
X628311Y-345616D01*
X629839Y-344449D01*
X630931Y-342408D01*
X631149Y-340074D01*
X630713Y-337741D01*
X629621Y-336282D01*
X628092Y-335116D01*
X626564Y-334824D01*
X625036Y-335116D01*
X623071Y-336282D01*
X623726Y-328699D01*
X629621D01*
G01X543229Y-301199D02*
Y-283699D01*
X548469D01*
X550216Y-284574D01*
X551526Y-286616D01*
X551963Y-288949D01*
X551526Y-291282D01*
X550434Y-293032D01*
X548469Y-293908D01*
X543229D01*
G01X569899Y-285158D02*
X568589Y-284282D01*
X567061Y-283699D01*
X565314D01*
X563349Y-284574D01*
X561821Y-286032D01*
X560729Y-287783D01*
X559856Y-290699D01*
X559637Y-293324D01*
X560074Y-295949D01*
X560729Y-297699D01*
X562039Y-299449D01*
X563568Y-300616D01*
X565096Y-301199D01*
X566624D01*
X568153Y-300616D01*
X569463Y-299741D01*
X570555Y-298575D01*
G01X584342Y-291866D02*
X585216Y-290991D01*
X585871Y-289533D01*
X586308Y-287490D01*
X585871Y-285741D01*
X584998Y-284574D01*
X583469Y-283699D01*
X577574D01*
Y-301199D01*
X584779D01*
X586308Y-300033D01*
X587181Y-298282D01*
X587618Y-296241D01*
X587181Y-294199D01*
X585871Y-292449D01*
X584342Y-291866D01*
X577574D01*
G01X593546Y-307032D02*
X606646D01*
G01X612574Y-301199D02*
Y-283699D01*
X622618Y-301199D01*
Y-283699D01*
G01X635096Y-301199D02*
X633349Y-300907D01*
X631821Y-299741D01*
X630511Y-297991D01*
X629637Y-295949D01*
X629201Y-293616D01*
Y-291282D01*
X629637Y-288949D01*
X630511Y-286907D01*
X631821Y-285158D01*
X633349Y-283991D01*
X635096Y-283699D01*
X636842Y-283991D01*
X638371Y-285158D01*
X639681Y-286907D01*
X640555Y-288949D01*
X640991Y-291282D01*
Y-293616D01*
X640555Y-295949D01*
X639681Y-297991D01*
X638371Y-299741D01*
X636842Y-300907D01*
X635096Y-301199D01*
G01X685937Y-283699D02*
X691396Y-301199D01*
X696855Y-283699D01*
G01X713263Y-301199D02*
X704529D01*
Y-283699D01*
X713263D01*
G01X709769Y-292157D02*
X704529D01*
G01X722029Y-301199D02*
Y-283699D01*
X727488D01*
X729234Y-284574D01*
X730326Y-285741D01*
X730763Y-288074D01*
X730326Y-290408D01*
X729016Y-291866D01*
X727488Y-292741D01*
X722029D01*
G01X727488D02*
X730763Y-301199D01*
G01X743896Y-301782D02*
X743459Y-301491D01*
Y-300907D01*
X743896Y-300616D01*
X744333Y-300907D01*
Y-301491D01*
X743896Y-301782D01*
G01X717646Y-346199D02*
Y-328699D01*
X715026Y-332199D01*
G01Y-346199D02*
X720266D01*
G01X892100Y-336866D02*
X891226Y-335991D01*
X890571Y-334533D01*
X890134Y-332490D01*
X890571Y-330741D01*
X891444Y-329574D01*
X892973Y-328699D01*
X898868D01*
Y-346199D01*
X891663D01*
X890134Y-345033D01*
X889261Y-343282D01*
X888824Y-341241D01*
X889261Y-339199D01*
X890571Y-337449D01*
X892100Y-336866D01*
X898868D01*
G01X880931Y-343866D02*
X879184Y-345324D01*
X877219Y-346199D01*
X875473D01*
X873726Y-345324D01*
X872416Y-343866D01*
X871761Y-341824D01*
X872198Y-339783D01*
X873289Y-338032D01*
X875254Y-336866D01*
X877874Y-336282D01*
X879403Y-335116D01*
X880058Y-333074D01*
X879621Y-331032D01*
X878529Y-329574D01*
X877001Y-328699D01*
X875473D01*
X873944Y-329282D01*
X872634Y-330741D01*
G01X861466Y-328699D02*
X856226D01*
G01X858846D02*
Y-346199D01*
G01X861466D02*
X856226D01*
G01X845713Y-328699D02*
Y-346199D01*
X836979D01*
G01X828649D02*
Y-328699D01*
G01X820353D02*
X828649Y-339491D01*
G01X819043Y-346199D02*
X824938Y-334533D01*
G01X819479Y-283699D02*
Y-301199D01*
X828213D01*
G01X845276D02*
Y-289533D01*
G01Y-291574D02*
X844403Y-290408D01*
X843092Y-289824D01*
X841564Y-289533D01*
X840036Y-290116D01*
X838726Y-291282D01*
X837852Y-293032D01*
X837416Y-295366D01*
X837852Y-297699D01*
X838726Y-299449D01*
X840036Y-300616D01*
X841564Y-301199D01*
X843092Y-300907D01*
X844403Y-300033D01*
X845276Y-298866D01*
G01X854261Y-306449D02*
X855571Y-307032D01*
X857318Y-306449D01*
X858409Y-305283D01*
X859283Y-303824D01*
X860592Y-299158D01*
X863431Y-289533D01*
G01X856444D02*
X860592Y-299158D01*
G01X873071Y-293324D02*
X880058D01*
X879403Y-291282D01*
X878311Y-290116D01*
X876783Y-289533D01*
X875254Y-289824D01*
X873944Y-290699D01*
X873071Y-292741D01*
X872634Y-294491D01*
Y-296241D01*
X873071Y-297991D01*
X874163Y-299741D01*
X875473Y-300907D01*
X877001Y-301199D01*
X878529Y-300616D01*
X880058Y-298866D01*
G01X890789Y-301199D02*
Y-289533D01*
G01Y-291866D02*
X891881Y-290699D01*
X892973Y-289824D01*
X894501Y-289533D01*
X895592Y-289824D01*
X896903Y-290699D01*
G01X959846Y-328699D02*
X962902Y-346199D01*
X966396Y-328699D01*
X969889Y-346199D01*
X972946Y-328699D01*
G01X979529Y-346199D02*
Y-328699D01*
X984769D01*
X986516Y-329574D01*
X987826Y-331616D01*
X988263Y-333949D01*
X987826Y-336282D01*
X986734Y-338032D01*
X984769Y-338908D01*
X979529D01*
G01X996811Y-346199D02*
Y-328699D01*
G01X1005981D02*
Y-346199D01*
G01Y-337449D02*
X996811D01*
G01X1016058Y-340366D02*
X1021734D01*
G01X1031593Y-346199D02*
Y-328699D01*
G01X1039889D02*
X1031593Y-339491D01*
G01X1041199Y-346199D02*
X1035304Y-334533D01*
G01X1058263Y-346199D02*
X1049529D01*
Y-328699D01*
X1058263D01*
G01X1054769Y-337157D02*
X1049529D01*
G01X1066374Y-346199D02*
Y-328699D01*
X1076418Y-346199D01*
Y-328699D01*
G01X1083874Y-346199D02*
Y-328699D01*
X1093918Y-346199D01*
Y-328699D01*
G01X961593Y-301199D02*
Y-283699D01*
X965959D01*
X967706Y-284574D01*
X969016Y-285741D01*
X970108Y-287490D01*
X970981Y-289533D01*
X971199Y-292449D01*
X970981Y-295366D01*
X970108Y-297408D01*
X969016Y-299158D01*
X967706Y-300324D01*
X965959Y-301199D01*
X961593D01*
G01X980621Y-293324D02*
X987608D01*
X986953Y-291282D01*
X985861Y-290116D01*
X984333Y-289533D01*
X982804Y-289824D01*
X981494Y-290699D01*
X980621Y-292741D01*
X980184Y-294491D01*
Y-296241D01*
X980621Y-297991D01*
X981713Y-299741D01*
X983023Y-300907D01*
X984551Y-301199D01*
X986079Y-300616D01*
X987608Y-298866D01*
G01X998121Y-299158D02*
X999213Y-300324D01*
X1000741Y-301199D01*
X1002051D01*
X1003361Y-300616D01*
X1004234Y-299741D01*
X1004671Y-298575D01*
X1004453Y-296824D01*
X1003579Y-295949D01*
X999649Y-294199D01*
X998776Y-292157D01*
X999213Y-290699D01*
X1000086Y-289824D01*
X1001396Y-289533D01*
X1002706Y-289824D01*
X1004016Y-290699D01*
G01X1018896Y-289533D02*
Y-301199D01*
G01Y-284866D02*
X1018459Y-284574D01*
Y-283991D01*
X1018896Y-283699D01*
X1019333Y-283991D01*
Y-284574D01*
X1018896Y-284866D01*
G01X1033339Y-305574D02*
X1034868Y-306741D01*
X1036614Y-307032D01*
X1038142Y-306741D01*
X1039453Y-305283D01*
X1040326Y-303241D01*
Y-289533D01*
G01Y-291866D02*
X1039453Y-290699D01*
X1038142Y-289824D01*
X1036614Y-289533D01*
X1034868Y-290116D01*
X1033776Y-291282D01*
X1032902Y-293324D01*
X1032466Y-295366D01*
X1032684Y-297116D01*
X1033558Y-299158D01*
X1034868Y-300616D01*
X1036614Y-301199D01*
X1037924Y-300907D01*
X1039453Y-299741D01*
X1040326Y-298575D01*
G01X1050184Y-301199D02*
Y-289533D01*
G01Y-292449D02*
X1051058Y-290991D01*
X1052368Y-289824D01*
X1054114Y-289533D01*
X1055642Y-289824D01*
X1056953Y-290991D01*
X1057608Y-293032D01*
Y-301199D01*
G01X1068121Y-293324D02*
X1075108D01*
X1074453Y-291282D01*
X1073361Y-290116D01*
X1071833Y-289533D01*
X1070304Y-289824D01*
X1068994Y-290699D01*
X1068121Y-292741D01*
X1067684Y-294491D01*
Y-296241D01*
X1068121Y-297991D01*
X1069213Y-299741D01*
X1070523Y-300907D01*
X1072051Y-301199D01*
X1073579Y-300616D01*
X1075108Y-298866D01*
G01X1085839Y-301199D02*
Y-289533D01*
G01Y-291866D02*
X1086931Y-290699D01*
X1088023Y-289824D01*
X1089551Y-289533D01*
X1090642Y-289824D01*
X1091953Y-290699D01*
G01X1132596Y-346199D02*
Y-328699D01*
X1129976Y-332199D01*
G01Y-346199D02*
X1135216D01*
G01X1150096D02*
Y-328699D01*
X1147476Y-332199D01*
G01Y-346199D02*
X1152716D01*
G01X1163666Y-346782D02*
X1171526Y-328699D01*
G01X1185096Y-346199D02*
Y-328699D01*
X1182476Y-332199D01*
G01Y-346199D02*
X1187716D01*
G01X1198448Y-338908D02*
X1199976Y-336866D01*
X1201286Y-335699D01*
X1203033Y-335116D01*
X1204561Y-335699D01*
X1205653Y-336866D01*
X1206526Y-338616D01*
X1206744Y-340657D01*
X1206526Y-342408D01*
X1205653Y-344158D01*
X1204342Y-345616D01*
X1202814Y-346199D01*
X1201068Y-345616D01*
X1199539Y-343866D01*
X1198666Y-341241D01*
X1198448Y-338324D01*
X1198884Y-334533D01*
X1199539Y-332490D01*
X1200631Y-330449D01*
X1202159Y-328991D01*
X1203688Y-328699D01*
X1205216Y-329282D01*
X1206308Y-330741D01*
G01X1216166Y-346782D02*
X1224026Y-328699D01*
G01X1233448Y-331616D02*
X1234758Y-329866D01*
X1236286Y-328991D01*
X1238033Y-328699D01*
X1240216Y-329282D01*
X1241744Y-330741D01*
X1242181Y-332490D01*
X1241963Y-334241D01*
X1241089Y-335699D01*
X1236723Y-338616D01*
X1234758Y-340657D01*
X1233448Y-343575D01*
X1233011Y-346199D01*
X1242181D01*
G01X1255096Y-328699D02*
X1253349Y-329282D01*
X1252039Y-330741D01*
X1251166Y-332490D01*
X1250511Y-334824D01*
X1250293Y-337449D01*
X1250511Y-340074D01*
X1251166Y-342408D01*
X1252039Y-344158D01*
X1253349Y-345616D01*
X1255096Y-346199D01*
X1256842Y-345616D01*
X1258153Y-344158D01*
X1259026Y-342408D01*
X1259681Y-340074D01*
X1259899Y-337449D01*
X1259681Y-334824D01*
X1259026Y-332490D01*
X1258153Y-330741D01*
X1256842Y-329282D01*
X1255096Y-328699D01*
G01X1272596Y-346199D02*
Y-328699D01*
X1269976Y-332199D01*
G01Y-346199D02*
X1275216D01*
G01X1285948Y-338908D02*
X1287476Y-336866D01*
X1288786Y-335699D01*
X1290533Y-335116D01*
X1292061Y-335699D01*
X1293153Y-336866D01*
X1294026Y-338616D01*
X1294244Y-340657D01*
X1294026Y-342408D01*
X1293153Y-344158D01*
X1291842Y-345616D01*
X1290314Y-346199D01*
X1288568Y-345616D01*
X1287039Y-343866D01*
X1286166Y-341241D01*
X1285948Y-338324D01*
X1286384Y-334533D01*
X1287039Y-332490D01*
X1288131Y-330449D01*
X1289659Y-328991D01*
X1291188Y-328699D01*
X1292716Y-329282D01*
X1293808Y-330741D01*
G01X1180293Y-301199D02*
Y-283699D01*
X1184659D01*
X1186406Y-284574D01*
X1187716Y-285741D01*
X1188808Y-287490D01*
X1189681Y-289533D01*
X1189899Y-292449D01*
X1189681Y-295366D01*
X1188808Y-297408D01*
X1187716Y-299158D01*
X1186406Y-300324D01*
X1184659Y-301199D01*
X1180293D01*
G01X1206526D02*
Y-289533D01*
G01Y-291574D02*
X1205653Y-290408D01*
X1204342Y-289824D01*
X1202814Y-289533D01*
X1201286Y-290116D01*
X1199976Y-291282D01*
X1199102Y-293032D01*
X1198666Y-295366D01*
X1199102Y-297699D01*
X1199976Y-299449D01*
X1201286Y-300616D01*
X1202814Y-301199D01*
X1204342Y-300907D01*
X1205653Y-300033D01*
X1206526Y-298866D01*
G01X1220096Y-283699D02*
Y-301199D01*
G01X1217039Y-289533D02*
X1223153D01*
G01X1234321Y-293324D02*
X1241308D01*
X1240653Y-291282D01*
X1239561Y-290116D01*
X1238033Y-289533D01*
X1236504Y-289824D01*
X1235194Y-290699D01*
X1234321Y-292741D01*
X1233884Y-294491D01*
Y-296241D01*
X1234321Y-297991D01*
X1235413Y-299741D01*
X1236723Y-300907D01*
X1238251Y-301199D01*
X1239779Y-300616D01*
X1241308Y-298866D01*
G01X25333Y269892D02*
X25583Y270017D01*
X25875Y270100D01*
X26208D01*
X26583Y269975D01*
X26875Y269767D01*
X27083Y269517D01*
X27250Y269100D01*
X27292Y268725D01*
X27208Y268350D01*
X27083Y268100D01*
X26833Y267850D01*
X26542Y267683D01*
X26250Y267600D01*
X25958D01*
X25667Y267683D01*
X25417Y267808D01*
X25208Y267975D01*
G01X22650Y267600D02*
Y270100D01*
X24192Y268308D01*
X22108D01*
G01X20842Y269683D02*
X20592Y269933D01*
X20300Y270058D01*
X19967Y270100D01*
X19550Y270017D01*
X19258Y269808D01*
X19175Y269558D01*
X19217Y269308D01*
X19383Y269100D01*
X20217Y268683D01*
X20592Y268392D01*
X20842Y267975D01*
X20925Y267600D01*
X19175D01*
G01X17867Y268100D02*
X17617Y267808D01*
X17283Y267642D01*
X16908Y267600D01*
X16575Y267642D01*
X16242Y267850D01*
X16033Y268100D01*
X15992Y268350D01*
X16075Y268642D01*
X16367Y268850D01*
X16658Y268933D01*
X17033D01*
G01X16658D02*
X16408Y269058D01*
X16200Y269267D01*
X16117Y269517D01*
X16200Y269767D01*
X16408Y269975D01*
X16783Y270100D01*
X17158Y270058D01*
X17533Y269892D01*
G01X26133Y279592D02*
X26383Y279717D01*
X26675Y279800D01*
X27008D01*
X27383Y279675D01*
X27675Y279467D01*
X27883Y279217D01*
X28050Y278800D01*
X28092Y278425D01*
X28008Y278050D01*
X27883Y277800D01*
X27633Y277550D01*
X27342Y277383D01*
X27050Y277300D01*
X26758D01*
X26467Y277383D01*
X26217Y277508D01*
X26008Y277675D01*
G01X24742Y278342D02*
X24450Y278633D01*
X24200Y278800D01*
X23867Y278883D01*
X23575Y278800D01*
X23367Y278633D01*
X23200Y278383D01*
X23158Y278092D01*
X23200Y277842D01*
X23367Y277592D01*
X23617Y277383D01*
X23908Y277300D01*
X24242Y277383D01*
X24533Y277633D01*
X24700Y278008D01*
X24742Y278425D01*
X24658Y278967D01*
X24533Y279258D01*
X24325Y279550D01*
X24033Y279758D01*
X23742Y279800D01*
X23450Y279717D01*
X23242Y279508D01*
G01X21642Y279383D02*
X21392Y279633D01*
X21100Y279758D01*
X20767Y279800D01*
X20350Y279717D01*
X20058Y279508D01*
X19975Y279258D01*
X20017Y279008D01*
X20183Y278800D01*
X21017Y278383D01*
X21392Y278092D01*
X21642Y277675D01*
X21725Y277300D01*
X19975D01*
G01X17250D02*
Y279800D01*
X18792Y278008D01*
X16708D01*
G01X26233Y306492D02*
X26483Y306617D01*
X26775Y306700D01*
X27108D01*
X27483Y306575D01*
X27775Y306367D01*
X27983Y306117D01*
X28150Y305700D01*
X28192Y305325D01*
X28108Y304950D01*
X27983Y304700D01*
X27733Y304450D01*
X27442Y304283D01*
X27150Y304200D01*
X26858D01*
X26567Y304283D01*
X26317Y304408D01*
X26108Y304575D01*
G01X23550Y304200D02*
Y306700D01*
X25092Y304908D01*
X23008D01*
G01X21867Y304700D02*
X21617Y304408D01*
X21283Y304242D01*
X20908Y304200D01*
X20575Y304242D01*
X20242Y304450D01*
X20033Y304700D01*
X19992Y304950D01*
X20075Y305242D01*
X20367Y305450D01*
X20658Y305533D01*
X21033D01*
G01X20658D02*
X20408Y305658D01*
X20200Y305867D01*
X20117Y306117D01*
X20200Y306367D01*
X20408Y306575D01*
X20783Y306700D01*
X21158Y306658D01*
X21533Y306492D01*
G01X17850Y306700D02*
X18183Y306617D01*
X18433Y306408D01*
X18600Y306158D01*
X18725Y305825D01*
X18767Y305450D01*
X18725Y305075D01*
X18600Y304742D01*
X18433Y304492D01*
X18183Y304283D01*
X17850Y304200D01*
X17517Y304283D01*
X17267Y304492D01*
X17100Y304742D01*
X16975Y305075D01*
X16933Y305450D01*
X16975Y305825D01*
X17100Y306158D01*
X17267Y306408D01*
X17517Y306617D01*
X17850Y306700D01*
G01X38527Y507943D02*
Y510443D01*
X37486D01*
X37152Y510318D01*
X36944Y510151D01*
X36861Y509818D01*
X36944Y509485D01*
X37194Y509276D01*
X37486Y509151D01*
X38527D01*
G01X37486D02*
X36861Y507943D01*
G01X35511Y508318D02*
X35261Y508110D01*
X34969Y507985D01*
X34594Y507943D01*
X34219Y508026D01*
X33927Y508193D01*
X33719Y508485D01*
X33677Y508818D01*
X33761Y509151D01*
X33969Y509360D01*
X34261Y509526D01*
X34552Y509568D01*
X34844Y509526D01*
X35219Y509360D01*
X35094Y510443D01*
X33969D01*
G01X32286Y508985D02*
X31994Y509276D01*
X31744Y509443D01*
X31411Y509526D01*
X31119Y509443D01*
X30911Y509276D01*
X30744Y509026D01*
X30702Y508735D01*
X30744Y508485D01*
X30911Y508235D01*
X31161Y508026D01*
X31452Y507943D01*
X31786Y508026D01*
X32077Y508276D01*
X32244Y508651D01*
X32286Y509068D01*
X32202Y509610D01*
X32077Y509901D01*
X31869Y510193D01*
X31577Y510401D01*
X31286Y510443D01*
X30994Y510360D01*
X30786Y510151D01*
G01X29311Y508318D02*
X29061Y508110D01*
X28769Y507985D01*
X28394Y507943D01*
X28019Y508026D01*
X27727Y508193D01*
X27519Y508485D01*
X27477Y508818D01*
X27561Y509151D01*
X27769Y509360D01*
X28061Y509526D01*
X28352Y509568D01*
X28644Y509526D01*
X29019Y509360D01*
X28894Y510443D01*
X27769D01*
G01X42803Y296008D02*
X43053Y296133D01*
X43345Y296216D01*
X43678D01*
X44053Y296091D01*
X44345Y295883D01*
X44553Y295633D01*
X44720Y295216D01*
X44762Y294841D01*
X44678Y294466D01*
X44553Y294216D01*
X44303Y293966D01*
X44012Y293799D01*
X43720Y293716D01*
X43428D01*
X43137Y293799D01*
X42887Y293924D01*
X42678Y294091D01*
G01X41412Y294758D02*
X41120Y295049D01*
X40870Y295216D01*
X40537Y295299D01*
X40245Y295216D01*
X40037Y295049D01*
X39870Y294799D01*
X39828Y294508D01*
X39870Y294258D01*
X40037Y294008D01*
X40287Y293799D01*
X40578Y293716D01*
X40912Y293799D01*
X41203Y294049D01*
X41370Y294424D01*
X41412Y294841D01*
X41328Y295383D01*
X41203Y295674D01*
X40995Y295966D01*
X40703Y296174D01*
X40412Y296216D01*
X40120Y296133D01*
X39912Y295924D01*
G01X38312Y295799D02*
X38062Y296049D01*
X37770Y296174D01*
X37437Y296216D01*
X37020Y296133D01*
X36728Y295924D01*
X36645Y295674D01*
X36687Y295424D01*
X36853Y295216D01*
X37687Y294799D01*
X38062Y294508D01*
X38312Y294091D01*
X38395Y293716D01*
X36645D01*
G01X34420D02*
Y296216D01*
X34920Y295716D01*
G01Y293716D02*
X33920D01*
G01X42810Y292563D02*
X43060Y292688D01*
X43352Y292771D01*
X43685D01*
X44060Y292646D01*
X44352Y292438D01*
X44560Y292188D01*
X44727Y291771D01*
X44769Y291396D01*
X44685Y291021D01*
X44560Y290771D01*
X44310Y290521D01*
X44019Y290354D01*
X43727Y290271D01*
X43435D01*
X43144Y290354D01*
X42894Y290479D01*
X42685Y290646D01*
G01X41419Y291313D02*
X41127Y291604D01*
X40877Y291771D01*
X40544Y291854D01*
X40252Y291771D01*
X40044Y291604D01*
X39877Y291354D01*
X39835Y291063D01*
X39877Y290813D01*
X40044Y290563D01*
X40294Y290354D01*
X40585Y290271D01*
X40919Y290354D01*
X41210Y290604D01*
X41377Y290979D01*
X41419Y291396D01*
X41335Y291938D01*
X41210Y292229D01*
X41002Y292521D01*
X40710Y292729D01*
X40419Y292771D01*
X40127Y292688D01*
X39919Y292479D01*
G01X38319Y292354D02*
X38069Y292604D01*
X37777Y292729D01*
X37444Y292771D01*
X37027Y292688D01*
X36735Y292479D01*
X36652Y292229D01*
X36694Y291979D01*
X36860Y291771D01*
X37694Y291354D01*
X38069Y291063D01*
X38319Y290646D01*
X38402Y290271D01*
X36652D01*
G01X35219Y292354D02*
X34969Y292604D01*
X34677Y292729D01*
X34344Y292771D01*
X33927Y292688D01*
X33635Y292479D01*
X33552Y292229D01*
X33594Y291979D01*
X33760Y291771D01*
X34594Y291354D01*
X34969Y291063D01*
X35219Y290646D01*
X35302Y290271D01*
X33552D01*
G01X42633Y301292D02*
X42883Y301417D01*
X43175Y301500D01*
X43508D01*
X43883Y301375D01*
X44175Y301167D01*
X44383Y300917D01*
X44550Y300500D01*
X44592Y300125D01*
X44508Y299750D01*
X44383Y299500D01*
X44133Y299250D01*
X43842Y299083D01*
X43550Y299000D01*
X43258D01*
X42967Y299083D01*
X42717Y299208D01*
X42508Y299375D01*
G01X41242Y300042D02*
X40950Y300333D01*
X40700Y300500D01*
X40367Y300583D01*
X40075Y300500D01*
X39867Y300333D01*
X39700Y300083D01*
X39658Y299792D01*
X39700Y299542D01*
X39867Y299292D01*
X40117Y299083D01*
X40408Y299000D01*
X40742Y299083D01*
X41033Y299333D01*
X41200Y299708D01*
X41242Y300125D01*
X41158Y300667D01*
X41033Y300958D01*
X40825Y301250D01*
X40533Y301458D01*
X40242Y301500D01*
X39950Y301417D01*
X39742Y301208D01*
G01X38267Y299500D02*
X38017Y299208D01*
X37683Y299042D01*
X37308Y299000D01*
X36975Y299042D01*
X36642Y299250D01*
X36433Y299500D01*
X36392Y299750D01*
X36475Y300042D01*
X36767Y300250D01*
X37058Y300333D01*
X37433D01*
G01X37058D02*
X36808Y300458D01*
X36600Y300667D01*
X36517Y300917D01*
X36600Y301167D01*
X36808Y301375D01*
X37183Y301500D01*
X37558Y301458D01*
X37933Y301292D01*
G01X35167Y299375D02*
X34917Y299167D01*
X34625Y299042D01*
X34250Y299000D01*
X33875Y299083D01*
X33583Y299250D01*
X33375Y299542D01*
X33333Y299875D01*
X33417Y300208D01*
X33625Y300417D01*
X33917Y300583D01*
X34208Y300625D01*
X34500Y300583D01*
X34875Y300417D01*
X34750Y301500D01*
X33625D01*
G01X66433Y300192D02*
X66683Y300317D01*
X66975Y300400D01*
X67308D01*
X67683Y300275D01*
X67975Y300067D01*
X68183Y299817D01*
X68350Y299400D01*
X68392Y299025D01*
X68308Y298650D01*
X68183Y298400D01*
X67933Y298150D01*
X67642Y297983D01*
X67350Y297900D01*
X67058D01*
X66767Y297983D01*
X66517Y298108D01*
X66308Y298275D01*
G01X65042Y298942D02*
X64750Y299233D01*
X64500Y299400D01*
X64167Y299483D01*
X63875Y299400D01*
X63667Y299233D01*
X63500Y298983D01*
X63458Y298692D01*
X63500Y298442D01*
X63667Y298192D01*
X63917Y297983D01*
X64208Y297900D01*
X64542Y297983D01*
X64833Y298233D01*
X65000Y298608D01*
X65042Y299025D01*
X64958Y299567D01*
X64833Y299858D01*
X64625Y300150D01*
X64333Y300358D01*
X64042Y300400D01*
X63750Y300317D01*
X63542Y300108D01*
G01X62067Y298400D02*
X61817Y298108D01*
X61483Y297942D01*
X61108Y297900D01*
X60775Y297942D01*
X60442Y298150D01*
X60233Y298400D01*
X60192Y298650D01*
X60275Y298942D01*
X60567Y299150D01*
X60858Y299233D01*
X61233D01*
G01X60858D02*
X60608Y299358D01*
X60400Y299567D01*
X60317Y299817D01*
X60400Y300067D01*
X60608Y300275D01*
X60983Y300400D01*
X61358Y300358D01*
X61733Y300192D01*
G01X58842Y298942D02*
X58550Y299233D01*
X58300Y299400D01*
X57967Y299483D01*
X57675Y299400D01*
X57467Y299233D01*
X57300Y298983D01*
X57258Y298692D01*
X57300Y298442D01*
X57467Y298192D01*
X57717Y297983D01*
X58008Y297900D01*
X58342Y297983D01*
X58633Y298233D01*
X58800Y298608D01*
X58842Y299025D01*
X58758Y299567D01*
X58633Y299858D01*
X58425Y300150D01*
X58133Y300358D01*
X57842Y300400D01*
X57550Y300317D01*
X57342Y300108D01*
G01X42811Y289126D02*
X43061Y289251D01*
X43353Y289334D01*
X43686D01*
X44061Y289209D01*
X44353Y289001D01*
X44561Y288751D01*
X44728Y288334D01*
X44770Y287959D01*
X44686Y287584D01*
X44561Y287334D01*
X44311Y287084D01*
X44020Y286917D01*
X43728Y286834D01*
X43436D01*
X43145Y286917D01*
X42895Y287042D01*
X42686Y287209D01*
G01X41420Y287876D02*
X41128Y288167D01*
X40878Y288334D01*
X40545Y288417D01*
X40253Y288334D01*
X40045Y288167D01*
X39878Y287917D01*
X39836Y287626D01*
X39878Y287376D01*
X40045Y287126D01*
X40295Y286917D01*
X40586Y286834D01*
X40920Y286917D01*
X41211Y287167D01*
X41378Y287542D01*
X41420Y287959D01*
X41336Y288501D01*
X41211Y288792D01*
X41003Y289084D01*
X40711Y289292D01*
X40420Y289334D01*
X40128Y289251D01*
X39920Y289042D01*
G01X38320Y288917D02*
X38070Y289167D01*
X37778Y289292D01*
X37445Y289334D01*
X37028Y289251D01*
X36736Y289042D01*
X36653Y288792D01*
X36695Y288542D01*
X36861Y288334D01*
X37695Y287917D01*
X38070Y287626D01*
X38320Y287209D01*
X38403Y286834D01*
X36653D01*
G01X35136Y287126D02*
X34845Y286917D01*
X34511Y286834D01*
X34178Y286917D01*
X33886Y287167D01*
X33678Y287542D01*
X33595Y287917D01*
Y288376D01*
X33678Y288751D01*
X33886Y289084D01*
X34136Y289251D01*
X34428Y289334D01*
X34761Y289251D01*
X35011Y289084D01*
X35178Y288834D01*
X35261Y288501D01*
X35178Y288209D01*
X34970Y287917D01*
X34720Y287751D01*
X34428Y287709D01*
X34095Y287792D01*
X33845Y288001D01*
X33595Y288376D01*
G01X64933Y322692D02*
X65183Y322817D01*
X65475Y322900D01*
X65808D01*
X66183Y322775D01*
X66475Y322567D01*
X66683Y322317D01*
X66850Y321900D01*
X66892Y321525D01*
X66808Y321150D01*
X66683Y320900D01*
X66433Y320650D01*
X66142Y320483D01*
X65850Y320400D01*
X65558D01*
X65267Y320483D01*
X65017Y320608D01*
X64808Y320775D01*
G01X63542Y321442D02*
X63250Y321733D01*
X63000Y321900D01*
X62667Y321983D01*
X62375Y321900D01*
X62167Y321733D01*
X62000Y321483D01*
X61958Y321192D01*
X62000Y320942D01*
X62167Y320692D01*
X62417Y320483D01*
X62708Y320400D01*
X63042Y320483D01*
X63333Y320733D01*
X63500Y321108D01*
X63542Y321525D01*
X63458Y322067D01*
X63333Y322358D01*
X63125Y322650D01*
X62833Y322858D01*
X62542Y322900D01*
X62250Y322817D01*
X62042Y322608D01*
G01X60567Y320900D02*
X60317Y320608D01*
X59983Y320442D01*
X59608Y320400D01*
X59275Y320442D01*
X58942Y320650D01*
X58733Y320900D01*
X58692Y321150D01*
X58775Y321442D01*
X59067Y321650D01*
X59358Y321733D01*
X59733D01*
G01X59358D02*
X59108Y321858D01*
X58900Y322067D01*
X58817Y322317D01*
X58900Y322567D01*
X59108Y322775D01*
X59483Y322900D01*
X59858Y322858D01*
X60233Y322692D01*
G01X57467Y320900D02*
X57217Y320608D01*
X56883Y320442D01*
X56508Y320400D01*
X56175Y320442D01*
X55842Y320650D01*
X55633Y320900D01*
X55592Y321150D01*
X55675Y321442D01*
X55967Y321650D01*
X56258Y321733D01*
X56633D01*
G01X56258D02*
X56008Y321858D01*
X55800Y322067D01*
X55717Y322317D01*
X55800Y322567D01*
X56008Y322775D01*
X56383Y322900D01*
X56758Y322858D01*
X57133Y322692D01*
G01X45192Y334967D02*
X45317Y334717D01*
X45400Y334425D01*
Y334092D01*
X45275Y333717D01*
X45067Y333425D01*
X44817Y333217D01*
X44400Y333050D01*
X44025Y333008D01*
X43650Y333092D01*
X43400Y333217D01*
X43150Y333467D01*
X42983Y333758D01*
X42900Y334050D01*
Y334342D01*
X42983Y334633D01*
X43108Y334883D01*
X43275Y335092D01*
G01X43942Y336358D02*
X44233Y336650D01*
X44400Y336900D01*
X44483Y337233D01*
X44400Y337525D01*
X44233Y337733D01*
X43983Y337900D01*
X43692Y337942D01*
X43442Y337900D01*
X43192Y337733D01*
X42983Y337483D01*
X42900Y337192D01*
X42983Y336858D01*
X43233Y336567D01*
X43608Y336400D01*
X44025Y336358D01*
X44567Y336442D01*
X44858Y336567D01*
X45150Y336775D01*
X45358Y337067D01*
X45400Y337358D01*
X45317Y337650D01*
X45108Y337858D01*
G01X44983Y339458D02*
X45233Y339708D01*
X45358Y340000D01*
X45400Y340333D01*
X45317Y340750D01*
X45108Y341042D01*
X44858Y341125D01*
X44608Y341083D01*
X44400Y340917D01*
X43983Y340083D01*
X43692Y339708D01*
X43275Y339458D01*
X42900Y339375D01*
Y341125D01*
G01Y343267D02*
X43442Y343350D01*
X43900Y343475D01*
X44317Y343642D01*
X44775Y343850D01*
X45400Y344183D01*
Y342517D01*
G01X45583Y428561D02*
Y431061D01*
X44583D01*
X44250Y430936D01*
X44000Y430644D01*
X43917Y430311D01*
X44000Y429978D01*
X44208Y429728D01*
X44583Y429603D01*
X45583D01*
G01X40733Y430853D02*
X40983Y430978D01*
X41275Y431061D01*
X41608D01*
X41983Y430936D01*
X42275Y430728D01*
X42483Y430478D01*
X42650Y430061D01*
X42692Y429686D01*
X42608Y429311D01*
X42483Y429061D01*
X42233Y428811D01*
X41942Y428644D01*
X41650Y428561D01*
X41358D01*
X41067Y428644D01*
X40817Y428769D01*
X40608Y428936D01*
G01X38550Y428561D02*
X38258Y428603D01*
X37925Y428728D01*
X37717Y428936D01*
X37633Y429228D01*
X37717Y429519D01*
X37967Y429769D01*
X38342Y429894D01*
X38758D01*
X39008Y429978D01*
X39217Y430186D01*
X39300Y430478D01*
X39175Y430769D01*
X38883Y430978D01*
X38550Y431061D01*
X38217Y430978D01*
X37925Y430769D01*
X37800Y430478D01*
X37883Y430186D01*
X38092Y429978D01*
X38342Y429894D01*
X38758D01*
X39133Y429769D01*
X39383Y429519D01*
X39467Y429228D01*
X39383Y428936D01*
X39175Y428728D01*
X38842Y428603D01*
X38550Y428561D01*
G01X36367Y428936D02*
X36117Y428728D01*
X35825Y428603D01*
X35450Y428561D01*
X35075Y428644D01*
X34783Y428811D01*
X34575Y429103D01*
X34533Y429436D01*
X34617Y429769D01*
X34825Y429978D01*
X35117Y430144D01*
X35408Y430186D01*
X35700Y430144D01*
X36075Y429978D01*
X35950Y431061D01*
X34825D01*
G01X45583Y432561D02*
Y435061D01*
X44583D01*
X44250Y434936D01*
X44000Y434644D01*
X43917Y434311D01*
X44000Y433978D01*
X44208Y433728D01*
X44583Y433603D01*
X45583D01*
G01X40733Y434853D02*
X40983Y434978D01*
X41275Y435061D01*
X41608D01*
X41983Y434936D01*
X42275Y434728D01*
X42483Y434478D01*
X42650Y434061D01*
X42692Y433686D01*
X42608Y433311D01*
X42483Y433061D01*
X42233Y432811D01*
X41942Y432644D01*
X41650Y432561D01*
X41358D01*
X41067Y432644D01*
X40817Y432769D01*
X40608Y432936D01*
G01X38550Y432561D02*
X38258Y432603D01*
X37925Y432728D01*
X37717Y432936D01*
X37633Y433228D01*
X37717Y433519D01*
X37967Y433769D01*
X38342Y433894D01*
X38758D01*
X39008Y433978D01*
X39217Y434186D01*
X39300Y434478D01*
X39175Y434769D01*
X38883Y434978D01*
X38550Y435061D01*
X38217Y434978D01*
X37925Y434769D01*
X37800Y434478D01*
X37883Y434186D01*
X38092Y433978D01*
X38342Y433894D01*
X38758D01*
X39133Y433769D01*
X39383Y433519D01*
X39467Y433228D01*
X39383Y432936D01*
X39175Y432728D01*
X38842Y432603D01*
X38550Y432561D01*
G01X36367Y433061D02*
X36117Y432769D01*
X35783Y432603D01*
X35408Y432561D01*
X35075Y432603D01*
X34742Y432811D01*
X34533Y433061D01*
X34492Y433311D01*
X34575Y433603D01*
X34867Y433811D01*
X35158Y433894D01*
X35533D01*
G01X35158D02*
X34908Y434019D01*
X34700Y434228D01*
X34617Y434478D01*
X34700Y434728D01*
X34908Y434936D01*
X35283Y435061D01*
X35658Y435019D01*
X36033Y434853D01*
G01X74983Y477870D02*
Y480370D01*
X73942D01*
X73608Y480245D01*
X73400Y480078D01*
X73317Y479745D01*
X73400Y479412D01*
X73650Y479203D01*
X73942Y479078D01*
X74983D01*
G01X73942D02*
X73317Y477870D01*
G01X71842Y479953D02*
X71592Y480203D01*
X71300Y480328D01*
X70967Y480370D01*
X70550Y480287D01*
X70258Y480078D01*
X70175Y479828D01*
X70217Y479578D01*
X70383Y479370D01*
X71217Y478953D01*
X71592Y478662D01*
X71842Y478245D01*
X71925Y477870D01*
X70175D01*
G01X68742Y479953D02*
X68492Y480203D01*
X68200Y480328D01*
X67867Y480370D01*
X67450Y480287D01*
X67158Y480078D01*
X67075Y479828D01*
X67117Y479578D01*
X67283Y479370D01*
X68117Y478953D01*
X68492Y478662D01*
X68742Y478245D01*
X68825Y477870D01*
X67075D01*
G01X65767Y478245D02*
X65517Y478037D01*
X65225Y477912D01*
X64850Y477870D01*
X64475Y477953D01*
X64183Y478120D01*
X63975Y478412D01*
X63933Y478745D01*
X64017Y479078D01*
X64225Y479287D01*
X64517Y479453D01*
X64808Y479495D01*
X65100Y479453D01*
X65475Y479287D01*
X65350Y480370D01*
X64225D01*
G01X56530Y479289D02*
X59030D01*
Y480330D01*
X58905Y480664D01*
X58738Y480872D01*
X58405Y480955D01*
X58072Y480872D01*
X57863Y480622D01*
X57738Y480330D01*
Y479289D01*
G01Y480330D02*
X56530Y480955D01*
G01X56905Y482305D02*
X56697Y482555D01*
X56572Y482847D01*
X56530Y483222D01*
X56613Y483597D01*
X56780Y483889D01*
X57072Y484097D01*
X57405Y484139D01*
X57738Y484055D01*
X57947Y483847D01*
X58113Y483555D01*
X58155Y483264D01*
X58113Y482972D01*
X57947Y482597D01*
X59030Y482722D01*
Y483847D01*
G01X58613Y485530D02*
X58863Y485780D01*
X58988Y486072D01*
X59030Y486405D01*
X58947Y486822D01*
X58738Y487114D01*
X58488Y487197D01*
X58238Y487155D01*
X58030Y486989D01*
X57613Y486155D01*
X57322Y485780D01*
X56905Y485530D01*
X56530Y485447D01*
Y487197D01*
G01X58613Y488630D02*
X58863Y488880D01*
X58988Y489172D01*
X59030Y489505D01*
X58947Y489922D01*
X58738Y490214D01*
X58488Y490297D01*
X58238Y490255D01*
X58030Y490089D01*
X57613Y489255D01*
X57322Y488880D01*
X56905Y488630D01*
X56530Y488547D01*
Y490297D01*
G01X52430Y479289D02*
X54930D01*
Y480330D01*
X54805Y480664D01*
X54638Y480872D01*
X54305Y480955D01*
X53972Y480872D01*
X53763Y480622D01*
X53638Y480330D01*
Y479289D01*
G01Y480330D02*
X52430Y480955D01*
G01X52805Y482305D02*
X52597Y482555D01*
X52472Y482847D01*
X52430Y483222D01*
X52513Y483597D01*
X52680Y483889D01*
X52972Y484097D01*
X53305Y484139D01*
X53638Y484055D01*
X53847Y483847D01*
X54013Y483555D01*
X54055Y483264D01*
X54013Y482972D01*
X53847Y482597D01*
X54930Y482722D01*
Y483847D01*
G01X54513Y485530D02*
X54763Y485780D01*
X54888Y486072D01*
X54930Y486405D01*
X54847Y486822D01*
X54638Y487114D01*
X54388Y487197D01*
X54138Y487155D01*
X53930Y486989D01*
X53513Y486155D01*
X53222Y485780D01*
X52805Y485530D01*
X52430Y485447D01*
Y487197D01*
G01Y489922D02*
X54930D01*
X53138Y488380D01*
Y490464D01*
G01X68516Y501180D02*
Y503680D01*
X67475D01*
X67141Y503555D01*
X66933Y503388D01*
X66850Y503055D01*
X66933Y502722D01*
X67183Y502513D01*
X67475Y502388D01*
X68516D01*
G01X67475D02*
X66850Y501180D01*
G01X65375Y503263D02*
X65125Y503513D01*
X64833Y503638D01*
X64500Y503680D01*
X64083Y503597D01*
X63791Y503388D01*
X63708Y503138D01*
X63750Y502888D01*
X63916Y502680D01*
X64750Y502263D01*
X65125Y501972D01*
X65375Y501555D01*
X65458Y501180D01*
X63708D01*
G01X62400Y501680D02*
X62150Y501388D01*
X61816Y501222D01*
X61441Y501180D01*
X61108Y501222D01*
X60775Y501430D01*
X60566Y501680D01*
X60525Y501930D01*
X60608Y502222D01*
X60900Y502430D01*
X61191Y502513D01*
X61566D01*
G01X61191D02*
X60941Y502638D01*
X60733Y502847D01*
X60650Y503097D01*
X60733Y503347D01*
X60941Y503555D01*
X61316Y503680D01*
X61691Y503638D01*
X62066Y503472D01*
G01X59175Y502222D02*
X58883Y502513D01*
X58633Y502680D01*
X58300Y502763D01*
X58008Y502680D01*
X57800Y502513D01*
X57633Y502263D01*
X57591Y501972D01*
X57633Y501722D01*
X57800Y501472D01*
X58050Y501263D01*
X58341Y501180D01*
X58675Y501263D01*
X58966Y501513D01*
X59133Y501888D01*
X59175Y502305D01*
X59091Y502847D01*
X58966Y503138D01*
X58758Y503430D01*
X58466Y503638D01*
X58175Y503680D01*
X57883Y503597D01*
X57675Y503388D01*
G01X74394Y484254D02*
Y486754D01*
X73353D01*
X73019Y486629D01*
X72811Y486462D01*
X72728Y486129D01*
X72811Y485796D01*
X73061Y485587D01*
X73353Y485462D01*
X74394D01*
G01X73353D02*
X72728Y484254D01*
G01X71253Y486337D02*
X71003Y486587D01*
X70711Y486712D01*
X70378Y486754D01*
X69961Y486671D01*
X69669Y486462D01*
X69586Y486212D01*
X69628Y485962D01*
X69794Y485754D01*
X70628Y485337D01*
X71003Y485046D01*
X71253Y484629D01*
X71336Y484254D01*
X69586D01*
G01X66861D02*
Y486754D01*
X68403Y484962D01*
X66319D01*
G01X64261Y486754D02*
X64594Y486671D01*
X64844Y486462D01*
X65011Y486212D01*
X65136Y485879D01*
X65178Y485504D01*
X65136Y485129D01*
X65011Y484796D01*
X64844Y484546D01*
X64594Y484337D01*
X64261Y484254D01*
X63928Y484337D01*
X63678Y484546D01*
X63511Y484796D01*
X63386Y485129D01*
X63344Y485504D01*
X63386Y485879D01*
X63511Y486212D01*
X63678Y486462D01*
X63928Y486671D01*
X64261Y486754D01*
G01X72831Y489552D02*
Y492052D01*
X71790D01*
X71456Y491927D01*
X71248Y491760D01*
X71165Y491427D01*
X71248Y491094D01*
X71498Y490885D01*
X71790Y490760D01*
X72831D01*
G01X71790D02*
X71165Y489552D01*
G01X69690Y491635D02*
X69440Y491885D01*
X69148Y492010D01*
X68815Y492052D01*
X68398Y491969D01*
X68106Y491760D01*
X68023Y491510D01*
X68065Y491260D01*
X68231Y491052D01*
X69065Y490635D01*
X69440Y490344D01*
X69690Y489927D01*
X69773Y489552D01*
X68023D01*
G01X65298D02*
Y492052D01*
X66840Y490260D01*
X64756D01*
G01X62698Y489552D02*
Y492052D01*
X63198Y491552D01*
G01Y489552D02*
X62198D01*
G01X59700Y493800D02*
X55700D01*
Y501200D01*
G01X55600Y493800D02*
X51600D01*
Y501200D01*
G01X50967Y511817D02*
Y514317D01*
X49926D01*
X49592Y514192D01*
X49384Y514025D01*
X49301Y513692D01*
X49384Y513359D01*
X49634Y513150D01*
X49926Y513025D01*
X50967D01*
G01X49926D02*
X49301Y511817D01*
G01X47951Y512317D02*
X47701Y512025D01*
X47367Y511859D01*
X46992Y511817D01*
X46659Y511859D01*
X46326Y512067D01*
X46117Y512317D01*
X46076Y512567D01*
X46159Y512859D01*
X46451Y513067D01*
X46742Y513150D01*
X47117D01*
G01X46742D02*
X46492Y513275D01*
X46284Y513484D01*
X46201Y513734D01*
X46284Y513984D01*
X46492Y514192D01*
X46867Y514317D01*
X47242Y514275D01*
X47617Y514109D01*
G01X43434Y511817D02*
Y514317D01*
X44976Y512525D01*
X42892D01*
G01X40834Y514317D02*
X41167Y514234D01*
X41417Y514025D01*
X41584Y513775D01*
X41709Y513442D01*
X41751Y513067D01*
X41709Y512692D01*
X41584Y512359D01*
X41417Y512109D01*
X41167Y511900D01*
X40834Y511817D01*
X40501Y511900D01*
X40251Y512109D01*
X40084Y512359D01*
X39959Y512692D01*
X39917Y513067D01*
X39959Y513442D01*
X40084Y513775D01*
X40251Y514025D01*
X40501Y514234D01*
X40834Y514317D01*
G01X50967Y503817D02*
Y506317D01*
X49926D01*
X49592Y506192D01*
X49384Y506025D01*
X49301Y505692D01*
X49384Y505359D01*
X49634Y505150D01*
X49926Y505025D01*
X50967D01*
G01X49926D02*
X49301Y503817D01*
G01X47951Y504317D02*
X47701Y504025D01*
X47367Y503859D01*
X46992Y503817D01*
X46659Y503859D01*
X46326Y504067D01*
X46117Y504317D01*
X46076Y504567D01*
X46159Y504859D01*
X46451Y505067D01*
X46742Y505150D01*
X47117D01*
G01X46742D02*
X46492Y505275D01*
X46284Y505484D01*
X46201Y505734D01*
X46284Y505984D01*
X46492Y506192D01*
X46867Y506317D01*
X47242Y506275D01*
X47617Y506109D01*
G01X43434Y503817D02*
Y506317D01*
X44976Y504525D01*
X42892D01*
G01X40334Y503817D02*
Y506317D01*
X41876Y504525D01*
X39792D01*
G01X50967Y507817D02*
Y510317D01*
X49926D01*
X49592Y510192D01*
X49384Y510025D01*
X49301Y509692D01*
X49384Y509359D01*
X49634Y509150D01*
X49926Y509025D01*
X50967D01*
G01X49926D02*
X49301Y507817D01*
G01X47951Y508317D02*
X47701Y508025D01*
X47367Y507859D01*
X46992Y507817D01*
X46659Y507859D01*
X46326Y508067D01*
X46117Y508317D01*
X46076Y508567D01*
X46159Y508859D01*
X46451Y509067D01*
X46742Y509150D01*
X47117D01*
G01X46742D02*
X46492Y509275D01*
X46284Y509484D01*
X46201Y509734D01*
X46284Y509984D01*
X46492Y510192D01*
X46867Y510317D01*
X47242Y510275D01*
X47617Y510109D01*
G01X44726Y508859D02*
X44434Y509150D01*
X44184Y509317D01*
X43851Y509400D01*
X43559Y509317D01*
X43351Y509150D01*
X43184Y508900D01*
X43142Y508609D01*
X43184Y508359D01*
X43351Y508109D01*
X43601Y507900D01*
X43892Y507817D01*
X44226Y507900D01*
X44517Y508150D01*
X44684Y508525D01*
X44726Y508942D01*
X44642Y509484D01*
X44517Y509775D01*
X44309Y510067D01*
X44017Y510275D01*
X43726Y510317D01*
X43434Y510234D01*
X43226Y510025D01*
G01X40834Y507817D02*
Y510317D01*
X41334Y509817D01*
G01Y507817D02*
X40334D01*
G01X50967Y515817D02*
Y518317D01*
X49926D01*
X49592Y518192D01*
X49384Y518025D01*
X49301Y517692D01*
X49384Y517359D01*
X49634Y517150D01*
X49926Y517025D01*
X50967D01*
G01X49926D02*
X49301Y515817D01*
G01X47951Y516317D02*
X47701Y516025D01*
X47367Y515859D01*
X46992Y515817D01*
X46659Y515859D01*
X46326Y516067D01*
X46117Y516317D01*
X46076Y516567D01*
X46159Y516859D01*
X46451Y517067D01*
X46742Y517150D01*
X47117D01*
G01X46742D02*
X46492Y517275D01*
X46284Y517484D01*
X46201Y517734D01*
X46284Y517984D01*
X46492Y518192D01*
X46867Y518317D01*
X47242Y518275D01*
X47617Y518109D01*
G01X43434Y515817D02*
Y518317D01*
X44976Y516525D01*
X42892D01*
G01X41751Y516192D02*
X41501Y515984D01*
X41209Y515859D01*
X40834Y515817D01*
X40459Y515900D01*
X40167Y516067D01*
X39959Y516359D01*
X39917Y516692D01*
X40001Y517025D01*
X40209Y517234D01*
X40501Y517400D01*
X40792Y517442D01*
X41084Y517400D01*
X41459Y517234D01*
X41334Y518317D01*
X40209D01*
G01X63483Y517161D02*
Y519661D01*
X62442D01*
X62108Y519536D01*
X61900Y519369D01*
X61817Y519036D01*
X61900Y518703D01*
X62150Y518494D01*
X62442Y518369D01*
X63483D01*
G01X62442D02*
X61817Y517161D01*
G01X60467Y517661D02*
X60217Y517369D01*
X59883Y517203D01*
X59508Y517161D01*
X59175Y517203D01*
X58842Y517411D01*
X58633Y517661D01*
X58592Y517911D01*
X58675Y518203D01*
X58967Y518411D01*
X59258Y518494D01*
X59633D01*
G01X59258D02*
X59008Y518619D01*
X58800Y518828D01*
X58717Y519078D01*
X58800Y519328D01*
X59008Y519536D01*
X59383Y519661D01*
X59758Y519619D01*
X60133Y519453D01*
G01X57367Y517536D02*
X57117Y517328D01*
X56825Y517203D01*
X56450Y517161D01*
X56075Y517244D01*
X55783Y517411D01*
X55575Y517703D01*
X55533Y518036D01*
X55617Y518369D01*
X55825Y518578D01*
X56117Y518744D01*
X56408Y518786D01*
X56700Y518744D01*
X57075Y518578D01*
X56950Y519661D01*
X55825D01*
G01X54058Y517453D02*
X53767Y517244D01*
X53433Y517161D01*
X53100Y517244D01*
X52808Y517494D01*
X52600Y517869D01*
X52517Y518244D01*
Y518703D01*
X52600Y519078D01*
X52808Y519411D01*
X53058Y519578D01*
X53350Y519661D01*
X53683Y519578D01*
X53933Y519411D01*
X54100Y519161D01*
X54183Y518828D01*
X54100Y518536D01*
X53892Y518244D01*
X53642Y518078D01*
X53350Y518036D01*
X53017Y518119D01*
X52767Y518328D01*
X52517Y518703D01*
G01X47533Y533661D02*
Y536161D01*
X46492D01*
X46158Y536036D01*
X45950Y535869D01*
X45867Y535536D01*
X45950Y535203D01*
X46200Y534994D01*
X46492Y534869D01*
X47533D01*
G01X46492D02*
X45867Y533661D01*
G01X43600D02*
Y536161D01*
X44100Y535661D01*
G01Y533661D02*
X43100D01*
G01X41292Y535744D02*
X41042Y535994D01*
X40750Y536119D01*
X40417Y536161D01*
X40000Y536078D01*
X39708Y535869D01*
X39625Y535619D01*
X39667Y535369D01*
X39833Y535161D01*
X40667Y534744D01*
X41042Y534453D01*
X41292Y534036D01*
X41375Y533661D01*
X39625D01*
G01X37400Y536161D02*
X37733Y536078D01*
X37983Y535869D01*
X38150Y535619D01*
X38275Y535286D01*
X38317Y534911D01*
X38275Y534536D01*
X38150Y534203D01*
X37983Y533953D01*
X37733Y533744D01*
X37400Y533661D01*
X37067Y533744D01*
X36817Y533953D01*
X36650Y534203D01*
X36525Y534536D01*
X36483Y534911D01*
X36525Y535286D01*
X36650Y535619D01*
X36817Y535869D01*
X37067Y536078D01*
X37400Y536161D01*
G01X35092Y535744D02*
X34842Y535994D01*
X34550Y536119D01*
X34217Y536161D01*
X33800Y536078D01*
X33508Y535869D01*
X33425Y535619D01*
X33467Y535369D01*
X33633Y535161D01*
X34467Y534744D01*
X34842Y534453D01*
X35092Y534036D01*
X35175Y533661D01*
X33425D01*
G01X63483Y545161D02*
Y547661D01*
X62442D01*
X62108Y547536D01*
X61900Y547369D01*
X61817Y547036D01*
X61900Y546703D01*
X62150Y546494D01*
X62442Y546369D01*
X63483D01*
G01X62442D02*
X61817Y545161D01*
G01X60342Y546203D02*
X60050Y546494D01*
X59800Y546661D01*
X59467Y546744D01*
X59175Y546661D01*
X58967Y546494D01*
X58800Y546244D01*
X58758Y545953D01*
X58800Y545703D01*
X58967Y545453D01*
X59217Y545244D01*
X59508Y545161D01*
X59842Y545244D01*
X60133Y545494D01*
X60300Y545869D01*
X60342Y546286D01*
X60258Y546828D01*
X60133Y547119D01*
X59925Y547411D01*
X59633Y547619D01*
X59342Y547661D01*
X59050Y547578D01*
X58842Y547369D01*
G01X57367Y545536D02*
X57117Y545328D01*
X56825Y545203D01*
X56450Y545161D01*
X56075Y545244D01*
X55783Y545411D01*
X55575Y545703D01*
X55533Y546036D01*
X55617Y546369D01*
X55825Y546578D01*
X56117Y546744D01*
X56408Y546786D01*
X56700Y546744D01*
X57075Y546578D01*
X56950Y547661D01*
X55825D01*
G01X54058Y545453D02*
X53767Y545244D01*
X53433Y545161D01*
X53100Y545244D01*
X52808Y545494D01*
X52600Y545869D01*
X52517Y546244D01*
Y546703D01*
X52600Y547078D01*
X52808Y547411D01*
X53058Y547578D01*
X53350Y547661D01*
X53683Y547578D01*
X53933Y547411D01*
X54100Y547161D01*
X54183Y546828D01*
X54100Y546536D01*
X53892Y546244D01*
X53642Y546078D01*
X53350Y546036D01*
X53017Y546119D01*
X52767Y546328D01*
X52517Y546703D01*
G01X63483Y529161D02*
Y531661D01*
X62442D01*
X62108Y531536D01*
X61900Y531369D01*
X61817Y531036D01*
X61900Y530703D01*
X62150Y530494D01*
X62442Y530369D01*
X63483D01*
G01X62442D02*
X61817Y529161D01*
G01X60467Y529536D02*
X60217Y529328D01*
X59925Y529203D01*
X59550Y529161D01*
X59175Y529244D01*
X58883Y529411D01*
X58675Y529703D01*
X58633Y530036D01*
X58717Y530369D01*
X58925Y530578D01*
X59217Y530744D01*
X59508Y530786D01*
X59800Y530744D01*
X60175Y530578D01*
X60050Y531661D01*
X58925D01*
G01X57242Y531244D02*
X56992Y531494D01*
X56700Y531619D01*
X56367Y531661D01*
X55950Y531578D01*
X55658Y531369D01*
X55575Y531119D01*
X55617Y530869D01*
X55783Y530661D01*
X56617Y530244D01*
X56992Y529953D01*
X57242Y529536D01*
X57325Y529161D01*
X55575D01*
G01X54267Y529661D02*
X54017Y529369D01*
X53683Y529203D01*
X53308Y529161D01*
X52975Y529203D01*
X52642Y529411D01*
X52433Y529661D01*
X52392Y529911D01*
X52475Y530203D01*
X52767Y530411D01*
X53058Y530494D01*
X53433D01*
G01X53058D02*
X52808Y530619D01*
X52600Y530828D01*
X52517Y531078D01*
X52600Y531328D01*
X52808Y531536D01*
X53183Y531661D01*
X53558Y531619D01*
X53933Y531453D01*
G01X63483Y537161D02*
Y539661D01*
X62442D01*
X62108Y539536D01*
X61900Y539369D01*
X61817Y539036D01*
X61900Y538703D01*
X62150Y538494D01*
X62442Y538369D01*
X63483D01*
G01X62442D02*
X61817Y537161D01*
G01X60342Y538203D02*
X60050Y538494D01*
X59800Y538661D01*
X59467Y538744D01*
X59175Y538661D01*
X58967Y538494D01*
X58800Y538244D01*
X58758Y537953D01*
X58800Y537703D01*
X58967Y537453D01*
X59217Y537244D01*
X59508Y537161D01*
X59842Y537244D01*
X60133Y537494D01*
X60300Y537869D01*
X60342Y538286D01*
X60258Y538828D01*
X60133Y539119D01*
X59925Y539411D01*
X59633Y539619D01*
X59342Y539661D01*
X59050Y539578D01*
X58842Y539369D01*
G01X56450Y539661D02*
X56783Y539578D01*
X57033Y539369D01*
X57200Y539119D01*
X57325Y538786D01*
X57367Y538411D01*
X57325Y538036D01*
X57200Y537703D01*
X57033Y537453D01*
X56783Y537244D01*
X56450Y537161D01*
X56117Y537244D01*
X55867Y537453D01*
X55700Y537703D01*
X55575Y538036D01*
X55533Y538411D01*
X55575Y538786D01*
X55700Y539119D01*
X55867Y539369D01*
X56117Y539578D01*
X56450Y539661D01*
G01X54142Y538203D02*
X53850Y538494D01*
X53600Y538661D01*
X53267Y538744D01*
X52975Y538661D01*
X52767Y538494D01*
X52600Y538244D01*
X52558Y537953D01*
X52600Y537703D01*
X52767Y537453D01*
X53017Y537244D01*
X53308Y537161D01*
X53642Y537244D01*
X53933Y537494D01*
X54100Y537869D01*
X54142Y538286D01*
X54058Y538828D01*
X53933Y539119D01*
X53725Y539411D01*
X53433Y539619D01*
X53142Y539661D01*
X52850Y539578D01*
X52642Y539369D01*
G01X63170Y541293D02*
Y543793D01*
X62129D01*
X61795Y543668D01*
X61587Y543501D01*
X61504Y543168D01*
X61587Y542835D01*
X61837Y542626D01*
X62129Y542501D01*
X63170D01*
G01X62129D02*
X61504Y541293D01*
G01X60029Y542335D02*
X59737Y542626D01*
X59487Y542793D01*
X59154Y542876D01*
X58862Y542793D01*
X58654Y542626D01*
X58487Y542376D01*
X58445Y542085D01*
X58487Y541835D01*
X58654Y541585D01*
X58904Y541376D01*
X59195Y541293D01*
X59529Y541376D01*
X59820Y541626D01*
X59987Y542001D01*
X60029Y542418D01*
X59945Y542960D01*
X59820Y543251D01*
X59612Y543543D01*
X59320Y543751D01*
X59029Y543793D01*
X58737Y543710D01*
X58529Y543501D01*
G01X57054Y541793D02*
X56804Y541501D01*
X56470Y541335D01*
X56095Y541293D01*
X55762Y541335D01*
X55429Y541543D01*
X55220Y541793D01*
X55179Y542043D01*
X55262Y542335D01*
X55554Y542543D01*
X55845Y542626D01*
X56220D01*
G01X55845D02*
X55595Y542751D01*
X55387Y542960D01*
X55304Y543210D01*
X55387Y543460D01*
X55595Y543668D01*
X55970Y543793D01*
X56345Y543751D01*
X56720Y543585D01*
G01X53829Y542335D02*
X53537Y542626D01*
X53287Y542793D01*
X52954Y542876D01*
X52662Y542793D01*
X52454Y542626D01*
X52287Y542376D01*
X52245Y542085D01*
X52287Y541835D01*
X52454Y541585D01*
X52704Y541376D01*
X52995Y541293D01*
X53329Y541376D01*
X53620Y541626D01*
X53787Y542001D01*
X53829Y542418D01*
X53745Y542960D01*
X53620Y543251D01*
X53412Y543543D01*
X53120Y543751D01*
X52829Y543793D01*
X52537Y543710D01*
X52329Y543501D01*
G01X63483Y533161D02*
Y535661D01*
X62442D01*
X62108Y535536D01*
X61900Y535369D01*
X61817Y535036D01*
X61900Y534703D01*
X62150Y534494D01*
X62442Y534369D01*
X63483D01*
G01X62442D02*
X61817Y533161D01*
G01X60342Y534203D02*
X60050Y534494D01*
X59800Y534661D01*
X59467Y534744D01*
X59175Y534661D01*
X58967Y534494D01*
X58800Y534244D01*
X58758Y533953D01*
X58800Y533703D01*
X58967Y533453D01*
X59217Y533244D01*
X59508Y533161D01*
X59842Y533244D01*
X60133Y533494D01*
X60300Y533869D01*
X60342Y534286D01*
X60258Y534828D01*
X60133Y535119D01*
X59925Y535411D01*
X59633Y535619D01*
X59342Y535661D01*
X59050Y535578D01*
X58842Y535369D01*
G01X57367Y533661D02*
X57117Y533369D01*
X56783Y533203D01*
X56408Y533161D01*
X56075Y533203D01*
X55742Y533411D01*
X55533Y533661D01*
X55492Y533911D01*
X55575Y534203D01*
X55867Y534411D01*
X56158Y534494D01*
X56533D01*
G01X56158D02*
X55908Y534619D01*
X55700Y534828D01*
X55617Y535078D01*
X55700Y535328D01*
X55908Y535536D01*
X56283Y535661D01*
X56658Y535619D01*
X57033Y535453D01*
G01X53350Y533161D02*
X53058Y533203D01*
X52725Y533328D01*
X52517Y533536D01*
X52433Y533828D01*
X52517Y534119D01*
X52767Y534369D01*
X53142Y534494D01*
X53558D01*
X53808Y534578D01*
X54017Y534786D01*
X54100Y535078D01*
X53975Y535369D01*
X53683Y535578D01*
X53350Y535661D01*
X53017Y535578D01*
X52725Y535369D01*
X52600Y535078D01*
X52683Y534786D01*
X52892Y534578D01*
X53142Y534494D01*
X53558D01*
X53933Y534369D01*
X54183Y534119D01*
X54267Y533828D01*
X54183Y533536D01*
X53975Y533328D01*
X53642Y533203D01*
X53350Y533161D01*
G01X63655Y520878D02*
Y523378D01*
X62614D01*
X62280Y523253D01*
X62072Y523086D01*
X61989Y522753D01*
X62072Y522420D01*
X62322Y522211D01*
X62614Y522086D01*
X63655D01*
G01X62614D02*
X61989Y520878D01*
G01X60514Y521920D02*
X60222Y522211D01*
X59972Y522378D01*
X59639Y522461D01*
X59347Y522378D01*
X59139Y522211D01*
X58972Y521961D01*
X58930Y521670D01*
X58972Y521420D01*
X59139Y521170D01*
X59389Y520961D01*
X59680Y520878D01*
X60014Y520961D01*
X60305Y521211D01*
X60472Y521586D01*
X60514Y522003D01*
X60430Y522545D01*
X60305Y522836D01*
X60097Y523128D01*
X59805Y523336D01*
X59514Y523378D01*
X59222Y523295D01*
X59014Y523086D01*
G01X57539Y521378D02*
X57289Y521086D01*
X56955Y520920D01*
X56580Y520878D01*
X56247Y520920D01*
X55914Y521128D01*
X55705Y521378D01*
X55664Y521628D01*
X55747Y521920D01*
X56039Y522128D01*
X56330Y522211D01*
X56705D01*
G01X56330D02*
X56080Y522336D01*
X55872Y522545D01*
X55789Y522795D01*
X55872Y523045D01*
X56080Y523253D01*
X56455Y523378D01*
X56830Y523336D01*
X57205Y523170D01*
G01X54230Y521170D02*
X53939Y520961D01*
X53605Y520878D01*
X53272Y520961D01*
X52980Y521211D01*
X52772Y521586D01*
X52689Y521961D01*
Y522420D01*
X52772Y522795D01*
X52980Y523128D01*
X53230Y523295D01*
X53522Y523378D01*
X53855Y523295D01*
X54105Y523128D01*
X54272Y522878D01*
X54355Y522545D01*
X54272Y522253D01*
X54064Y521961D01*
X53814Y521795D01*
X53522Y521753D01*
X53189Y521836D01*
X52939Y522045D01*
X52689Y522420D01*
G01X54983Y525300D02*
Y527800D01*
X53942D01*
X53608Y527675D01*
X53400Y527508D01*
X53317Y527175D01*
X53400Y526842D01*
X53650Y526633D01*
X53942Y526508D01*
X54983D01*
G01X53942D02*
X53317Y525300D01*
G01X51842Y527383D02*
X51592Y527633D01*
X51300Y527758D01*
X50967Y527800D01*
X50550Y527717D01*
X50258Y527508D01*
X50175Y527258D01*
X50217Y527008D01*
X50383Y526800D01*
X51217Y526383D01*
X51592Y526092D01*
X51842Y525675D01*
X51925Y525300D01*
X50175D01*
G01X48867Y525675D02*
X48617Y525467D01*
X48325Y525342D01*
X47950Y525300D01*
X47575Y525383D01*
X47283Y525550D01*
X47075Y525842D01*
X47033Y526175D01*
X47117Y526508D01*
X47325Y526717D01*
X47617Y526883D01*
X47908Y526925D01*
X48200Y526883D01*
X48575Y526717D01*
X48450Y527800D01*
X47325D01*
G01X45767Y525675D02*
X45517Y525467D01*
X45225Y525342D01*
X44850Y525300D01*
X44475Y525383D01*
X44183Y525550D01*
X43975Y525842D01*
X43933Y526175D01*
X44017Y526508D01*
X44225Y526717D01*
X44517Y526883D01*
X44808Y526925D01*
X45100Y526883D01*
X45475Y526717D01*
X45350Y527800D01*
X44225D01*
G01X46800Y521700D02*
Y524200D01*
X45759D01*
X45425Y524075D01*
X45217Y523908D01*
X45134Y523575D01*
X45217Y523242D01*
X45467Y523033D01*
X45759Y522908D01*
X46800D01*
G01X45759D02*
X45134Y521700D01*
G01X43659Y523783D02*
X43409Y524033D01*
X43117Y524158D01*
X42784Y524200D01*
X42367Y524117D01*
X42075Y523908D01*
X41992Y523658D01*
X42034Y523408D01*
X42200Y523200D01*
X43034Y522783D01*
X43409Y522492D01*
X43659Y522075D01*
X43742Y521700D01*
X41992D01*
G01X40559Y522742D02*
X40267Y523033D01*
X40017Y523200D01*
X39684Y523283D01*
X39392Y523200D01*
X39184Y523033D01*
X39017Y522783D01*
X38975Y522492D01*
X39017Y522242D01*
X39184Y521992D01*
X39434Y521783D01*
X39725Y521700D01*
X40059Y521783D01*
X40350Y522033D01*
X40517Y522408D01*
X40559Y522825D01*
X40475Y523367D01*
X40350Y523658D01*
X40142Y523950D01*
X39850Y524158D01*
X39559Y524200D01*
X39267Y524117D01*
X39059Y523908D01*
G01X36167Y521700D02*
Y524200D01*
X37709Y522408D01*
X35625D01*
G01X49151Y543056D02*
Y545556D01*
X48110D01*
X47776Y545431D01*
X47568Y545264D01*
X47485Y544931D01*
X47568Y544598D01*
X47818Y544389D01*
X48110Y544264D01*
X49151D01*
G01X48110D02*
X47485Y543056D01*
G01X46010Y545139D02*
X45760Y545389D01*
X45468Y545514D01*
X45135Y545556D01*
X44718Y545473D01*
X44426Y545264D01*
X44343Y545014D01*
X44385Y544764D01*
X44551Y544556D01*
X45385Y544139D01*
X45760Y543848D01*
X46010Y543431D01*
X46093Y543056D01*
X44343D01*
G01X42826Y543348D02*
X42535Y543139D01*
X42201Y543056D01*
X41868Y543139D01*
X41576Y543389D01*
X41368Y543764D01*
X41285Y544139D01*
Y544598D01*
X41368Y544973D01*
X41576Y545306D01*
X41826Y545473D01*
X42118Y545556D01*
X42451Y545473D01*
X42701Y545306D01*
X42868Y545056D01*
X42951Y544723D01*
X42868Y544431D01*
X42660Y544139D01*
X42410Y543973D01*
X42118Y543931D01*
X41785Y544014D01*
X41535Y544223D01*
X41285Y544598D01*
G01X39101Y543056D02*
X39018Y543598D01*
X38893Y544056D01*
X38726Y544473D01*
X38518Y544931D01*
X38185Y545556D01*
X39851D01*
G01X35918Y543056D02*
X35626Y543098D01*
X35293Y543223D01*
X35085Y543431D01*
X35001Y543723D01*
X35085Y544014D01*
X35335Y544264D01*
X35710Y544389D01*
X36126D01*
X36376Y544473D01*
X36585Y544681D01*
X36668Y544973D01*
X36543Y545264D01*
X36251Y545473D01*
X35918Y545556D01*
X35585Y545473D01*
X35293Y545264D01*
X35168Y544973D01*
X35251Y544681D01*
X35460Y544473D01*
X35710Y544389D01*
X36126D01*
X36501Y544264D01*
X36751Y544014D01*
X36835Y543723D01*
X36751Y543431D01*
X36543Y543223D01*
X36210Y543098D01*
X35918Y543056D01*
G01X63483Y553161D02*
Y555661D01*
X62442D01*
X62108Y555536D01*
X61900Y555369D01*
X61817Y555036D01*
X61900Y554703D01*
X62150Y554494D01*
X62442Y554369D01*
X63483D01*
G01X62442D02*
X61817Y553161D01*
G01X60342Y555244D02*
X60092Y555494D01*
X59800Y555619D01*
X59467Y555661D01*
X59050Y555578D01*
X58758Y555369D01*
X58675Y555119D01*
X58717Y554869D01*
X58883Y554661D01*
X59717Y554244D01*
X60092Y553953D01*
X60342Y553536D01*
X60425Y553161D01*
X58675D01*
G01X57158Y553453D02*
X56867Y553244D01*
X56533Y553161D01*
X56200Y553244D01*
X55908Y553494D01*
X55700Y553869D01*
X55617Y554244D01*
Y554703D01*
X55700Y555078D01*
X55908Y555411D01*
X56158Y555578D01*
X56450Y555661D01*
X56783Y555578D01*
X57033Y555411D01*
X57200Y555161D01*
X57283Y554828D01*
X57200Y554536D01*
X56992Y554244D01*
X56742Y554078D01*
X56450Y554036D01*
X56117Y554119D01*
X55867Y554328D01*
X55617Y554703D01*
G01X54058Y553453D02*
X53767Y553244D01*
X53433Y553161D01*
X53100Y553244D01*
X52808Y553494D01*
X52600Y553869D01*
X52517Y554244D01*
Y554703D01*
X52600Y555078D01*
X52808Y555411D01*
X53058Y555578D01*
X53350Y555661D01*
X53683Y555578D01*
X53933Y555411D01*
X54100Y555161D01*
X54183Y554828D01*
X54100Y554536D01*
X53892Y554244D01*
X53642Y554078D01*
X53350Y554036D01*
X53017Y554119D01*
X52767Y554328D01*
X52517Y554703D01*
G01X63483Y549161D02*
Y551661D01*
X62442D01*
X62108Y551536D01*
X61900Y551369D01*
X61817Y551036D01*
X61900Y550703D01*
X62150Y550494D01*
X62442Y550369D01*
X63483D01*
G01X62442D02*
X61817Y549161D01*
G01X60342Y550203D02*
X60050Y550494D01*
X59800Y550661D01*
X59467Y550744D01*
X59175Y550661D01*
X58967Y550494D01*
X58800Y550244D01*
X58758Y549953D01*
X58800Y549703D01*
X58967Y549453D01*
X59217Y549244D01*
X59508Y549161D01*
X59842Y549244D01*
X60133Y549494D01*
X60300Y549869D01*
X60342Y550286D01*
X60258Y550828D01*
X60133Y551119D01*
X59925Y551411D01*
X59633Y551619D01*
X59342Y551661D01*
X59050Y551578D01*
X58842Y551369D01*
G01X55950Y549161D02*
Y551661D01*
X57492Y549869D01*
X55408D01*
G01X53433Y549161D02*
X53350Y549703D01*
X53225Y550161D01*
X53058Y550578D01*
X52850Y551036D01*
X52517Y551661D01*
X54183D01*
G01X59483Y562800D02*
Y565300D01*
X58442D01*
X58108Y565175D01*
X57900Y565008D01*
X57817Y564675D01*
X57900Y564342D01*
X58150Y564133D01*
X58442Y564008D01*
X59483D01*
G01X58442D02*
X57817Y562800D01*
G01X56467Y563175D02*
X56217Y562967D01*
X55925Y562842D01*
X55550Y562800D01*
X55175Y562883D01*
X54883Y563050D01*
X54675Y563342D01*
X54633Y563675D01*
X54717Y564008D01*
X54925Y564217D01*
X55217Y564383D01*
X55508Y564425D01*
X55800Y564383D01*
X56175Y564217D01*
X56050Y565300D01*
X54925D01*
G01X53367Y563300D02*
X53117Y563008D01*
X52783Y562842D01*
X52408Y562800D01*
X52075Y562842D01*
X51742Y563050D01*
X51533Y563300D01*
X51492Y563550D01*
X51575Y563842D01*
X51867Y564050D01*
X52158Y564133D01*
X52533D01*
G01X52158D02*
X51908Y564258D01*
X51700Y564467D01*
X51617Y564717D01*
X51700Y564967D01*
X51908Y565175D01*
X52283Y565300D01*
X52658Y565258D01*
X53033Y565092D01*
G01X49350Y562800D02*
X49058Y562842D01*
X48725Y562967D01*
X48517Y563175D01*
X48433Y563467D01*
X48517Y563758D01*
X48767Y564008D01*
X49142Y564133D01*
X49558D01*
X49808Y564217D01*
X50017Y564425D01*
X50100Y564717D01*
X49975Y565008D01*
X49683Y565217D01*
X49350Y565300D01*
X49017Y565217D01*
X48725Y565008D01*
X48600Y564717D01*
X48683Y564425D01*
X48892Y564217D01*
X49142Y564133D01*
X49558D01*
X49933Y564008D01*
X50183Y563758D01*
X50267Y563467D01*
X50183Y563175D01*
X49975Y562967D01*
X49642Y562842D01*
X49350Y562800D01*
G01X60083Y557700D02*
Y560200D01*
X59042D01*
X58708Y560075D01*
X58500Y559908D01*
X58417Y559575D01*
X58500Y559242D01*
X58750Y559033D01*
X59042Y558908D01*
X60083D01*
G01X59042D02*
X58417Y557700D01*
G01X56233D02*
X56150Y558242D01*
X56025Y558700D01*
X55858Y559117D01*
X55650Y559575D01*
X55317Y560200D01*
X56983D01*
G01X52550Y557700D02*
Y560200D01*
X54092Y558408D01*
X52008D01*
G01X50867Y558200D02*
X50617Y557908D01*
X50283Y557742D01*
X49908Y557700D01*
X49575Y557742D01*
X49242Y557950D01*
X49033Y558200D01*
X48992Y558450D01*
X49075Y558742D01*
X49367Y558950D01*
X49658Y559033D01*
X50033D01*
G01X49658D02*
X49408Y559158D01*
X49200Y559367D01*
X49117Y559617D01*
X49200Y559867D01*
X49408Y560075D01*
X49783Y560200D01*
X50158Y560158D01*
X50533Y559992D01*
G01X92292Y259967D02*
X92417Y259717D01*
X92500Y259425D01*
Y259092D01*
X92375Y258717D01*
X92167Y258425D01*
X91917Y258217D01*
X91500Y258050D01*
X91125Y258008D01*
X90750Y258092D01*
X90500Y258217D01*
X90250Y258467D01*
X90083Y258758D01*
X90000Y259050D01*
Y259342D01*
X90083Y259633D01*
X90208Y259883D01*
X90375Y260092D01*
G01X91042Y261358D02*
X91333Y261650D01*
X91500Y261900D01*
X91583Y262233D01*
X91500Y262525D01*
X91333Y262733D01*
X91083Y262900D01*
X90792Y262942D01*
X90542Y262900D01*
X90292Y262733D01*
X90083Y262483D01*
X90000Y262192D01*
X90083Y261858D01*
X90333Y261567D01*
X90708Y261400D01*
X91125Y261358D01*
X91667Y261442D01*
X91958Y261567D01*
X92250Y261775D01*
X92458Y262067D01*
X92500Y262358D01*
X92417Y262650D01*
X92208Y262858D01*
G01X92083Y264458D02*
X92333Y264708D01*
X92458Y265000D01*
X92500Y265333D01*
X92417Y265750D01*
X92208Y266042D01*
X91958Y266125D01*
X91708Y266083D01*
X91500Y265917D01*
X91083Y265083D01*
X90792Y264708D01*
X90375Y264458D01*
X90000Y264375D01*
Y266125D01*
G01X91042Y267558D02*
X91333Y267850D01*
X91500Y268100D01*
X91583Y268433D01*
X91500Y268725D01*
X91333Y268933D01*
X91083Y269100D01*
X90792Y269142D01*
X90542Y269100D01*
X90292Y268933D01*
X90083Y268683D01*
X90000Y268392D01*
X90083Y268058D01*
X90333Y267767D01*
X90708Y267600D01*
X91125Y267558D01*
X91667Y267642D01*
X91958Y267767D01*
X92250Y267975D01*
X92458Y268267D01*
X92500Y268558D01*
X92417Y268850D01*
X92208Y269058D01*
G01X73700Y253717D02*
X76200D01*
Y254758D01*
X76075Y255092D01*
X75908Y255300D01*
X75575Y255383D01*
X75242Y255300D01*
X75033Y255050D01*
X74908Y254758D01*
Y253717D01*
G01Y254758D02*
X73700Y255383D01*
G01X74200Y256733D02*
X73908Y256983D01*
X73742Y257317D01*
X73700Y257692D01*
X73742Y258025D01*
X73950Y258358D01*
X74200Y258567D01*
X74450Y258608D01*
X74742Y258525D01*
X74950Y258233D01*
X75033Y257942D01*
Y257567D01*
G01Y257942D02*
X75158Y258192D01*
X75367Y258400D01*
X75617Y258483D01*
X75867Y258400D01*
X76075Y258192D01*
X76200Y257817D01*
X76158Y257442D01*
X75992Y257067D01*
G01X73700Y260667D02*
X74242Y260750D01*
X74700Y260875D01*
X75117Y261042D01*
X75575Y261250D01*
X76200Y261583D01*
Y259917D01*
G01X73700Y264350D02*
X76200D01*
X74408Y262808D01*
Y264892D01*
G01X78400Y253717D02*
X80900D01*
Y254758D01*
X80775Y255092D01*
X80608Y255300D01*
X80275Y255383D01*
X79942Y255300D01*
X79733Y255050D01*
X79608Y254758D01*
Y253717D01*
G01Y254758D02*
X78400Y255383D01*
G01Y258150D02*
X80900D01*
X79108Y256608D01*
Y258692D01*
G01X80483Y259958D02*
X80733Y260208D01*
X80858Y260500D01*
X80900Y260833D01*
X80817Y261250D01*
X80608Y261542D01*
X80358Y261625D01*
X80108Y261583D01*
X79900Y261417D01*
X79483Y260583D01*
X79192Y260208D01*
X78775Y259958D01*
X78400Y259875D01*
Y261625D01*
G01X78775Y262933D02*
X78567Y263183D01*
X78442Y263475D01*
X78400Y263850D01*
X78483Y264225D01*
X78650Y264517D01*
X78942Y264725D01*
X79275Y264767D01*
X79608Y264683D01*
X79817Y264475D01*
X79983Y264183D01*
X80025Y263892D01*
X79983Y263600D01*
X79817Y263225D01*
X80900Y263350D01*
Y264475D01*
G01X96500Y273460D02*
Y277460D01*
X103900D01*
G01X86800Y271940D02*
Y275940D01*
X94200D01*
G01X86533Y298092D02*
X86783Y298217D01*
X87075Y298300D01*
X87408D01*
X87783Y298175D01*
X88075Y297967D01*
X88283Y297717D01*
X88450Y297300D01*
X88492Y296925D01*
X88408Y296550D01*
X88283Y296300D01*
X88033Y296050D01*
X87742Y295883D01*
X87450Y295800D01*
X87158D01*
X86867Y295883D01*
X86617Y296008D01*
X86408Y296175D01*
G01X85142Y296842D02*
X84850Y297133D01*
X84600Y297300D01*
X84267Y297383D01*
X83975Y297300D01*
X83767Y297133D01*
X83600Y296883D01*
X83558Y296592D01*
X83600Y296342D01*
X83767Y296092D01*
X84017Y295883D01*
X84308Y295800D01*
X84642Y295883D01*
X84933Y296133D01*
X85100Y296508D01*
X85142Y296925D01*
X85058Y297467D01*
X84933Y297758D01*
X84725Y298050D01*
X84433Y298258D01*
X84142Y298300D01*
X83850Y298217D01*
X83642Y298008D01*
G01X82167Y296300D02*
X81917Y296008D01*
X81583Y295842D01*
X81208Y295800D01*
X80875Y295842D01*
X80542Y296050D01*
X80333Y296300D01*
X80292Y296550D01*
X80375Y296842D01*
X80667Y297050D01*
X80958Y297133D01*
X81333D01*
G01X80958D02*
X80708Y297258D01*
X80500Y297467D01*
X80417Y297717D01*
X80500Y297967D01*
X80708Y298175D01*
X81083Y298300D01*
X81458Y298258D01*
X81833Y298092D01*
G01X77650Y295800D02*
Y298300D01*
X79192Y296508D01*
X77108D01*
G01X87983Y280200D02*
Y282700D01*
X86942D01*
X86608Y282575D01*
X86400Y282408D01*
X86317Y282075D01*
X86400Y281742D01*
X86650Y281533D01*
X86942Y281408D01*
X87983D01*
G01X86942D02*
X86317Y280200D01*
G01X84967Y280700D02*
X84717Y280408D01*
X84383Y280242D01*
X84008Y280200D01*
X83675Y280242D01*
X83342Y280450D01*
X83133Y280700D01*
X83092Y280950D01*
X83175Y281242D01*
X83467Y281450D01*
X83758Y281533D01*
X84133D01*
G01X83758D02*
X83508Y281658D01*
X83300Y281867D01*
X83217Y282117D01*
X83300Y282367D01*
X83508Y282575D01*
X83883Y282700D01*
X84258Y282658D01*
X84633Y282492D01*
G01X81658Y280492D02*
X81367Y280283D01*
X81033Y280200D01*
X80700Y280283D01*
X80408Y280533D01*
X80200Y280908D01*
X80117Y281283D01*
Y281742D01*
X80200Y282117D01*
X80408Y282450D01*
X80658Y282617D01*
X80950Y282700D01*
X81283Y282617D01*
X81533Y282450D01*
X81700Y282200D01*
X81783Y281867D01*
X81700Y281575D01*
X81492Y281283D01*
X81242Y281117D01*
X80950Y281075D01*
X80617Y281158D01*
X80367Y281367D01*
X80117Y281742D01*
G01X78642Y281242D02*
X78350Y281533D01*
X78100Y281700D01*
X77767Y281783D01*
X77475Y281700D01*
X77267Y281533D01*
X77100Y281283D01*
X77058Y280992D01*
X77100Y280742D01*
X77267Y280492D01*
X77517Y280283D01*
X77808Y280200D01*
X78142Y280283D01*
X78433Y280533D01*
X78600Y280908D01*
X78642Y281325D01*
X78558Y281867D01*
X78433Y282158D01*
X78225Y282450D01*
X77933Y282658D01*
X77642Y282700D01*
X77350Y282617D01*
X77142Y282408D01*
G01X106933Y316692D02*
X107183Y316817D01*
X107475Y316900D01*
X107808D01*
X108183Y316775D01*
X108475Y316567D01*
X108683Y316317D01*
X108850Y315900D01*
X108892Y315525D01*
X108808Y315150D01*
X108683Y314900D01*
X108433Y314650D01*
X108142Y314483D01*
X107850Y314400D01*
X107558D01*
X107267Y314483D01*
X107017Y314608D01*
X106808Y314775D01*
G01X105542Y315442D02*
X105250Y315733D01*
X105000Y315900D01*
X104667Y315983D01*
X104375Y315900D01*
X104167Y315733D01*
X104000Y315483D01*
X103958Y315192D01*
X104000Y314942D01*
X104167Y314692D01*
X104417Y314483D01*
X104708Y314400D01*
X105042Y314483D01*
X105333Y314733D01*
X105500Y315108D01*
X105542Y315525D01*
X105458Y316067D01*
X105333Y316358D01*
X105125Y316650D01*
X104833Y316858D01*
X104542Y316900D01*
X104250Y316817D01*
X104042Y316608D01*
G01X102442Y316483D02*
X102192Y316733D01*
X101900Y316858D01*
X101567Y316900D01*
X101150Y316817D01*
X100858Y316608D01*
X100775Y316358D01*
X100817Y316108D01*
X100983Y315900D01*
X101817Y315483D01*
X102192Y315192D01*
X102442Y314775D01*
X102525Y314400D01*
X100775D01*
G01X99467Y314775D02*
X99217Y314567D01*
X98925Y314442D01*
X98550Y314400D01*
X98175Y314483D01*
X97883Y314650D01*
X97675Y314942D01*
X97633Y315275D01*
X97717Y315608D01*
X97925Y315817D01*
X98217Y315983D01*
X98508Y316025D01*
X98800Y315983D01*
X99175Y315817D01*
X99050Y316900D01*
X97925D01*
G01X82506Y314177D02*
X82631Y313927D01*
X82714Y313635D01*
Y313302D01*
X82589Y312927D01*
X82381Y312635D01*
X82131Y312427D01*
X81714Y312260D01*
X81339Y312218D01*
X80964Y312302D01*
X80714Y312427D01*
X80464Y312677D01*
X80297Y312968D01*
X80214Y313260D01*
Y313552D01*
X80297Y313843D01*
X80422Y314093D01*
X80589Y314302D01*
G01X81256Y315568D02*
X81547Y315860D01*
X81714Y316110D01*
X81797Y316443D01*
X81714Y316735D01*
X81547Y316943D01*
X81297Y317110D01*
X81006Y317152D01*
X80756Y317110D01*
X80506Y316943D01*
X80297Y316693D01*
X80214Y316402D01*
X80297Y316068D01*
X80547Y315777D01*
X80922Y315610D01*
X81339Y315568D01*
X81881Y315652D01*
X82172Y315777D01*
X82464Y315985D01*
X82672Y316277D01*
X82714Y316568D01*
X82631Y316860D01*
X82422Y317068D01*
G01X80214Y319960D02*
X82714D01*
X80922Y318418D01*
Y320502D01*
G01X82714Y322560D02*
X82631Y322227D01*
X82422Y321977D01*
X82172Y321810D01*
X81839Y321685D01*
X81464Y321643D01*
X81089Y321685D01*
X80756Y321810D01*
X80506Y321977D01*
X80297Y322227D01*
X80214Y322560D01*
X80297Y322893D01*
X80506Y323143D01*
X80756Y323310D01*
X81089Y323435D01*
X81464Y323477D01*
X81839Y323435D01*
X82172Y323310D01*
X82422Y323143D01*
X82631Y322893D01*
X82714Y322560D01*
G01X86142Y471905D02*
Y474405D01*
X85101D01*
X84767Y474280D01*
X84559Y474113D01*
X84476Y473780D01*
X84559Y473447D01*
X84809Y473238D01*
X85101Y473113D01*
X86142D01*
G01X85101D02*
X84476Y471905D01*
G01X83126Y472280D02*
X82876Y472072D01*
X82584Y471947D01*
X82209Y471905D01*
X81834Y471988D01*
X81542Y472155D01*
X81334Y472447D01*
X81292Y472780D01*
X81376Y473113D01*
X81584Y473322D01*
X81876Y473488D01*
X82167Y473530D01*
X82459Y473488D01*
X82834Y473322D01*
X82709Y474405D01*
X81584D01*
G01X80026Y472280D02*
X79776Y472072D01*
X79484Y471947D01*
X79109Y471905D01*
X78734Y471988D01*
X78442Y472155D01*
X78234Y472447D01*
X78192Y472780D01*
X78276Y473113D01*
X78484Y473322D01*
X78776Y473488D01*
X79067Y473530D01*
X79359Y473488D01*
X79734Y473322D01*
X79609Y474405D01*
X78484D01*
G01X75509Y471905D02*
Y474405D01*
X77051Y472613D01*
X74967D01*
G01X98700Y478400D02*
Y474400D01*
X91300D01*
G01X98700Y482400D02*
Y478400D01*
X91300D01*
G01X86192Y468205D02*
Y470705D01*
X85151D01*
X84817Y470580D01*
X84609Y470413D01*
X84526Y470080D01*
X84609Y469747D01*
X84859Y469538D01*
X85151Y469413D01*
X86192D01*
G01X85151D02*
X84526Y468205D01*
G01X82967Y468497D02*
X82676Y468288D01*
X82342Y468205D01*
X82009Y468288D01*
X81717Y468538D01*
X81509Y468913D01*
X81426Y469288D01*
Y469747D01*
X81509Y470122D01*
X81717Y470455D01*
X81967Y470622D01*
X82259Y470705D01*
X82592Y470622D01*
X82842Y470455D01*
X83009Y470205D01*
X83092Y469872D01*
X83009Y469580D01*
X82801Y469288D01*
X82551Y469122D01*
X82259Y469080D01*
X81926Y469163D01*
X81676Y469372D01*
X81426Y469747D01*
G01X79159Y470705D02*
X79492Y470622D01*
X79742Y470413D01*
X79909Y470163D01*
X80034Y469830D01*
X80076Y469455D01*
X80034Y469080D01*
X79909Y468747D01*
X79742Y468497D01*
X79492Y468288D01*
X79159Y468205D01*
X78826Y468288D01*
X78576Y468497D01*
X78409Y468747D01*
X78284Y469080D01*
X78242Y469455D01*
X78284Y469830D01*
X78409Y470163D01*
X78576Y470413D01*
X78826Y470622D01*
X79159Y470705D01*
G01X76851Y470288D02*
X76601Y470538D01*
X76309Y470663D01*
X75976Y470705D01*
X75559Y470622D01*
X75267Y470413D01*
X75184Y470163D01*
X75226Y469913D01*
X75392Y469705D01*
X76226Y469288D01*
X76601Y468997D01*
X76851Y468580D01*
X76934Y468205D01*
X75184D01*
G01X72459D02*
Y470705D01*
X74001Y468913D01*
X71917D01*
G01X98700Y474400D02*
Y470400D01*
X91300D01*
G01X77125Y461233D02*
Y463733D01*
X76084D01*
X75750Y463608D01*
X75542Y463441D01*
X75459Y463108D01*
X75542Y462775D01*
X75792Y462566D01*
X76084Y462441D01*
X77125D01*
G01X76084D02*
X75459Y461233D01*
G01X73275D02*
X73192Y461775D01*
X73067Y462233D01*
X72900Y462650D01*
X72692Y463108D01*
X72359Y463733D01*
X74025D01*
G01X70092Y461233D02*
Y463733D01*
X70592Y463233D01*
G01Y461233D02*
X69592D01*
G01X66992D02*
Y463733D01*
X67492Y463233D01*
G01Y461233D02*
X66492D01*
G01X86042Y465549D02*
Y461549D01*
X78642D01*
G01X82900Y480600D02*
Y476600D01*
X75500D01*
G01X104587Y487082D02*
Y489582D01*
X103546D01*
X103212Y489457D01*
X103004Y489290D01*
X102921Y488957D01*
X103004Y488624D01*
X103254Y488415D01*
X103546Y488290D01*
X104587D01*
G01X103546D02*
X102921Y487082D01*
G01X100737D02*
X100654Y487624D01*
X100529Y488082D01*
X100362Y488499D01*
X100154Y488957D01*
X99821Y489582D01*
X101487D01*
G01X97554D02*
X97887Y489499D01*
X98137Y489290D01*
X98304Y489040D01*
X98429Y488707D01*
X98471Y488332D01*
X98429Y487957D01*
X98304Y487624D01*
X98137Y487374D01*
X97887Y487165D01*
X97554Y487082D01*
X97221Y487165D01*
X96971Y487374D01*
X96804Y487624D01*
X96679Y487957D01*
X96637Y488332D01*
X96679Y488707D01*
X96804Y489040D01*
X96971Y489290D01*
X97221Y489499D01*
X97554Y489582D01*
G01X93954Y487082D02*
Y489582D01*
X95496Y487790D01*
X93412D01*
G01X98700Y486600D02*
Y482600D01*
X91300D01*
G01X78800Y512500D02*
Y516500D01*
X86200D01*
G01X90559Y511567D02*
Y515567D01*
X97959D01*
G01X90256Y485842D02*
Y488342D01*
X89215D01*
X88881Y488217D01*
X88673Y488050D01*
X88590Y487717D01*
X88673Y487384D01*
X88923Y487175D01*
X89215Y487050D01*
X90256D01*
G01X89215D02*
X88590Y485842D01*
G01X87115Y487925D02*
X86865Y488175D01*
X86573Y488300D01*
X86240Y488342D01*
X85823Y488259D01*
X85531Y488050D01*
X85448Y487800D01*
X85490Y487550D01*
X85656Y487342D01*
X86490Y486925D01*
X86865Y486634D01*
X87115Y486217D01*
X87198Y485842D01*
X85448D01*
G01X84015Y487925D02*
X83765Y488175D01*
X83473Y488300D01*
X83140Y488342D01*
X82723Y488259D01*
X82431Y488050D01*
X82348Y487800D01*
X82390Y487550D01*
X82556Y487342D01*
X83390Y486925D01*
X83765Y486634D01*
X84015Y486217D01*
X84098Y485842D01*
X82348D01*
G01X80123D02*
Y488342D01*
X80623Y487842D01*
G01Y485842D02*
X79623D01*
G01X76200Y500500D02*
Y496500D01*
X68800D01*
G01X76617Y488086D02*
Y492086D01*
X84017D01*
G01X76617D02*
Y496086D01*
X84017D01*
G01X78800Y508500D02*
Y512500D01*
X86200D01*
G01X78800Y500500D02*
Y504500D01*
X86200D01*
G01X89987Y494084D02*
Y498084D01*
X97387D01*
G01X89987D02*
Y502084D01*
X97387D01*
G01X78800Y504500D02*
Y508500D01*
X86200D01*
G01X89987Y502084D02*
Y506084D01*
X97387D01*
G01X75808Y508552D02*
Y504552D01*
X68408D01*
G01X101750Y523300D02*
Y520800D01*
G01X102708Y523300D02*
X100792D01*
G01X99483Y520800D02*
Y523300D01*
X98483D01*
X98150Y523175D01*
X97900Y522883D01*
X97817Y522550D01*
X97900Y522217D01*
X98108Y521967D01*
X98483Y521842D01*
X99483D01*
G01X96258Y521092D02*
X95967Y520883D01*
X95633Y520800D01*
X95300Y520883D01*
X95008Y521133D01*
X94800Y521508D01*
X94717Y521883D01*
Y522342D01*
X94800Y522717D01*
X95008Y523050D01*
X95258Y523217D01*
X95550Y523300D01*
X95883Y523217D01*
X96133Y523050D01*
X96300Y522800D01*
X96383Y522467D01*
X96300Y522175D01*
X96092Y521883D01*
X95842Y521717D01*
X95550Y521675D01*
X95217Y521758D01*
X94967Y521967D01*
X94717Y522342D01*
G01X93242Y521842D02*
X92950Y522133D01*
X92700Y522300D01*
X92367Y522383D01*
X92075Y522300D01*
X91867Y522133D01*
X91700Y521883D01*
X91658Y521592D01*
X91700Y521342D01*
X91867Y521092D01*
X92117Y520883D01*
X92408Y520800D01*
X92742Y520883D01*
X93033Y521133D01*
X93200Y521508D01*
X93242Y521925D01*
X93158Y522467D01*
X93033Y522758D01*
X92825Y523050D01*
X92533Y523258D01*
X92242Y523300D01*
X91950Y523217D01*
X91742Y523008D01*
G01X90420Y539681D02*
Y543681D01*
X97820D01*
G01X91336Y524266D02*
Y528266D01*
X98736D01*
G01X90559Y515567D02*
Y519567D01*
X97959D01*
G01X78800Y516500D02*
Y520500D01*
X86200D01*
G01X90420Y543681D02*
Y547681D01*
X97820D01*
G01X65300Y533000D02*
Y537000D01*
X72700D01*
G01X86200Y548500D02*
Y544500D01*
X78800D01*
G01X86200Y532500D02*
Y528500D01*
X78800D01*
G01Y536500D02*
Y540500D01*
X86200D01*
G01Y544500D02*
Y540500D01*
X78800D01*
G01Y532500D02*
Y536500D01*
X86200D01*
G01Y524500D02*
Y520500D01*
X78800D01*
G01X64900Y524900D02*
Y528900D01*
X72300D01*
G01X68800Y520500D02*
Y524500D01*
X76200D01*
G01X91336Y528266D02*
Y532266D01*
X98736D01*
G01X68600Y543700D02*
Y547700D01*
X76000D01*
G01X78800Y552500D02*
Y556500D01*
X86200D01*
G01Y552500D02*
Y548500D01*
X78800D01*
G01X94360Y561310D02*
X90360D01*
Y568710D01*
G01X90420Y547681D02*
Y551681D01*
X97820D01*
G01X86022Y564789D02*
Y560789D01*
X78622D01*
G01X99857Y571209D02*
Y573709D01*
X98816D01*
X98482Y573584D01*
X98274Y573417D01*
X98191Y573084D01*
X98274Y572751D01*
X98524Y572542D01*
X98816Y572417D01*
X99857D01*
G01X98816D02*
X98191Y571209D01*
G01X96841Y571709D02*
X96591Y571417D01*
X96257Y571251D01*
X95882Y571209D01*
X95549Y571251D01*
X95216Y571459D01*
X95007Y571709D01*
X94966Y571959D01*
X95049Y572251D01*
X95341Y572459D01*
X95632Y572542D01*
X96007D01*
G01X95632D02*
X95382Y572667D01*
X95174Y572876D01*
X95091Y573126D01*
X95174Y573376D01*
X95382Y573584D01*
X95757Y573709D01*
X96132Y573667D01*
X96507Y573501D01*
G01X93741Y571584D02*
X93491Y571376D01*
X93199Y571251D01*
X92824Y571209D01*
X92449Y571292D01*
X92157Y571459D01*
X91949Y571751D01*
X91907Y572084D01*
X91991Y572417D01*
X92199Y572626D01*
X92491Y572792D01*
X92782Y572834D01*
X93074Y572792D01*
X93449Y572626D01*
X93324Y573709D01*
X92199D01*
G01X90516Y572251D02*
X90224Y572542D01*
X89974Y572709D01*
X89641Y572792D01*
X89349Y572709D01*
X89141Y572542D01*
X88974Y572292D01*
X88932Y572001D01*
X88974Y571751D01*
X89141Y571501D01*
X89391Y571292D01*
X89682Y571209D01*
X90016Y571292D01*
X90307Y571542D01*
X90474Y571917D01*
X90516Y572334D01*
X90432Y572876D01*
X90307Y573167D01*
X90099Y573459D01*
X89807Y573667D01*
X89516Y573709D01*
X89224Y573626D01*
X89016Y573417D01*
G01X100034Y574881D02*
Y577381D01*
X98993D01*
X98659Y577256D01*
X98451Y577089D01*
X98368Y576756D01*
X98451Y576423D01*
X98701Y576214D01*
X98993Y576089D01*
X100034D01*
G01X98993D02*
X98368Y574881D01*
G01X97018Y575381D02*
X96768Y575089D01*
X96434Y574923D01*
X96059Y574881D01*
X95726Y574923D01*
X95393Y575131D01*
X95184Y575381D01*
X95143Y575631D01*
X95226Y575923D01*
X95518Y576131D01*
X95809Y576214D01*
X96184D01*
G01X95809D02*
X95559Y576339D01*
X95351Y576548D01*
X95268Y576798D01*
X95351Y577048D01*
X95559Y577256D01*
X95934Y577381D01*
X96309Y577339D01*
X96684Y577173D01*
G01X93793Y575923D02*
X93501Y576214D01*
X93251Y576381D01*
X92918Y576464D01*
X92626Y576381D01*
X92418Y576214D01*
X92251Y575964D01*
X92209Y575673D01*
X92251Y575423D01*
X92418Y575173D01*
X92668Y574964D01*
X92959Y574881D01*
X93293Y574964D01*
X93584Y575214D01*
X93751Y575589D01*
X93793Y576006D01*
X93709Y576548D01*
X93584Y576839D01*
X93376Y577131D01*
X93084Y577339D01*
X92793Y577381D01*
X92501Y577298D01*
X92293Y577089D01*
G01X89901Y577381D02*
X90234Y577298D01*
X90484Y577089D01*
X90651Y576839D01*
X90776Y576506D01*
X90818Y576131D01*
X90776Y575756D01*
X90651Y575423D01*
X90484Y575173D01*
X90234Y574964D01*
X89901Y574881D01*
X89568Y574964D01*
X89318Y575173D01*
X89151Y575423D01*
X89026Y575756D01*
X88984Y576131D01*
X89026Y576506D01*
X89151Y576839D01*
X89318Y577089D01*
X89568Y577298D01*
X89901Y577381D01*
G01X99883Y578403D02*
Y580903D01*
X98842D01*
X98508Y580778D01*
X98300Y580611D01*
X98217Y580278D01*
X98300Y579945D01*
X98550Y579736D01*
X98842Y579611D01*
X99883D01*
G01X98842D02*
X98217Y578403D01*
G01X96867Y578903D02*
X96617Y578611D01*
X96283Y578445D01*
X95908Y578403D01*
X95575Y578445D01*
X95242Y578653D01*
X95033Y578903D01*
X94992Y579153D01*
X95075Y579445D01*
X95367Y579653D01*
X95658Y579736D01*
X96033D01*
G01X95658D02*
X95408Y579861D01*
X95200Y580070D01*
X95117Y580320D01*
X95200Y580570D01*
X95408Y580778D01*
X95783Y580903D01*
X96158Y580861D01*
X96533Y580695D01*
G01X93642Y579445D02*
X93350Y579736D01*
X93100Y579903D01*
X92767Y579986D01*
X92475Y579903D01*
X92267Y579736D01*
X92100Y579486D01*
X92058Y579195D01*
X92100Y578945D01*
X92267Y578695D01*
X92517Y578486D01*
X92808Y578403D01*
X93142Y578486D01*
X93433Y578736D01*
X93600Y579111D01*
X93642Y579528D01*
X93558Y580070D01*
X93433Y580361D01*
X93225Y580653D01*
X92933Y580861D01*
X92642Y580903D01*
X92350Y580820D01*
X92142Y580611D01*
G01X89250Y578403D02*
Y580903D01*
X90792Y579111D01*
X88708D01*
G01X78762Y556640D02*
Y560640D01*
X86162D01*
G01X99883Y582033D02*
Y584533D01*
X98842D01*
X98508Y584408D01*
X98300Y584241D01*
X98217Y583908D01*
X98300Y583575D01*
X98550Y583366D01*
X98842Y583241D01*
X99883D01*
G01X98842D02*
X98217Y582033D01*
G01X96867Y582533D02*
X96617Y582241D01*
X96283Y582075D01*
X95908Y582033D01*
X95575Y582075D01*
X95242Y582283D01*
X95033Y582533D01*
X94992Y582783D01*
X95075Y583075D01*
X95367Y583283D01*
X95658Y583366D01*
X96033D01*
G01X95658D02*
X95408Y583491D01*
X95200Y583700D01*
X95117Y583950D01*
X95200Y584200D01*
X95408Y584408D01*
X95783Y584533D01*
X96158Y584491D01*
X96533Y584325D01*
G01X92350Y582033D02*
Y584533D01*
X93892Y582741D01*
X91808D01*
G01X90458Y582325D02*
X90167Y582116D01*
X89833Y582033D01*
X89500Y582116D01*
X89208Y582366D01*
X89000Y582741D01*
X88917Y583116D01*
Y583575D01*
X89000Y583950D01*
X89208Y584283D01*
X89458Y584450D01*
X89750Y584533D01*
X90083Y584450D01*
X90333Y584283D01*
X90500Y584033D01*
X90583Y583700D01*
X90500Y583408D01*
X90292Y583116D01*
X90042Y582950D01*
X89750Y582908D01*
X89417Y582991D01*
X89167Y583200D01*
X88917Y583575D01*
G01X99759Y595643D02*
Y598143D01*
X98718D01*
X98384Y598018D01*
X98176Y597851D01*
X98093Y597518D01*
X98176Y597185D01*
X98426Y596976D01*
X98718Y596851D01*
X99759D01*
G01X98718D02*
X98093Y595643D01*
G01X96743Y596143D02*
X96493Y595851D01*
X96159Y595685D01*
X95784Y595643D01*
X95451Y595685D01*
X95118Y595893D01*
X94909Y596143D01*
X94868Y596393D01*
X94951Y596685D01*
X95243Y596893D01*
X95534Y596976D01*
X95909D01*
G01X95534D02*
X95284Y597101D01*
X95076Y597310D01*
X94993Y597560D01*
X95076Y597810D01*
X95284Y598018D01*
X95659Y598143D01*
X96034Y598101D01*
X96409Y597935D01*
G01X93643Y596018D02*
X93393Y595810D01*
X93101Y595685D01*
X92726Y595643D01*
X92351Y595726D01*
X92059Y595893D01*
X91851Y596185D01*
X91809Y596518D01*
X91893Y596851D01*
X92101Y597060D01*
X92393Y597226D01*
X92684Y597268D01*
X92976Y597226D01*
X93351Y597060D01*
X93226Y598143D01*
X92101D01*
G01X89626D02*
X89959Y598060D01*
X90209Y597851D01*
X90376Y597601D01*
X90501Y597268D01*
X90543Y596893D01*
X90501Y596518D01*
X90376Y596185D01*
X90209Y595935D01*
X89959Y595726D01*
X89626Y595643D01*
X89293Y595726D01*
X89043Y595935D01*
X88876Y596185D01*
X88751Y596518D01*
X88709Y596893D01*
X88751Y597268D01*
X88876Y597601D01*
X89043Y597851D01*
X89293Y598060D01*
X89626Y598143D01*
G01X99883Y588826D02*
Y591326D01*
X98842D01*
X98508Y591201D01*
X98300Y591034D01*
X98217Y590701D01*
X98300Y590368D01*
X98550Y590159D01*
X98842Y590034D01*
X99883D01*
G01X98842D02*
X98217Y588826D01*
G01X96867Y589326D02*
X96617Y589034D01*
X96283Y588868D01*
X95908Y588826D01*
X95575Y588868D01*
X95242Y589076D01*
X95033Y589326D01*
X94992Y589576D01*
X95075Y589868D01*
X95367Y590076D01*
X95658Y590159D01*
X96033D01*
G01X95658D02*
X95408Y590284D01*
X95200Y590493D01*
X95117Y590743D01*
X95200Y590993D01*
X95408Y591201D01*
X95783Y591326D01*
X96158Y591284D01*
X96533Y591118D01*
G01X93767Y589201D02*
X93517Y588993D01*
X93225Y588868D01*
X92850Y588826D01*
X92475Y588909D01*
X92183Y589076D01*
X91975Y589368D01*
X91933Y589701D01*
X92017Y590034D01*
X92225Y590243D01*
X92517Y590409D01*
X92808Y590451D01*
X93100Y590409D01*
X93475Y590243D01*
X93350Y591326D01*
X92225D01*
G01X89750Y588826D02*
Y591326D01*
X90250Y590826D01*
G01Y588826D02*
X89250D01*
G01X99883Y585483D02*
Y587983D01*
X98842D01*
X98508Y587858D01*
X98300Y587691D01*
X98217Y587358D01*
X98300Y587025D01*
X98550Y586816D01*
X98842Y586691D01*
X99883D01*
G01X98842D02*
X98217Y585483D01*
G01X96867Y585983D02*
X96617Y585691D01*
X96283Y585525D01*
X95908Y585483D01*
X95575Y585525D01*
X95242Y585733D01*
X95033Y585983D01*
X94992Y586233D01*
X95075Y586525D01*
X95367Y586733D01*
X95658Y586816D01*
X96033D01*
G01X95658D02*
X95408Y586941D01*
X95200Y587150D01*
X95117Y587400D01*
X95200Y587650D01*
X95408Y587858D01*
X95783Y587983D01*
X96158Y587941D01*
X96533Y587775D01*
G01X93767Y585858D02*
X93517Y585650D01*
X93225Y585525D01*
X92850Y585483D01*
X92475Y585566D01*
X92183Y585733D01*
X91975Y586025D01*
X91933Y586358D01*
X92017Y586691D01*
X92225Y586900D01*
X92517Y587066D01*
X92808Y587108D01*
X93100Y587066D01*
X93475Y586900D01*
X93350Y587983D01*
X92225D01*
G01X90667Y585858D02*
X90417Y585650D01*
X90125Y585525D01*
X89750Y585483D01*
X89375Y585566D01*
X89083Y585733D01*
X88875Y586025D01*
X88833Y586358D01*
X88917Y586691D01*
X89125Y586900D01*
X89417Y587066D01*
X89708Y587108D01*
X90000Y587066D01*
X90375Y586900D01*
X90250Y587983D01*
X89125D01*
G01X99936Y599800D02*
Y602300D01*
X98895D01*
X98561Y602175D01*
X98353Y602008D01*
X98270Y601675D01*
X98353Y601342D01*
X98603Y601133D01*
X98895Y601008D01*
X99936D01*
G01X98895D02*
X98270Y599800D01*
G01X96920Y600300D02*
X96670Y600008D01*
X96336Y599842D01*
X95961Y599800D01*
X95628Y599842D01*
X95295Y600050D01*
X95086Y600300D01*
X95045Y600550D01*
X95128Y600842D01*
X95420Y601050D01*
X95711Y601133D01*
X96086D01*
G01X95711D02*
X95461Y601258D01*
X95253Y601467D01*
X95170Y601717D01*
X95253Y601967D01*
X95461Y602175D01*
X95836Y602300D01*
X96211Y602258D01*
X96586Y602092D01*
G01X93695Y600842D02*
X93403Y601133D01*
X93153Y601300D01*
X92820Y601383D01*
X92528Y601300D01*
X92320Y601133D01*
X92153Y600883D01*
X92111Y600592D01*
X92153Y600342D01*
X92320Y600092D01*
X92570Y599883D01*
X92861Y599800D01*
X93195Y599883D01*
X93486Y600133D01*
X93653Y600508D01*
X93695Y600925D01*
X93611Y601467D01*
X93486Y601758D01*
X93278Y602050D01*
X92986Y602258D01*
X92695Y602300D01*
X92403Y602217D01*
X92195Y602008D01*
G01X90595Y601883D02*
X90345Y602133D01*
X90053Y602258D01*
X89720Y602300D01*
X89303Y602217D01*
X89011Y602008D01*
X88928Y601758D01*
X88970Y601508D01*
X89136Y601300D01*
X89970Y600883D01*
X90345Y600592D01*
X90595Y600175D01*
X90678Y599800D01*
X88928D01*
G01X99083Y607200D02*
Y609700D01*
X98042D01*
X97708Y609575D01*
X97500Y609408D01*
X97417Y609075D01*
X97500Y608742D01*
X97750Y608533D01*
X98042Y608408D01*
X99083D01*
G01X98042D02*
X97417Y607200D01*
G01X96067Y607700D02*
X95817Y607408D01*
X95483Y607242D01*
X95108Y607200D01*
X94775Y607242D01*
X94442Y607450D01*
X94233Y607700D01*
X94192Y607950D01*
X94275Y608242D01*
X94567Y608450D01*
X94858Y608533D01*
X95233D01*
G01X94858D02*
X94608Y608658D01*
X94400Y608867D01*
X94317Y609117D01*
X94400Y609367D01*
X94608Y609575D01*
X94983Y609700D01*
X95358Y609658D01*
X95733Y609492D01*
G01X92050Y607200D02*
Y609700D01*
X92550Y609200D01*
G01Y607200D02*
X91550D01*
G01X89033D02*
X88950Y607742D01*
X88825Y608200D01*
X88658Y608617D01*
X88450Y609075D01*
X88117Y609700D01*
X89783D01*
G01X99803Y603470D02*
Y605970D01*
X98762D01*
X98428Y605845D01*
X98220Y605678D01*
X98137Y605345D01*
X98220Y605012D01*
X98470Y604803D01*
X98762Y604678D01*
X99803D01*
G01X98762D02*
X98137Y603470D01*
G01X96787Y603970D02*
X96537Y603678D01*
X96203Y603512D01*
X95828Y603470D01*
X95495Y603512D01*
X95162Y603720D01*
X94953Y603970D01*
X94912Y604220D01*
X94995Y604512D01*
X95287Y604720D01*
X95578Y604803D01*
X95953D01*
G01X95578D02*
X95328Y604928D01*
X95120Y605137D01*
X95037Y605387D01*
X95120Y605637D01*
X95328Y605845D01*
X95703Y605970D01*
X96078Y605928D01*
X96453Y605762D01*
G01X92853Y603470D02*
X92770Y604012D01*
X92645Y604470D01*
X92478Y604887D01*
X92270Y605345D01*
X91937Y605970D01*
X93603D01*
G01X89670D02*
X90003Y605887D01*
X90253Y605678D01*
X90420Y605428D01*
X90545Y605095D01*
X90587Y604720D01*
X90545Y604345D01*
X90420Y604012D01*
X90253Y603762D01*
X90003Y603553D01*
X89670Y603470D01*
X89337Y603553D01*
X89087Y603762D01*
X88920Y604012D01*
X88795Y604345D01*
X88753Y604720D01*
X88795Y605095D01*
X88920Y605428D01*
X89087Y605678D01*
X89337Y605887D01*
X89670Y605970D01*
G01X99883Y592171D02*
Y594671D01*
X98842D01*
X98508Y594546D01*
X98300Y594379D01*
X98217Y594046D01*
X98300Y593713D01*
X98550Y593504D01*
X98842Y593379D01*
X99883D01*
G01X98842D02*
X98217Y592171D01*
G01X96867Y592671D02*
X96617Y592379D01*
X96283Y592213D01*
X95908Y592171D01*
X95575Y592213D01*
X95242Y592421D01*
X95033Y592671D01*
X94992Y592921D01*
X95075Y593213D01*
X95367Y593421D01*
X95658Y593504D01*
X96033D01*
G01X95658D02*
X95408Y593629D01*
X95200Y593838D01*
X95117Y594088D01*
X95200Y594338D01*
X95408Y594546D01*
X95783Y594671D01*
X96158Y594629D01*
X96533Y594463D01*
G01X92350Y592171D02*
Y594671D01*
X93892Y592879D01*
X91808D01*
G01X89750Y592171D02*
Y594671D01*
X90250Y594171D01*
G01Y592171D02*
X89250D01*
G01X74077Y714061D02*
X74202Y713811D01*
X74285Y713519D01*
Y713186D01*
X74160Y712811D01*
X73952Y712519D01*
X73702Y712311D01*
X73285Y712144D01*
X72910Y712102D01*
X72535Y712186D01*
X72285Y712311D01*
X72035Y712561D01*
X71868Y712852D01*
X71785Y713144D01*
Y713436D01*
X71868Y713727D01*
X71993Y713977D01*
X72160Y714186D01*
G01X72285Y715327D02*
X71993Y715577D01*
X71827Y715911D01*
X71785Y716286D01*
X71827Y716619D01*
X72035Y716952D01*
X72285Y717161D01*
X72535Y717202D01*
X72827Y717119D01*
X73035Y716827D01*
X73118Y716536D01*
Y716161D01*
G01Y716536D02*
X73243Y716786D01*
X73452Y716994D01*
X73702Y717077D01*
X73952Y716994D01*
X74160Y716786D01*
X74285Y716411D01*
X74243Y716036D01*
X74077Y715661D01*
G01X71785Y719261D02*
X72327Y719344D01*
X72785Y719469D01*
X73202Y719636D01*
X73660Y719844D01*
X74285Y720177D01*
Y718511D01*
G01X73868Y721652D02*
X74118Y721902D01*
X74243Y722194D01*
X74285Y722527D01*
X74202Y722944D01*
X73993Y723236D01*
X73743Y723319D01*
X73493Y723277D01*
X73285Y723111D01*
X72868Y722277D01*
X72577Y721902D01*
X72160Y721652D01*
X71785Y721569D01*
Y723319D01*
G01X89933Y716961D02*
Y719461D01*
X88892D01*
X88558Y719336D01*
X88350Y719169D01*
X88267Y718836D01*
X88350Y718503D01*
X88600Y718294D01*
X88892Y718169D01*
X89933D01*
G01X88892D02*
X88267Y716961D01*
G01X86792Y719044D02*
X86542Y719294D01*
X86250Y719419D01*
X85917Y719461D01*
X85500Y719378D01*
X85208Y719169D01*
X85125Y718919D01*
X85167Y718669D01*
X85333Y718461D01*
X86167Y718044D01*
X86542Y717753D01*
X86792Y717336D01*
X86875Y716961D01*
X85125D01*
G01X82900D02*
Y719461D01*
X83400Y718961D01*
G01Y716961D02*
X82400D01*
G01X80592Y719044D02*
X80342Y719294D01*
X80050Y719419D01*
X79717Y719461D01*
X79300Y719378D01*
X79008Y719169D01*
X78925Y718919D01*
X78967Y718669D01*
X79133Y718461D01*
X79967Y718044D01*
X80342Y717753D01*
X80592Y717336D01*
X80675Y716961D01*
X78925D01*
G01X77492Y719044D02*
X77242Y719294D01*
X76950Y719419D01*
X76617Y719461D01*
X76200Y719378D01*
X75908Y719169D01*
X75825Y718919D01*
X75867Y718669D01*
X76033Y718461D01*
X76867Y718044D01*
X77242Y717753D01*
X77492Y717336D01*
X77575Y716961D01*
X75825D01*
G01X82100Y731300D02*
Y727300D01*
X74700D01*
G01X89933Y720961D02*
Y723461D01*
X88892D01*
X88558Y723336D01*
X88350Y723169D01*
X88267Y722836D01*
X88350Y722503D01*
X88600Y722294D01*
X88892Y722169D01*
X89933D01*
G01X88892D02*
X88267Y720961D01*
G01X86792Y723044D02*
X86542Y723294D01*
X86250Y723419D01*
X85917Y723461D01*
X85500Y723378D01*
X85208Y723169D01*
X85125Y722919D01*
X85167Y722669D01*
X85333Y722461D01*
X86167Y722044D01*
X86542Y721753D01*
X86792Y721336D01*
X86875Y720961D01*
X85125D01*
G01X82900D02*
Y723461D01*
X83400Y722961D01*
G01Y720961D02*
X82400D01*
G01X79800D02*
Y723461D01*
X80300Y722961D01*
G01Y720961D02*
X79300D01*
G01X77408Y721253D02*
X77117Y721044D01*
X76783Y720961D01*
X76450Y721044D01*
X76158Y721294D01*
X75950Y721669D01*
X75867Y722044D01*
Y722503D01*
X75950Y722878D01*
X76158Y723211D01*
X76408Y723378D01*
X76700Y723461D01*
X77033Y723378D01*
X77283Y723211D01*
X77450Y722961D01*
X77533Y722628D01*
X77450Y722336D01*
X77242Y722044D01*
X76992Y721878D01*
X76700Y721836D01*
X76367Y721919D01*
X76117Y722128D01*
X75867Y722503D01*
G01X82100Y735300D02*
Y731300D01*
X74700D01*
G01X115283Y270300D02*
Y272800D01*
X114242D01*
X113908Y272675D01*
X113700Y272508D01*
X113617Y272175D01*
X113700Y271842D01*
X113950Y271633D01*
X114242Y271508D01*
X115283D01*
G01X114242D02*
X113617Y270300D01*
G01X110850D02*
Y272800D01*
X112392Y271008D01*
X110308D01*
G01X109167Y270675D02*
X108917Y270467D01*
X108625Y270342D01*
X108250Y270300D01*
X107875Y270383D01*
X107583Y270550D01*
X107375Y270842D01*
X107333Y271175D01*
X107417Y271508D01*
X107625Y271717D01*
X107917Y271883D01*
X108208Y271925D01*
X108500Y271883D01*
X108875Y271717D01*
X108750Y272800D01*
X107625D01*
G01X105858Y270592D02*
X105567Y270383D01*
X105233Y270300D01*
X104900Y270383D01*
X104608Y270633D01*
X104400Y271008D01*
X104317Y271383D01*
Y271842D01*
X104400Y272217D01*
X104608Y272550D01*
X104858Y272717D01*
X105150Y272800D01*
X105483Y272717D01*
X105733Y272550D01*
X105900Y272300D01*
X105983Y271967D01*
X105900Y271675D01*
X105692Y271383D01*
X105442Y271217D01*
X105150Y271175D01*
X104817Y271258D01*
X104567Y271467D01*
X104317Y271842D01*
G01X120300Y293817D02*
X122800D01*
Y294817D01*
X122675Y295150D01*
X122383Y295400D01*
X122050Y295483D01*
X121717Y295400D01*
X121467Y295192D01*
X121342Y294817D01*
Y293817D01*
G01X120300Y296917D02*
X122800D01*
Y297958D01*
X122675Y298292D01*
X122508Y298500D01*
X122175Y298583D01*
X121842Y298500D01*
X121633Y298250D01*
X121508Y297958D01*
Y296917D01*
G01Y297958D02*
X120300Y298583D01*
G01X120592Y300142D02*
X120383Y300433D01*
X120300Y300767D01*
X120383Y301100D01*
X120633Y301392D01*
X121008Y301600D01*
X121383Y301683D01*
X121842D01*
X122217Y301600D01*
X122550Y301392D01*
X122717Y301142D01*
X122800Y300850D01*
X122717Y300517D01*
X122550Y300267D01*
X122300Y300100D01*
X121967Y300017D01*
X121675Y300100D01*
X121383Y300308D01*
X121217Y300558D01*
X121175Y300850D01*
X121258Y301183D01*
X121467Y301433D01*
X121842Y301683D01*
G01X122800Y303950D02*
X122717Y303617D01*
X122508Y303367D01*
X122258Y303200D01*
X121925Y303075D01*
X121550Y303033D01*
X121175Y303075D01*
X120842Y303200D01*
X120592Y303367D01*
X120383Y303617D01*
X120300Y303950D01*
X120383Y304283D01*
X120592Y304533D01*
X120842Y304700D01*
X121175Y304825D01*
X121550Y304867D01*
X121925Y304825D01*
X122258Y304700D01*
X122508Y304533D01*
X122717Y304283D01*
X122800Y303950D01*
G01Y307050D02*
X122717Y306717D01*
X122508Y306467D01*
X122258Y306300D01*
X121925Y306175D01*
X121550Y306133D01*
X121175Y306175D01*
X120842Y306300D01*
X120592Y306467D01*
X120383Y306717D01*
X120300Y307050D01*
X120383Y307383D01*
X120592Y307633D01*
X120842Y307800D01*
X121175Y307925D01*
X121550Y307967D01*
X121925Y307925D01*
X122258Y307800D01*
X122508Y307633D01*
X122717Y307383D01*
X122800Y307050D01*
G01X120300Y310150D02*
X120342Y310442D01*
X120467Y310775D01*
X120675Y310983D01*
X120967Y311067D01*
X121258Y310983D01*
X121508Y310733D01*
X121633Y310358D01*
Y309942D01*
X121717Y309692D01*
X121925Y309483D01*
X122217Y309400D01*
X122508Y309525D01*
X122717Y309817D01*
X122800Y310150D01*
X122717Y310483D01*
X122508Y310775D01*
X122217Y310900D01*
X121925Y310817D01*
X121717Y310608D01*
X121633Y310358D01*
Y309942D01*
X121508Y309567D01*
X121258Y309317D01*
X120967Y309233D01*
X120675Y309317D01*
X120467Y309525D01*
X120342Y309858D01*
X120300Y310150D01*
G01X103500Y293200D02*
X107500D01*
Y285800D01*
G01X124800Y293617D02*
X127300D01*
Y294617D01*
X127175Y294950D01*
X126883Y295200D01*
X126550Y295283D01*
X126217Y295200D01*
X125967Y294992D01*
X125842Y294617D01*
Y293617D01*
G01X124800Y296717D02*
X127300D01*
Y297758D01*
X127175Y298092D01*
X127008Y298300D01*
X126675Y298383D01*
X126342Y298300D01*
X126133Y298050D01*
X126008Y297758D01*
Y296717D01*
G01Y297758D02*
X124800Y298383D01*
G01X125842Y299858D02*
X126133Y300150D01*
X126300Y300400D01*
X126383Y300733D01*
X126300Y301025D01*
X126133Y301233D01*
X125883Y301400D01*
X125592Y301442D01*
X125342Y301400D01*
X125092Y301233D01*
X124883Y300983D01*
X124800Y300692D01*
X124883Y300358D01*
X125133Y300067D01*
X125508Y299900D01*
X125925Y299858D01*
X126467Y299942D01*
X126758Y300067D01*
X127050Y300275D01*
X127258Y300567D01*
X127300Y300858D01*
X127217Y301150D01*
X127008Y301358D01*
G01X125842Y302958D02*
X126133Y303250D01*
X126300Y303500D01*
X126383Y303833D01*
X126300Y304125D01*
X126133Y304333D01*
X125883Y304500D01*
X125592Y304542D01*
X125342Y304500D01*
X125092Y304333D01*
X124883Y304083D01*
X124800Y303792D01*
X124883Y303458D01*
X125133Y303167D01*
X125508Y303000D01*
X125925Y302958D01*
X126467Y303042D01*
X126758Y303167D01*
X127050Y303375D01*
X127258Y303667D01*
X127300Y303958D01*
X127217Y304250D01*
X127008Y304458D01*
G01X112000Y285800D02*
X108000D01*
Y293200D01*
G01X134183Y286500D02*
Y289000D01*
X133183D01*
X132850Y288875D01*
X132600Y288583D01*
X132517Y288250D01*
X132600Y287917D01*
X132808Y287667D01*
X133183Y287542D01*
X134183D01*
G01X131083Y286500D02*
Y289000D01*
X130042D01*
X129708Y288875D01*
X129500Y288708D01*
X129417Y288375D01*
X129500Y288042D01*
X129750Y287833D01*
X130042Y287708D01*
X131083D01*
G01X130042D02*
X129417Y286500D01*
G01X127942Y287542D02*
X127650Y287833D01*
X127400Y288000D01*
X127067Y288083D01*
X126775Y288000D01*
X126567Y287833D01*
X126400Y287583D01*
X126358Y287292D01*
X126400Y287042D01*
X126567Y286792D01*
X126817Y286583D01*
X127108Y286500D01*
X127442Y286583D01*
X127733Y286833D01*
X127900Y287208D01*
X127942Y287625D01*
X127858Y288167D01*
X127733Y288458D01*
X127525Y288750D01*
X127233Y288958D01*
X126942Y289000D01*
X126650Y288917D01*
X126442Y288708D01*
G01X123550Y286500D02*
Y289000D01*
X125092Y287208D01*
X123008D01*
G01X119800Y290100D02*
Y286100D01*
X112400D01*
G01X127392Y417855D02*
Y420355D01*
X126351D01*
X126017Y420230D01*
X125809Y420063D01*
X125726Y419730D01*
X125809Y419397D01*
X126059Y419188D01*
X126351Y419063D01*
X127392D01*
G01X126351D02*
X125726Y417855D01*
G01X124251Y419938D02*
X124001Y420188D01*
X123709Y420313D01*
X123376Y420355D01*
X122959Y420272D01*
X122667Y420063D01*
X122584Y419813D01*
X122626Y419563D01*
X122792Y419355D01*
X123626Y418938D01*
X124001Y418647D01*
X124251Y418230D01*
X124334Y417855D01*
X122584D01*
G01X120359D02*
X120067Y417897D01*
X119734Y418022D01*
X119526Y418230D01*
X119442Y418522D01*
X119526Y418813D01*
X119776Y419063D01*
X120151Y419188D01*
X120567D01*
X120817Y419272D01*
X121026Y419480D01*
X121109Y419772D01*
X120984Y420063D01*
X120692Y420272D01*
X120359Y420355D01*
X120026Y420272D01*
X119734Y420063D01*
X119609Y419772D01*
X119692Y419480D01*
X119901Y419272D01*
X120151Y419188D01*
X120567D01*
X120942Y419063D01*
X121192Y418813D01*
X121276Y418522D01*
X121192Y418230D01*
X120984Y418022D01*
X120651Y417897D01*
X120359Y417855D01*
G01X117259D02*
X116967Y417897D01*
X116634Y418022D01*
X116426Y418230D01*
X116342Y418522D01*
X116426Y418813D01*
X116676Y419063D01*
X117051Y419188D01*
X117467D01*
X117717Y419272D01*
X117926Y419480D01*
X118009Y419772D01*
X117884Y420063D01*
X117592Y420272D01*
X117259Y420355D01*
X116926Y420272D01*
X116634Y420063D01*
X116509Y419772D01*
X116592Y419480D01*
X116801Y419272D01*
X117051Y419188D01*
X117467D01*
X117842Y419063D01*
X118092Y418813D01*
X118176Y418522D01*
X118092Y418230D01*
X117884Y418022D01*
X117551Y417897D01*
X117259Y417855D01*
G01X129709Y424337D02*
Y428337D01*
X137109D01*
G01X101667Y442020D02*
X104167D01*
Y443061D01*
X104042Y443395D01*
X103875Y443603D01*
X103542Y443686D01*
X103209Y443603D01*
X103000Y443353D01*
X102875Y443061D01*
Y442020D01*
G01Y443061D02*
X101667Y443686D01*
G01X103750Y445161D02*
X104000Y445411D01*
X104125Y445703D01*
X104167Y446036D01*
X104084Y446453D01*
X103875Y446745D01*
X103625Y446828D01*
X103375Y446786D01*
X103167Y446620D01*
X102750Y445786D01*
X102459Y445411D01*
X102042Y445161D01*
X101667Y445078D01*
Y446828D01*
G01X102042Y448136D02*
X101834Y448386D01*
X101709Y448678D01*
X101667Y449053D01*
X101750Y449428D01*
X101917Y449720D01*
X102209Y449928D01*
X102542Y449970D01*
X102875Y449886D01*
X103084Y449678D01*
X103250Y449386D01*
X103292Y449095D01*
X103250Y448803D01*
X103084Y448428D01*
X104167Y448553D01*
Y449678D01*
G01X101959Y451445D02*
X101750Y451736D01*
X101667Y452070D01*
X101750Y452403D01*
X102000Y452695D01*
X102375Y452903D01*
X102750Y452986D01*
X103209D01*
X103584Y452903D01*
X103917Y452695D01*
X104084Y452445D01*
X104167Y452153D01*
X104084Y451820D01*
X103917Y451570D01*
X103667Y451403D01*
X103334Y451320D01*
X103042Y451403D01*
X102750Y451611D01*
X102584Y451861D01*
X102542Y452153D01*
X102625Y452486D01*
X102834Y452736D01*
X103209Y452986D01*
G01X127391Y421883D02*
Y424383D01*
X126350D01*
X126016Y424258D01*
X125808Y424091D01*
X125725Y423758D01*
X125808Y423425D01*
X126058Y423216D01*
X126350Y423091D01*
X127391D01*
G01X126350D02*
X125725Y421883D01*
G01X124250Y423966D02*
X124000Y424216D01*
X123708Y424341D01*
X123375Y424383D01*
X122958Y424300D01*
X122666Y424091D01*
X122583Y423841D01*
X122625Y423591D01*
X122791Y423383D01*
X123625Y422966D01*
X124000Y422675D01*
X124250Y422258D01*
X124333Y421883D01*
X122583D01*
G01X121066Y422175D02*
X120775Y421966D01*
X120441Y421883D01*
X120108Y421966D01*
X119816Y422216D01*
X119608Y422591D01*
X119525Y422966D01*
Y423425D01*
X119608Y423800D01*
X119816Y424133D01*
X120066Y424300D01*
X120358Y424383D01*
X120691Y424300D01*
X120941Y424133D01*
X121108Y423883D01*
X121191Y423550D01*
X121108Y423258D01*
X120900Y422966D01*
X120650Y422800D01*
X120358Y422758D01*
X120025Y422841D01*
X119775Y423050D01*
X119525Y423425D01*
G01X117258Y421883D02*
Y424383D01*
X117758Y423883D01*
G01Y421883D02*
X116758D01*
G01X129708Y428365D02*
Y432365D01*
X137108D01*
G01X129826Y467830D02*
Y465330D01*
G01X130784Y467830D02*
X128868D01*
G01X127559Y465330D02*
Y467830D01*
X126559D01*
X126226Y467705D01*
X125976Y467413D01*
X125893Y467080D01*
X125976Y466747D01*
X126184Y466497D01*
X126559Y466372D01*
X127559D01*
G01X124418Y467413D02*
X124168Y467663D01*
X123876Y467788D01*
X123543Y467830D01*
X123126Y467747D01*
X122834Y467538D01*
X122751Y467288D01*
X122793Y467038D01*
X122959Y466830D01*
X123793Y466413D01*
X124168Y466122D01*
X124418Y465705D01*
X124501Y465330D01*
X122751D01*
G01X121318Y467413D02*
X121068Y467663D01*
X120776Y467788D01*
X120443Y467830D01*
X120026Y467747D01*
X119734Y467538D01*
X119651Y467288D01*
X119693Y467038D01*
X119859Y466830D01*
X120693Y466413D01*
X121068Y466122D01*
X121318Y465705D01*
X121401Y465330D01*
X119651D01*
G01X117426Y467830D02*
X117759Y467747D01*
X118009Y467538D01*
X118176Y467288D01*
X118301Y466955D01*
X118343Y466580D01*
X118301Y466205D01*
X118176Y465872D01*
X118009Y465622D01*
X117759Y465413D01*
X117426Y465330D01*
X117093Y465413D01*
X116843Y465622D01*
X116676Y465872D01*
X116551Y466205D01*
X116509Y466580D01*
X116551Y466955D01*
X116676Y467288D01*
X116843Y467538D01*
X117093Y467747D01*
X117426Y467830D01*
G01X130093Y464331D02*
Y461831D01*
G01X131051Y464331D02*
X129135D01*
G01X127826Y461831D02*
Y464331D01*
X126826D01*
X126493Y464206D01*
X126243Y463914D01*
X126160Y463581D01*
X126243Y463248D01*
X126451Y462998D01*
X126826Y462873D01*
X127826D01*
G01X124685Y463914D02*
X124435Y464164D01*
X124143Y464289D01*
X123810Y464331D01*
X123393Y464248D01*
X123101Y464039D01*
X123018Y463789D01*
X123060Y463539D01*
X123226Y463331D01*
X124060Y462914D01*
X124435Y462623D01*
X124685Y462206D01*
X124768Y461831D01*
X123018D01*
G01X121585Y463914D02*
X121335Y464164D01*
X121043Y464289D01*
X120710Y464331D01*
X120293Y464248D01*
X120001Y464039D01*
X119918Y463789D01*
X119960Y463539D01*
X120126Y463331D01*
X120960Y462914D01*
X121335Y462623D01*
X121585Y462206D01*
X121668Y461831D01*
X119918D01*
G01X118485Y462873D02*
X118193Y463164D01*
X117943Y463331D01*
X117610Y463414D01*
X117318Y463331D01*
X117110Y463164D01*
X116943Y462914D01*
X116901Y462623D01*
X116943Y462373D01*
X117110Y462123D01*
X117360Y461914D01*
X117651Y461831D01*
X117985Y461914D01*
X118276Y462164D01*
X118443Y462539D01*
X118485Y462956D01*
X118401Y463498D01*
X118276Y463789D01*
X118068Y464081D01*
X117776Y464289D01*
X117485Y464331D01*
X117193Y464248D01*
X116985Y464039D01*
G01X119265Y481108D02*
Y478608D01*
G01X120223Y481108D02*
X118307D01*
G01X116998Y478608D02*
Y481108D01*
X115998D01*
X115665Y480983D01*
X115415Y480691D01*
X115332Y480358D01*
X115415Y480025D01*
X115623Y479775D01*
X115998Y479650D01*
X116998D01*
G01X113982Y479108D02*
X113732Y478816D01*
X113398Y478650D01*
X113023Y478608D01*
X112690Y478650D01*
X112357Y478858D01*
X112148Y479108D01*
X112107Y479358D01*
X112190Y479650D01*
X112482Y479858D01*
X112773Y479941D01*
X113148D01*
G01X112773D02*
X112523Y480066D01*
X112315Y480275D01*
X112232Y480525D01*
X112315Y480775D01*
X112523Y480983D01*
X112898Y481108D01*
X113273Y481066D01*
X113648Y480900D01*
G01X109965Y481108D02*
X110298Y481025D01*
X110548Y480816D01*
X110715Y480566D01*
X110840Y480233D01*
X110882Y479858D01*
X110840Y479483D01*
X110715Y479150D01*
X110548Y478900D01*
X110298Y478691D01*
X109965Y478608D01*
X109632Y478691D01*
X109382Y478900D01*
X109215Y479150D01*
X109090Y479483D01*
X109048Y479858D01*
X109090Y480233D01*
X109215Y480566D01*
X109382Y480816D01*
X109632Y481025D01*
X109965Y481108D01*
G01X106948Y478608D02*
X106865Y479150D01*
X106740Y479608D01*
X106573Y480025D01*
X106365Y480483D01*
X106032Y481108D01*
X107698D01*
G01X102667Y469052D02*
X100167D01*
G01X102667Y468094D02*
Y470010D01*
G01X100167Y471319D02*
X102667D01*
Y472319D01*
X102542Y472652D01*
X102250Y472902D01*
X101917Y472985D01*
X101584Y472902D01*
X101334Y472694D01*
X101209Y472319D01*
Y471319D01*
G01X102250Y474460D02*
X102500Y474710D01*
X102625Y475002D01*
X102667Y475335D01*
X102584Y475752D01*
X102375Y476044D01*
X102125Y476127D01*
X101875Y476085D01*
X101667Y475919D01*
X101250Y475085D01*
X100959Y474710D01*
X100542Y474460D01*
X100167Y474377D01*
Y476127D01*
G01Y478269D02*
X100709Y478352D01*
X101167Y478477D01*
X101584Y478644D01*
X102042Y478852D01*
X102667Y479185D01*
Y477519D01*
G01X100667Y480535D02*
X100375Y480785D01*
X100209Y481119D01*
X100167Y481494D01*
X100209Y481827D01*
X100417Y482160D01*
X100667Y482369D01*
X100917Y482410D01*
X101209Y482327D01*
X101417Y482035D01*
X101500Y481744D01*
Y481369D01*
G01Y481744D02*
X101625Y481994D01*
X101834Y482202D01*
X102084Y482285D01*
X102334Y482202D01*
X102542Y481994D01*
X102667Y481619D01*
X102625Y481244D01*
X102459Y480869D01*
G01X125400Y446317D02*
X127900D01*
Y447358D01*
X127775Y447692D01*
X127608Y447900D01*
X127275Y447983D01*
X126942Y447900D01*
X126733Y447650D01*
X126608Y447358D01*
Y446317D01*
G01Y447358D02*
X125400Y447983D01*
G01X127483Y449458D02*
X127733Y449708D01*
X127858Y450000D01*
X127900Y450333D01*
X127817Y450750D01*
X127608Y451042D01*
X127358Y451125D01*
X127108Y451083D01*
X126900Y450917D01*
X126483Y450083D01*
X126192Y449708D01*
X125775Y449458D01*
X125400Y449375D01*
Y451125D01*
G01Y453350D02*
X125442Y453642D01*
X125567Y453975D01*
X125775Y454183D01*
X126067Y454267D01*
X126358Y454183D01*
X126608Y453933D01*
X126733Y453558D01*
Y453142D01*
X126817Y452892D01*
X127025Y452683D01*
X127317Y452600D01*
X127608Y452725D01*
X127817Y453017D01*
X127900Y453350D01*
X127817Y453683D01*
X127608Y453975D01*
X127317Y454100D01*
X127025Y454017D01*
X126817Y453808D01*
X126733Y453558D01*
Y453142D01*
X126608Y452767D01*
X126358Y452517D01*
X126067Y452433D01*
X125775Y452517D01*
X125567Y452725D01*
X125442Y453058D01*
X125400Y453350D01*
G01X125900Y455533D02*
X125608Y455783D01*
X125442Y456117D01*
X125400Y456492D01*
X125442Y456825D01*
X125650Y457158D01*
X125900Y457367D01*
X126150Y457408D01*
X126442Y457325D01*
X126650Y457033D01*
X126733Y456742D01*
Y456367D01*
G01Y456742D02*
X126858Y456992D01*
X127067Y457200D01*
X127317Y457283D01*
X127567Y457200D01*
X127775Y456992D01*
X127900Y456617D01*
X127858Y456242D01*
X127692Y455867D01*
G01X120600Y446017D02*
X123100D01*
Y447058D01*
X122975Y447392D01*
X122808Y447600D01*
X122475Y447683D01*
X122142Y447600D01*
X121933Y447350D01*
X121808Y447058D01*
Y446017D01*
G01Y447058D02*
X120600Y447683D01*
G01X122683Y449158D02*
X122933Y449408D01*
X123058Y449700D01*
X123100Y450033D01*
X123017Y450450D01*
X122808Y450742D01*
X122558Y450825D01*
X122308Y450783D01*
X122100Y450617D01*
X121683Y449783D01*
X121392Y449408D01*
X120975Y449158D01*
X120600Y449075D01*
Y450825D01*
G01Y453050D02*
X120642Y453342D01*
X120767Y453675D01*
X120975Y453883D01*
X121267Y453967D01*
X121558Y453883D01*
X121808Y453633D01*
X121933Y453258D01*
Y452842D01*
X122017Y452592D01*
X122225Y452383D01*
X122517Y452300D01*
X122808Y452425D01*
X123017Y452717D01*
X123100Y453050D01*
X123017Y453383D01*
X122808Y453675D01*
X122517Y453800D01*
X122225Y453717D01*
X122017Y453508D01*
X121933Y453258D01*
Y452842D01*
X121808Y452467D01*
X121558Y452217D01*
X121267Y452133D01*
X120975Y452217D01*
X120767Y452425D01*
X120642Y452758D01*
X120600Y453050D01*
G01X120975Y455233D02*
X120767Y455483D01*
X120642Y455775D01*
X120600Y456150D01*
X120683Y456525D01*
X120850Y456817D01*
X121142Y457025D01*
X121475Y457067D01*
X121808Y456983D01*
X122017Y456775D01*
X122183Y456483D01*
X122225Y456192D01*
X122183Y455900D01*
X122017Y455525D01*
X123100Y455650D01*
Y456775D01*
G01X116400Y446017D02*
X118900D01*
Y447058D01*
X118775Y447392D01*
X118608Y447600D01*
X118275Y447683D01*
X117942Y447600D01*
X117733Y447350D01*
X117608Y447058D01*
Y446017D01*
G01Y447058D02*
X116400Y447683D01*
G01X116775Y449033D02*
X116567Y449283D01*
X116442Y449575D01*
X116400Y449950D01*
X116483Y450325D01*
X116650Y450617D01*
X116942Y450825D01*
X117275Y450867D01*
X117608Y450783D01*
X117817Y450575D01*
X117983Y450283D01*
X118025Y449992D01*
X117983Y449700D01*
X117817Y449325D01*
X118900Y449450D01*
Y450575D01*
G01Y453050D02*
X118817Y452717D01*
X118608Y452467D01*
X118358Y452300D01*
X118025Y452175D01*
X117650Y452133D01*
X117275Y452175D01*
X116942Y452300D01*
X116692Y452467D01*
X116483Y452717D01*
X116400Y453050D01*
X116483Y453383D01*
X116692Y453633D01*
X116942Y453800D01*
X117275Y453925D01*
X117650Y453967D01*
X118025Y453925D01*
X118358Y453800D01*
X118608Y453633D01*
X118817Y453383D01*
X118900Y453050D01*
G01X117442Y455358D02*
X117733Y455650D01*
X117900Y455900D01*
X117983Y456233D01*
X117900Y456525D01*
X117733Y456733D01*
X117483Y456900D01*
X117192Y456942D01*
X116942Y456900D01*
X116692Y456733D01*
X116483Y456483D01*
X116400Y456192D01*
X116483Y455858D01*
X116733Y455567D01*
X117108Y455400D01*
X117525Y455358D01*
X118067Y455442D01*
X118358Y455567D01*
X118650Y455775D01*
X118858Y456067D01*
X118900Y456358D01*
X118817Y456650D01*
X118608Y456858D01*
G01X101500Y463200D02*
X105500D01*
Y455800D01*
G01X107544Y462970D02*
X110044D01*
Y464011D01*
X109919Y464345D01*
X109752Y464553D01*
X109419Y464636D01*
X109086Y464553D01*
X108877Y464303D01*
X108752Y464011D01*
Y462970D01*
G01Y464011D02*
X107544Y464636D01*
G01Y466820D02*
X108086Y466903D01*
X108544Y467028D01*
X108961Y467195D01*
X109419Y467403D01*
X110044Y467736D01*
Y466070D01*
G01Y470003D02*
X109961Y469670D01*
X109752Y469420D01*
X109502Y469253D01*
X109169Y469128D01*
X108794Y469086D01*
X108419Y469128D01*
X108086Y469253D01*
X107836Y469420D01*
X107627Y469670D01*
X107544Y470003D01*
X107627Y470336D01*
X107836Y470586D01*
X108086Y470753D01*
X108419Y470878D01*
X108794Y470920D01*
X109169Y470878D01*
X109502Y470753D01*
X109752Y470586D01*
X109961Y470336D01*
X110044Y470003D01*
G01X107919Y472186D02*
X107711Y472436D01*
X107586Y472728D01*
X107544Y473103D01*
X107627Y473478D01*
X107794Y473770D01*
X108086Y473978D01*
X108419Y474020D01*
X108752Y473936D01*
X108961Y473728D01*
X109127Y473436D01*
X109169Y473145D01*
X109127Y472853D01*
X108961Y472478D01*
X110044Y472603D01*
Y473728D01*
G01X111000Y464200D02*
X115000D01*
Y456800D01*
G01X123983Y469800D02*
Y472300D01*
X122942D01*
X122608Y472175D01*
X122400Y472008D01*
X122317Y471675D01*
X122400Y471342D01*
X122650Y471133D01*
X122942Y471008D01*
X123983D01*
G01X122942D02*
X122317Y469800D01*
G01X120967Y470175D02*
X120717Y469967D01*
X120425Y469842D01*
X120050Y469800D01*
X119675Y469883D01*
X119383Y470050D01*
X119175Y470342D01*
X119133Y470675D01*
X119217Y471008D01*
X119425Y471217D01*
X119717Y471383D01*
X120008Y471425D01*
X120300Y471383D01*
X120675Y471217D01*
X120550Y472300D01*
X119425D01*
G01X117742Y470842D02*
X117450Y471133D01*
X117200Y471300D01*
X116867Y471383D01*
X116575Y471300D01*
X116367Y471133D01*
X116200Y470883D01*
X116158Y470592D01*
X116200Y470342D01*
X116367Y470092D01*
X116617Y469883D01*
X116908Y469800D01*
X117242Y469883D01*
X117533Y470133D01*
X117700Y470508D01*
X117742Y470925D01*
X117658Y471467D01*
X117533Y471758D01*
X117325Y472050D01*
X117033Y472258D01*
X116742Y472300D01*
X116450Y472217D01*
X116242Y472008D01*
G01X113350Y469800D02*
Y472300D01*
X114892Y470508D01*
X112808D01*
G01X125192Y468680D02*
Y472680D01*
X132592D01*
G01X122921Y507399D02*
Y504899D01*
G01X123879Y507399D02*
X121963D01*
G01X120654Y504899D02*
Y507399D01*
X119654D01*
X119321Y507274D01*
X119071Y506982D01*
X118988Y506649D01*
X119071Y506316D01*
X119279Y506066D01*
X119654Y505941D01*
X120654D01*
G01X117513Y506982D02*
X117263Y507232D01*
X116971Y507357D01*
X116638Y507399D01*
X116221Y507316D01*
X115929Y507107D01*
X115846Y506857D01*
X115888Y506607D01*
X116054Y506399D01*
X116888Y505982D01*
X117263Y505691D01*
X117513Y505274D01*
X117596Y504899D01*
X115846D01*
G01X113704D02*
X113621Y505441D01*
X113496Y505899D01*
X113329Y506316D01*
X113121Y506774D01*
X112788Y507399D01*
X114454D01*
G01X110521D02*
X110854Y507316D01*
X111104Y507107D01*
X111271Y506857D01*
X111396Y506524D01*
X111438Y506149D01*
X111396Y505774D01*
X111271Y505441D01*
X111104Y505191D01*
X110854Y504982D01*
X110521Y504899D01*
X110188Y504982D01*
X109938Y505191D01*
X109771Y505441D01*
X109646Y505774D01*
X109604Y506149D01*
X109646Y506524D01*
X109771Y506857D01*
X109938Y507107D01*
X110188Y507316D01*
X110521Y507399D01*
G01X133187Y487774D02*
Y485274D01*
G01X134145Y487774D02*
X132229D01*
G01X130920Y485274D02*
Y487774D01*
X129920D01*
X129587Y487649D01*
X129337Y487357D01*
X129254Y487024D01*
X129337Y486691D01*
X129545Y486441D01*
X129920Y486316D01*
X130920D01*
G01X127904Y485774D02*
X127654Y485482D01*
X127320Y485316D01*
X126945Y485274D01*
X126612Y485316D01*
X126279Y485524D01*
X126070Y485774D01*
X126029Y486024D01*
X126112Y486316D01*
X126404Y486524D01*
X126695Y486607D01*
X127070D01*
G01X126695D02*
X126445Y486732D01*
X126237Y486941D01*
X126154Y487191D01*
X126237Y487441D01*
X126445Y487649D01*
X126820Y487774D01*
X127195Y487732D01*
X127570Y487566D01*
G01X123887Y487774D02*
X124220Y487691D01*
X124470Y487482D01*
X124637Y487232D01*
X124762Y486899D01*
X124804Y486524D01*
X124762Y486149D01*
X124637Y485816D01*
X124470Y485566D01*
X124220Y485357D01*
X123887Y485274D01*
X123554Y485357D01*
X123304Y485566D01*
X123137Y485816D01*
X123012Y486149D01*
X122970Y486524D01*
X123012Y486899D01*
X123137Y487232D01*
X123304Y487482D01*
X123554Y487691D01*
X123887Y487774D01*
G01X121579Y486316D02*
X121287Y486607D01*
X121037Y486774D01*
X120704Y486857D01*
X120412Y486774D01*
X120204Y486607D01*
X120037Y486357D01*
X119995Y486066D01*
X120037Y485816D01*
X120204Y485566D01*
X120454Y485357D01*
X120745Y485274D01*
X121079Y485357D01*
X121370Y485607D01*
X121537Y485982D01*
X121579Y486399D01*
X121495Y486941D01*
X121370Y487232D01*
X121162Y487524D01*
X120870Y487732D01*
X120579Y487774D01*
X120287Y487691D01*
X120079Y487482D01*
G01X114800Y499404D02*
Y496904D01*
G01X115758Y499404D02*
X113842D01*
G01X112533Y496904D02*
Y499404D01*
X111533D01*
X111200Y499279D01*
X110950Y498987D01*
X110867Y498654D01*
X110950Y498321D01*
X111158Y498071D01*
X111533Y497946D01*
X112533D01*
G01X109392Y498987D02*
X109142Y499237D01*
X108850Y499362D01*
X108517Y499404D01*
X108100Y499321D01*
X107808Y499112D01*
X107725Y498862D01*
X107767Y498612D01*
X107933Y498404D01*
X108767Y497987D01*
X109142Y497696D01*
X109392Y497279D01*
X109475Y496904D01*
X107725D01*
G01X106292Y498987D02*
X106042Y499237D01*
X105750Y499362D01*
X105417Y499404D01*
X105000Y499321D01*
X104708Y499112D01*
X104625Y498862D01*
X104667Y498612D01*
X104833Y498404D01*
X105667Y497987D01*
X106042Y497696D01*
X106292Y497279D01*
X106375Y496904D01*
X104625D01*
G01X102400D02*
Y499404D01*
X102900Y498904D01*
G01Y496904D02*
X101900D01*
G01X116357Y495101D02*
Y492601D01*
G01X117315Y495101D02*
X115399D01*
G01X114090Y492601D02*
Y495101D01*
X113090D01*
X112757Y494976D01*
X112507Y494684D01*
X112424Y494351D01*
X112507Y494018D01*
X112715Y493768D01*
X113090Y493643D01*
X114090D01*
G01X110949Y494684D02*
X110699Y494934D01*
X110407Y495059D01*
X110074Y495101D01*
X109657Y495018D01*
X109365Y494809D01*
X109282Y494559D01*
X109324Y494309D01*
X109490Y494101D01*
X110324Y493684D01*
X110699Y493393D01*
X110949Y492976D01*
X111032Y492601D01*
X109282D01*
G01X106557D02*
Y495101D01*
X108099Y493309D01*
X106015D01*
G01X104874Y492976D02*
X104624Y492768D01*
X104332Y492643D01*
X103957Y492601D01*
X103582Y492684D01*
X103290Y492851D01*
X103082Y493143D01*
X103040Y493476D01*
X103124Y493809D01*
X103332Y494018D01*
X103624Y494184D01*
X103915Y494226D01*
X104207Y494184D01*
X104582Y494018D01*
X104457Y495101D01*
X103332D01*
G01X124794Y511262D02*
Y508762D01*
G01X125752Y511262D02*
X123836D01*
G01X122527Y508762D02*
Y511262D01*
X121527D01*
X121194Y511137D01*
X120944Y510845D01*
X120861Y510512D01*
X120944Y510179D01*
X121152Y509929D01*
X121527Y509804D01*
X122527D01*
G01X118594Y508762D02*
Y511262D01*
X119094Y510762D01*
G01Y508762D02*
X118094D01*
G01X115494Y511262D02*
X115827Y511179D01*
X116077Y510970D01*
X116244Y510720D01*
X116369Y510387D01*
X116411Y510012D01*
X116369Y509637D01*
X116244Y509304D01*
X116077Y509054D01*
X115827Y508845D01*
X115494Y508762D01*
X115161Y508845D01*
X114911Y509054D01*
X114744Y509304D01*
X114619Y509637D01*
X114577Y510012D01*
X114619Y510387D01*
X114744Y510720D01*
X114911Y510970D01*
X115161Y511179D01*
X115494Y511262D01*
G01X112477Y508762D02*
X112394Y509304D01*
X112269Y509762D01*
X112102Y510179D01*
X111894Y510637D01*
X111561Y511262D01*
X113227D01*
G01X121233Y514921D02*
X121483Y515046D01*
X121775Y515129D01*
X122108D01*
X122483Y515004D01*
X122775Y514796D01*
X122983Y514546D01*
X123150Y514129D01*
X123192Y513754D01*
X123108Y513379D01*
X122983Y513129D01*
X122733Y512879D01*
X122442Y512712D01*
X122150Y512629D01*
X121858D01*
X121567Y512712D01*
X121317Y512837D01*
X121108Y513004D01*
G01X119842Y514712D02*
X119592Y514962D01*
X119300Y515087D01*
X118967Y515129D01*
X118550Y515046D01*
X118258Y514837D01*
X118175Y514587D01*
X118217Y514337D01*
X118383Y514129D01*
X119217Y513712D01*
X119592Y513421D01*
X119842Y513004D01*
X119925Y512629D01*
X118175D01*
G01X115950Y515129D02*
X116283Y515046D01*
X116533Y514837D01*
X116700Y514587D01*
X116825Y514254D01*
X116867Y513879D01*
X116825Y513504D01*
X116700Y513171D01*
X116533Y512921D01*
X116283Y512712D01*
X115950Y512629D01*
X115617Y512712D01*
X115367Y512921D01*
X115200Y513171D01*
X115075Y513504D01*
X115033Y513879D01*
X115075Y514254D01*
X115200Y514587D01*
X115367Y514837D01*
X115617Y515046D01*
X115950Y515129D01*
G01X113558Y512921D02*
X113267Y512712D01*
X112933Y512629D01*
X112600Y512712D01*
X112308Y512962D01*
X112100Y513337D01*
X112017Y513712D01*
Y514171D01*
X112100Y514546D01*
X112308Y514879D01*
X112558Y515046D01*
X112850Y515129D01*
X113183Y515046D01*
X113433Y514879D01*
X113600Y514629D01*
X113683Y514296D01*
X113600Y514004D01*
X113392Y513712D01*
X113142Y513546D01*
X112850Y513504D01*
X112517Y513587D01*
X112267Y513796D01*
X112017Y514171D01*
G01X125233Y524663D02*
X125483Y524788D01*
X125775Y524871D01*
X126108D01*
X126483Y524746D01*
X126775Y524538D01*
X126983Y524288D01*
X127150Y523871D01*
X127192Y523496D01*
X127108Y523121D01*
X126983Y522871D01*
X126733Y522621D01*
X126442Y522454D01*
X126150Y522371D01*
X125858D01*
X125567Y522454D01*
X125317Y522579D01*
X125108Y522746D01*
G01X123842Y524454D02*
X123592Y524704D01*
X123300Y524829D01*
X122967Y524871D01*
X122550Y524788D01*
X122258Y524579D01*
X122175Y524329D01*
X122217Y524079D01*
X122383Y523871D01*
X123217Y523454D01*
X123592Y523163D01*
X123842Y522746D01*
X123925Y522371D01*
X122175D01*
G01X119950D02*
Y524871D01*
X120450Y524371D01*
G01Y522371D02*
X119450D01*
G01X116850Y524871D02*
X117183Y524788D01*
X117433Y524579D01*
X117600Y524329D01*
X117725Y523996D01*
X117767Y523621D01*
X117725Y523246D01*
X117600Y522913D01*
X117433Y522663D01*
X117183Y522454D01*
X116850Y522371D01*
X116517Y522454D01*
X116267Y522663D01*
X116100Y522913D01*
X115975Y523246D01*
X115933Y523621D01*
X115975Y523996D01*
X116100Y524329D01*
X116267Y524579D01*
X116517Y524788D01*
X116850Y524871D01*
G01X125233Y528186D02*
X125483Y528311D01*
X125775Y528394D01*
X126108D01*
X126483Y528269D01*
X126775Y528061D01*
X126983Y527811D01*
X127150Y527394D01*
X127192Y527019D01*
X127108Y526644D01*
X126983Y526394D01*
X126733Y526144D01*
X126442Y525977D01*
X126150Y525894D01*
X125858D01*
X125567Y525977D01*
X125317Y526102D01*
X125108Y526269D01*
G01X123842Y527977D02*
X123592Y528227D01*
X123300Y528352D01*
X122967Y528394D01*
X122550Y528311D01*
X122258Y528102D01*
X122175Y527852D01*
X122217Y527602D01*
X122383Y527394D01*
X123217Y526977D01*
X123592Y526686D01*
X123842Y526269D01*
X123925Y525894D01*
X122175D01*
G01X119950Y528394D02*
X120283Y528311D01*
X120533Y528102D01*
X120700Y527852D01*
X120825Y527519D01*
X120867Y527144D01*
X120825Y526769D01*
X120700Y526436D01*
X120533Y526186D01*
X120283Y525977D01*
X119950Y525894D01*
X119617Y525977D01*
X119367Y526186D01*
X119200Y526436D01*
X119075Y526769D01*
X119033Y527144D01*
X119075Y527519D01*
X119200Y527852D01*
X119367Y528102D01*
X119617Y528311D01*
X119950Y528394D01*
G01X116933Y525894D02*
X116850Y526436D01*
X116725Y526894D01*
X116558Y527311D01*
X116350Y527769D01*
X116017Y528394D01*
X117683D01*
G01X122733Y518730D02*
X122983Y518855D01*
X123275Y518938D01*
X123608D01*
X123983Y518813D01*
X124275Y518605D01*
X124483Y518355D01*
X124650Y517938D01*
X124692Y517563D01*
X124608Y517188D01*
X124483Y516938D01*
X124233Y516688D01*
X123942Y516521D01*
X123650Y516438D01*
X123358D01*
X123067Y516521D01*
X122817Y516646D01*
X122608Y516813D01*
G01X121342Y518521D02*
X121092Y518771D01*
X120800Y518896D01*
X120467Y518938D01*
X120050Y518855D01*
X119758Y518646D01*
X119675Y518396D01*
X119717Y518146D01*
X119883Y517938D01*
X120717Y517521D01*
X121092Y517230D01*
X121342Y516813D01*
X121425Y516438D01*
X119675D01*
G01X117450D02*
Y518938D01*
X117950Y518438D01*
G01Y516438D02*
X116950D01*
G01X115267Y516938D02*
X115017Y516646D01*
X114683Y516480D01*
X114308Y516438D01*
X113975Y516480D01*
X113642Y516688D01*
X113433Y516938D01*
X113392Y517188D01*
X113475Y517480D01*
X113767Y517688D01*
X114058Y517771D01*
X114433D01*
G01X114058D02*
X113808Y517896D01*
X113600Y518105D01*
X113517Y518355D01*
X113600Y518605D01*
X113808Y518813D01*
X114183Y518938D01*
X114558Y518896D01*
X114933Y518730D01*
G01X121918Y637624D02*
X122043Y637374D01*
X122126Y637082D01*
Y636749D01*
X122001Y636374D01*
X121793Y636082D01*
X121543Y635874D01*
X121126Y635707D01*
X120751Y635665D01*
X120376Y635749D01*
X120126Y635874D01*
X119876Y636124D01*
X119709Y636415D01*
X119626Y636707D01*
Y636999D01*
X119709Y637290D01*
X119834Y637540D01*
X120001Y637749D01*
G01X119626Y639807D02*
X122126D01*
X121626Y639307D01*
G01X119626D02*
Y640307D01*
G01X119918Y642199D02*
X119709Y642490D01*
X119626Y642824D01*
X119709Y643157D01*
X119959Y643449D01*
X120334Y643657D01*
X120709Y643740D01*
X121168D01*
X121543Y643657D01*
X121876Y643449D01*
X122043Y643199D01*
X122126Y642907D01*
X122043Y642574D01*
X121876Y642324D01*
X121626Y642157D01*
X121293Y642074D01*
X121001Y642157D01*
X120709Y642365D01*
X120543Y642615D01*
X120501Y642907D01*
X120584Y643240D01*
X120793Y643490D01*
X121168Y643740D01*
G01X119918Y645299D02*
X119709Y645590D01*
X119626Y645924D01*
X119709Y646257D01*
X119959Y646549D01*
X120334Y646757D01*
X120709Y646840D01*
X121168D01*
X121543Y646757D01*
X121876Y646549D01*
X122043Y646299D01*
X122126Y646007D01*
X122043Y645674D01*
X121876Y645424D01*
X121626Y645257D01*
X121293Y645174D01*
X121001Y645257D01*
X120709Y645465D01*
X120543Y645715D01*
X120501Y646007D01*
X120584Y646340D01*
X120793Y646590D01*
X121168Y646840D01*
G01X128418Y637624D02*
X128543Y637374D01*
X128626Y637082D01*
Y636749D01*
X128501Y636374D01*
X128293Y636082D01*
X128043Y635874D01*
X127626Y635707D01*
X127251Y635665D01*
X126876Y635749D01*
X126626Y635874D01*
X126376Y636124D01*
X126209Y636415D01*
X126126Y636707D01*
Y636999D01*
X126209Y637290D01*
X126334Y637540D01*
X126501Y637749D01*
G01X126126Y639807D02*
X128626D01*
X128126Y639307D01*
G01X126126D02*
Y640307D01*
G01X126418Y642199D02*
X126209Y642490D01*
X126126Y642824D01*
X126209Y643157D01*
X126459Y643449D01*
X126834Y643657D01*
X127209Y643740D01*
X127668D01*
X128043Y643657D01*
X128376Y643449D01*
X128543Y643199D01*
X128626Y642907D01*
X128543Y642574D01*
X128376Y642324D01*
X128126Y642157D01*
X127793Y642074D01*
X127501Y642157D01*
X127209Y642365D01*
X127043Y642615D01*
X127001Y642907D01*
X127084Y643240D01*
X127293Y643490D01*
X127668Y643740D01*
G01X126126Y646007D02*
X126168Y646299D01*
X126293Y646632D01*
X126501Y646840D01*
X126793Y646924D01*
X127084Y646840D01*
X127334Y646590D01*
X127459Y646215D01*
Y645799D01*
X127543Y645549D01*
X127751Y645340D01*
X128043Y645257D01*
X128334Y645382D01*
X128543Y645674D01*
X128626Y646007D01*
X128543Y646340D01*
X128334Y646632D01*
X128043Y646757D01*
X127751Y646674D01*
X127543Y646465D01*
X127459Y646215D01*
Y645799D01*
X127334Y645424D01*
X127084Y645174D01*
X126793Y645090D01*
X126501Y645174D01*
X126293Y645382D01*
X126168Y645715D01*
X126126Y646007D01*
G01X115583Y739561D02*
Y742061D01*
X114542D01*
X114208Y741936D01*
X114000Y741769D01*
X113917Y741436D01*
X114000Y741103D01*
X114250Y740894D01*
X114542Y740769D01*
X115583D01*
G01X114542D02*
X113917Y739561D01*
G01X111150D02*
Y742061D01*
X112692Y740269D01*
X110608D01*
G01X108050Y739561D02*
Y742061D01*
X109592Y740269D01*
X107508D01*
G01X105450Y739561D02*
X105158Y739603D01*
X104825Y739728D01*
X104617Y739936D01*
X104533Y740228D01*
X104617Y740519D01*
X104867Y740769D01*
X105242Y740894D01*
X105658D01*
X105908Y740978D01*
X106117Y741186D01*
X106200Y741478D01*
X106075Y741769D01*
X105783Y741978D01*
X105450Y742061D01*
X105117Y741978D01*
X104825Y741769D01*
X104700Y741478D01*
X104783Y741186D01*
X104992Y740978D01*
X105242Y740894D01*
X105658D01*
X106033Y740769D01*
X106283Y740519D01*
X106367Y740228D01*
X106283Y739936D01*
X106075Y739728D01*
X105742Y739603D01*
X105450Y739561D01*
G01X113800Y733900D02*
Y729900D01*
X106400D01*
G01X115583Y735561D02*
Y738061D01*
X114542D01*
X114208Y737936D01*
X114000Y737769D01*
X113917Y737436D01*
X114000Y737103D01*
X114250Y736894D01*
X114542Y736769D01*
X115583D01*
G01X114542D02*
X113917Y735561D01*
G01X111150D02*
Y738061D01*
X112692Y736269D01*
X110608D01*
G01X108050Y735561D02*
Y738061D01*
X109592Y736269D01*
X107508D01*
G01X106367Y736061D02*
X106117Y735769D01*
X105783Y735603D01*
X105408Y735561D01*
X105075Y735603D01*
X104742Y735811D01*
X104533Y736061D01*
X104492Y736311D01*
X104575Y736603D01*
X104867Y736811D01*
X105158Y736894D01*
X105533D01*
G01X105158D02*
X104908Y737019D01*
X104700Y737228D01*
X104617Y737478D01*
X104700Y737728D01*
X104908Y737936D01*
X105283Y738061D01*
X105658Y738019D01*
X106033Y737853D01*
G01X113800Y729900D02*
Y725900D01*
X106400D01*
G01X158400Y428100D02*
X177600D01*
Y388200D01*
X146100D01*
Y394500D01*
X154500D01*
Y428100D01*
X158400D01*
G01X160119Y389150D02*
X162619D01*
Y390191D01*
X162494Y390525D01*
X162327Y390733D01*
X161994Y390816D01*
X161661Y390733D01*
X161452Y390483D01*
X161327Y390191D01*
Y389150D01*
G01Y390191D02*
X160119Y390816D01*
G01Y393583D02*
X162619D01*
X160827Y392041D01*
Y394125D01*
G01X162202Y395391D02*
X162452Y395641D01*
X162577Y395933D01*
X162619Y396266D01*
X162536Y396683D01*
X162327Y396975D01*
X162077Y397058D01*
X161827Y397016D01*
X161619Y396850D01*
X161202Y396016D01*
X160911Y395641D01*
X160494Y395391D01*
X160119Y395308D01*
Y397058D01*
G01X162202Y398491D02*
X162452Y398741D01*
X162577Y399033D01*
X162619Y399366D01*
X162536Y399783D01*
X162327Y400075D01*
X162077Y400158D01*
X161827Y400116D01*
X161619Y399950D01*
X161202Y399116D01*
X160911Y398741D01*
X160494Y398491D01*
X160119Y398408D01*
Y400158D01*
G01X164119Y389150D02*
X166619D01*
Y390191D01*
X166494Y390525D01*
X166327Y390733D01*
X165994Y390816D01*
X165661Y390733D01*
X165452Y390483D01*
X165327Y390191D01*
Y389150D01*
G01Y390191D02*
X164119Y390816D01*
G01Y393583D02*
X166619D01*
X164827Y392041D01*
Y394125D01*
G01X164619Y395266D02*
X164327Y395516D01*
X164161Y395850D01*
X164119Y396225D01*
X164161Y396558D01*
X164369Y396891D01*
X164619Y397100D01*
X164869Y397141D01*
X165161Y397058D01*
X165369Y396766D01*
X165452Y396475D01*
Y396100D01*
G01Y396475D02*
X165577Y396725D01*
X165786Y396933D01*
X166036Y397016D01*
X166286Y396933D01*
X166494Y396725D01*
X166619Y396350D01*
X166577Y395975D01*
X166411Y395600D01*
G01X164619Y398366D02*
X164327Y398616D01*
X164161Y398950D01*
X164119Y399325D01*
X164161Y399658D01*
X164369Y399991D01*
X164619Y400200D01*
X164869Y400241D01*
X165161Y400158D01*
X165369Y399866D01*
X165452Y399575D01*
Y399200D01*
G01Y399575D02*
X165577Y399825D01*
X165786Y400033D01*
X166036Y400116D01*
X166286Y400033D01*
X166494Y399825D01*
X166619Y399450D01*
X166577Y399075D01*
X166411Y398700D01*
G01X163571Y403074D02*
X166071D01*
Y404115D01*
X165946Y404449D01*
X165779Y404657D01*
X165446Y404740D01*
X165113Y404657D01*
X164904Y404407D01*
X164779Y404115D01*
Y403074D01*
G01Y404115D02*
X163571Y404740D01*
G01Y407507D02*
X166071D01*
X164279Y405965D01*
Y408049D01*
G01X164613Y409315D02*
X164904Y409607D01*
X165071Y409857D01*
X165154Y410190D01*
X165071Y410482D01*
X164904Y410690D01*
X164654Y410857D01*
X164363Y410899D01*
X164113Y410857D01*
X163863Y410690D01*
X163654Y410440D01*
X163571Y410149D01*
X163654Y409815D01*
X163904Y409524D01*
X164279Y409357D01*
X164696Y409315D01*
X165238Y409399D01*
X165529Y409524D01*
X165821Y409732D01*
X166029Y410024D01*
X166071Y410315D01*
X165988Y410607D01*
X165779Y410815D01*
G01X165654Y412415D02*
X165904Y412665D01*
X166029Y412957D01*
X166071Y413290D01*
X165988Y413707D01*
X165779Y413999D01*
X165529Y414082D01*
X165279Y414040D01*
X165071Y413874D01*
X164654Y413040D01*
X164363Y412665D01*
X163946Y412415D01*
X163571Y412332D01*
Y414082D01*
G01X159571Y403074D02*
X162071D01*
Y404115D01*
X161946Y404449D01*
X161779Y404657D01*
X161446Y404740D01*
X161113Y404657D01*
X160904Y404407D01*
X160779Y404115D01*
Y403074D01*
G01Y404115D02*
X159571Y404740D01*
G01Y407507D02*
X162071D01*
X160279Y405965D01*
Y408049D01*
G01X160613Y409315D02*
X160904Y409607D01*
X161071Y409857D01*
X161154Y410190D01*
X161071Y410482D01*
X160904Y410690D01*
X160654Y410857D01*
X160363Y410899D01*
X160113Y410857D01*
X159863Y410690D01*
X159654Y410440D01*
X159571Y410149D01*
X159654Y409815D01*
X159904Y409524D01*
X160279Y409357D01*
X160696Y409315D01*
X161238Y409399D01*
X161529Y409524D01*
X161821Y409732D01*
X162029Y410024D01*
X162071Y410315D01*
X161988Y410607D01*
X161779Y410815D01*
G01X159946Y412290D02*
X159738Y412540D01*
X159613Y412832D01*
X159571Y413207D01*
X159654Y413582D01*
X159821Y413874D01*
X160113Y414082D01*
X160446Y414124D01*
X160779Y414040D01*
X160988Y413832D01*
X161154Y413540D01*
X161196Y413249D01*
X161154Y412957D01*
X160988Y412582D01*
X162071Y412707D01*
Y413832D01*
G01X156510Y391385D02*
X156760Y391510D01*
X157052Y391593D01*
X157385D01*
X157760Y391468D01*
X158052Y391260D01*
X158260Y391010D01*
X158427Y390593D01*
X158469Y390218D01*
X158385Y389843D01*
X158260Y389593D01*
X158010Y389343D01*
X157719Y389176D01*
X157427Y389093D01*
X157135D01*
X156844Y389176D01*
X156594Y389301D01*
X156385Y389468D01*
G01X155119Y391176D02*
X154869Y391426D01*
X154577Y391551D01*
X154244Y391593D01*
X153827Y391510D01*
X153535Y391301D01*
X153452Y391051D01*
X153494Y390801D01*
X153660Y390593D01*
X154494Y390176D01*
X154869Y389885D01*
X155119Y389468D01*
X155202Y389093D01*
X153452D01*
G01X151227D02*
Y391593D01*
X151727Y391093D01*
G01Y389093D02*
X150727D01*
G01X148835Y389385D02*
X148544Y389176D01*
X148210Y389093D01*
X147877Y389176D01*
X147585Y389426D01*
X147377Y389801D01*
X147294Y390176D01*
Y390635D01*
X147377Y391010D01*
X147585Y391343D01*
X147835Y391510D01*
X148127Y391593D01*
X148460Y391510D01*
X148710Y391343D01*
X148877Y391093D01*
X148960Y390760D01*
X148877Y390468D01*
X148669Y390176D01*
X148419Y390010D01*
X148127Y389968D01*
X147794Y390051D01*
X147544Y390260D01*
X147294Y390635D01*
G01X161321Y442074D02*
X158821D01*
G01X161321Y441116D02*
Y443032D01*
G01X158821Y444341D02*
X161321D01*
Y445341D01*
X161196Y445674D01*
X160904Y445924D01*
X160571Y446007D01*
X160238Y445924D01*
X159988Y445716D01*
X159863Y445341D01*
Y444341D01*
G01X159321Y447357D02*
X159029Y447607D01*
X158863Y447941D01*
X158821Y448316D01*
X158863Y448649D01*
X159071Y448982D01*
X159321Y449191D01*
X159571Y449232D01*
X159863Y449149D01*
X160071Y448857D01*
X160154Y448566D01*
Y448191D01*
G01Y448566D02*
X160279Y448816D01*
X160488Y449024D01*
X160738Y449107D01*
X160988Y449024D01*
X161196Y448816D01*
X161321Y448441D01*
X161279Y448066D01*
X161113Y447691D01*
G01X160904Y450582D02*
X161154Y450832D01*
X161279Y451124D01*
X161321Y451457D01*
X161238Y451874D01*
X161029Y452166D01*
X160779Y452249D01*
X160529Y452207D01*
X160321Y452041D01*
X159904Y451207D01*
X159613Y450832D01*
X159196Y450582D01*
X158821Y450499D01*
Y452249D01*
G01Y454974D02*
X161321D01*
X159529Y453432D01*
Y455516D01*
G01X159000Y416017D02*
X161500D01*
Y417058D01*
X161375Y417392D01*
X161208Y417600D01*
X160875Y417683D01*
X160542Y417600D01*
X160333Y417350D01*
X160208Y417058D01*
Y416017D01*
G01Y417058D02*
X159000Y417683D01*
G01X161083Y419158D02*
X161333Y419408D01*
X161458Y419700D01*
X161500Y420033D01*
X161417Y420450D01*
X161208Y420742D01*
X160958Y420825D01*
X160708Y420783D01*
X160500Y420617D01*
X160083Y419783D01*
X159792Y419408D01*
X159375Y419158D01*
X159000Y419075D01*
Y420825D01*
G01X161083Y422258D02*
X161333Y422508D01*
X161458Y422800D01*
X161500Y423133D01*
X161417Y423550D01*
X161208Y423842D01*
X160958Y423925D01*
X160708Y423883D01*
X160500Y423717D01*
X160083Y422883D01*
X159792Y422508D01*
X159375Y422258D01*
X159000Y422175D01*
Y423925D01*
G01X159500Y425233D02*
X159208Y425483D01*
X159042Y425817D01*
X159000Y426192D01*
X159042Y426525D01*
X159250Y426858D01*
X159500Y427067D01*
X159750Y427108D01*
X160042Y427025D01*
X160250Y426733D01*
X160333Y426442D01*
Y426067D01*
G01Y426442D02*
X160458Y426692D01*
X160667Y426900D01*
X160917Y426983D01*
X161167Y426900D01*
X161375Y426692D01*
X161500Y426317D01*
X161458Y425942D01*
X161292Y425567D01*
G01X146983Y435202D02*
Y437702D01*
X145942D01*
X145608Y437577D01*
X145400Y437410D01*
X145317Y437077D01*
X145400Y436744D01*
X145650Y436535D01*
X145942Y436410D01*
X146983D01*
G01X145942D02*
X145317Y435202D01*
G01X143842Y436244D02*
X143550Y436535D01*
X143300Y436702D01*
X142967Y436785D01*
X142675Y436702D01*
X142467Y436535D01*
X142300Y436285D01*
X142258Y435994D01*
X142300Y435744D01*
X142467Y435494D01*
X142717Y435285D01*
X143008Y435202D01*
X143342Y435285D01*
X143633Y435535D01*
X143800Y435910D01*
X143842Y436327D01*
X143758Y436869D01*
X143633Y437160D01*
X143425Y437452D01*
X143133Y437660D01*
X142842Y437702D01*
X142550Y437619D01*
X142342Y437410D01*
G01X140033Y435202D02*
X139950Y435744D01*
X139825Y436202D01*
X139658Y436619D01*
X139450Y437077D01*
X139117Y437702D01*
X140783D01*
G01X137558Y435494D02*
X137267Y435285D01*
X136933Y435202D01*
X136600Y435285D01*
X136308Y435535D01*
X136100Y435910D01*
X136017Y436285D01*
Y436744D01*
X136100Y437119D01*
X136308Y437452D01*
X136558Y437619D01*
X136850Y437702D01*
X137183Y437619D01*
X137433Y437452D01*
X137600Y437202D01*
X137683Y436869D01*
X137600Y436577D01*
X137392Y436285D01*
X137142Y436119D01*
X136850Y436077D01*
X136517Y436160D01*
X136267Y436369D01*
X136017Y436744D01*
G01X144546Y432391D02*
Y428391D01*
X137146D01*
G01X163441Y429411D02*
X165941D01*
Y430452D01*
X165816Y430786D01*
X165649Y430994D01*
X165316Y431077D01*
X164983Y430994D01*
X164774Y430744D01*
X164649Y430452D01*
Y429411D01*
G01Y430452D02*
X163441Y431077D01*
G01Y433844D02*
X165941D01*
X164149Y432302D01*
Y434386D01*
G01X164483Y435652D02*
X164774Y435944D01*
X164941Y436194D01*
X165024Y436527D01*
X164941Y436819D01*
X164774Y437027D01*
X164524Y437194D01*
X164233Y437236D01*
X163983Y437194D01*
X163733Y437027D01*
X163524Y436777D01*
X163441Y436486D01*
X163524Y436152D01*
X163774Y435861D01*
X164149Y435694D01*
X164566Y435652D01*
X165108Y435736D01*
X165399Y435861D01*
X165691Y436069D01*
X165899Y436361D01*
X165941Y436652D01*
X165858Y436944D01*
X165649Y437152D01*
G01X163441Y440044D02*
X165941D01*
X164149Y438502D01*
Y440586D01*
G01X159241Y429111D02*
X161741D01*
Y430152D01*
X161616Y430486D01*
X161449Y430694D01*
X161116Y430777D01*
X160783Y430694D01*
X160574Y430444D01*
X160449Y430152D01*
Y429111D01*
G01Y430152D02*
X159241Y430777D01*
G01X160283Y432252D02*
X160574Y432544D01*
X160741Y432794D01*
X160824Y433127D01*
X160741Y433419D01*
X160574Y433627D01*
X160324Y433794D01*
X160033Y433836D01*
X159783Y433794D01*
X159533Y433627D01*
X159324Y433377D01*
X159241Y433086D01*
X159324Y432752D01*
X159574Y432461D01*
X159949Y432294D01*
X160366Y432252D01*
X160908Y432336D01*
X161199Y432461D01*
X161491Y432669D01*
X161699Y432961D01*
X161741Y433252D01*
X161658Y433544D01*
X161449Y433752D01*
G01X161324Y435352D02*
X161574Y435602D01*
X161699Y435894D01*
X161741Y436227D01*
X161658Y436644D01*
X161449Y436936D01*
X161199Y437019D01*
X160949Y436977D01*
X160741Y436811D01*
X160324Y435977D01*
X160033Y435602D01*
X159616Y435352D01*
X159241Y435269D01*
Y437019D01*
G01X161741Y439244D02*
X161658Y438911D01*
X161449Y438661D01*
X161199Y438494D01*
X160866Y438369D01*
X160491Y438327D01*
X160116Y438369D01*
X159783Y438494D01*
X159533Y438661D01*
X159324Y438911D01*
X159241Y439244D01*
X159324Y439577D01*
X159533Y439827D01*
X159783Y439994D01*
X160116Y440119D01*
X160491Y440161D01*
X160866Y440119D01*
X161199Y439994D01*
X161449Y439827D01*
X161658Y439577D01*
X161741Y439244D01*
G01X165290Y442203D02*
X167790D01*
Y443244D01*
X167665Y443578D01*
X167498Y443786D01*
X167165Y443869D01*
X166832Y443786D01*
X166623Y443536D01*
X166498Y443244D01*
Y442203D01*
G01Y443244D02*
X165290Y443869D01*
G01X166332Y445344D02*
X166623Y445636D01*
X166790Y445886D01*
X166873Y446219D01*
X166790Y446511D01*
X166623Y446719D01*
X166373Y446886D01*
X166082Y446928D01*
X165832Y446886D01*
X165582Y446719D01*
X165373Y446469D01*
X165290Y446178D01*
X165373Y445844D01*
X165623Y445553D01*
X165998Y445386D01*
X166415Y445344D01*
X166957Y445428D01*
X167248Y445553D01*
X167540Y445761D01*
X167748Y446053D01*
X167790Y446344D01*
X167707Y446636D01*
X167498Y446844D01*
G01X165290Y449153D02*
X165832Y449236D01*
X166290Y449361D01*
X166707Y449528D01*
X167165Y449736D01*
X167790Y450069D01*
Y448403D01*
G01X167373Y451544D02*
X167623Y451794D01*
X167748Y452086D01*
X167790Y452419D01*
X167707Y452836D01*
X167498Y453128D01*
X167248Y453211D01*
X166998Y453169D01*
X166790Y453003D01*
X166373Y452169D01*
X166082Y451794D01*
X165665Y451544D01*
X165290Y451461D01*
Y453211D01*
G01X156500Y471800D02*
X154000D01*
G01X156500Y470842D02*
Y472758D01*
G01X154000Y474067D02*
X156500D01*
Y475067D01*
X156375Y475400D01*
X156083Y475650D01*
X155750Y475733D01*
X155417Y475650D01*
X155167Y475442D01*
X155042Y475067D01*
Y474067D01*
G01X156083Y477208D02*
X156333Y477458D01*
X156458Y477750D01*
X156500Y478083D01*
X156417Y478500D01*
X156208Y478792D01*
X155958Y478875D01*
X155708Y478833D01*
X155500Y478667D01*
X155083Y477833D01*
X154792Y477458D01*
X154375Y477208D01*
X154000Y477125D01*
Y478875D01*
G01X154292Y480392D02*
X154083Y480683D01*
X154000Y481017D01*
X154083Y481350D01*
X154333Y481642D01*
X154708Y481850D01*
X155083Y481933D01*
X155542D01*
X155917Y481850D01*
X156250Y481642D01*
X156417Y481392D01*
X156500Y481100D01*
X156417Y480767D01*
X156250Y480517D01*
X156000Y480350D01*
X155667Y480267D01*
X155375Y480350D01*
X155083Y480558D01*
X154917Y480808D01*
X154875Y481100D01*
X154958Y481433D01*
X155167Y481683D01*
X155542Y481933D01*
G01X155042Y483408D02*
X155333Y483700D01*
X155500Y483950D01*
X155583Y484283D01*
X155500Y484575D01*
X155333Y484783D01*
X155083Y484950D01*
X154792Y484992D01*
X154542Y484950D01*
X154292Y484783D01*
X154083Y484533D01*
X154000Y484242D01*
X154083Y483908D01*
X154333Y483617D01*
X154708Y483450D01*
X155125Y483408D01*
X155667Y483492D01*
X155958Y483617D01*
X156250Y483825D01*
X156458Y484117D01*
X156500Y484408D01*
X156417Y484700D01*
X156208Y484908D01*
G01X160910Y479441D02*
X158410D01*
G01X160910Y478483D02*
Y480399D01*
G01X158410Y481708D02*
X160910D01*
Y482708D01*
X160785Y483041D01*
X160493Y483291D01*
X160160Y483374D01*
X159827Y483291D01*
X159577Y483083D01*
X159452Y482708D01*
Y481708D01*
G01X160493Y484849D02*
X160743Y485099D01*
X160868Y485391D01*
X160910Y485724D01*
X160827Y486141D01*
X160618Y486433D01*
X160368Y486516D01*
X160118Y486474D01*
X159910Y486308D01*
X159493Y485474D01*
X159202Y485099D01*
X158785Y484849D01*
X158410Y484766D01*
Y486516D01*
G01X158702Y488033D02*
X158493Y488324D01*
X158410Y488658D01*
X158493Y488991D01*
X158743Y489283D01*
X159118Y489491D01*
X159493Y489574D01*
X159952D01*
X160327Y489491D01*
X160660Y489283D01*
X160827Y489033D01*
X160910Y488741D01*
X160827Y488408D01*
X160660Y488158D01*
X160410Y487991D01*
X160077Y487908D01*
X159785Y487991D01*
X159493Y488199D01*
X159327Y488449D01*
X159285Y488741D01*
X159368Y489074D01*
X159577Y489324D01*
X159952Y489574D01*
G01X158410Y491841D02*
X158452Y492133D01*
X158577Y492466D01*
X158785Y492674D01*
X159077Y492758D01*
X159368Y492674D01*
X159618Y492424D01*
X159743Y492049D01*
Y491633D01*
X159827Y491383D01*
X160035Y491174D01*
X160327Y491091D01*
X160618Y491216D01*
X160827Y491508D01*
X160910Y491841D01*
X160827Y492174D01*
X160618Y492466D01*
X160327Y492591D01*
X160035Y492508D01*
X159827Y492299D01*
X159743Y492049D01*
Y491633D01*
X159618Y491258D01*
X159368Y491008D01*
X159077Y490924D01*
X158785Y491008D01*
X158577Y491216D01*
X158452Y491549D01*
X158410Y491841D01*
G01X171893Y472694D02*
Y470194D01*
G01X172851Y472694D02*
X170935D01*
G01X169626Y470194D02*
Y472694D01*
X168626D01*
X168293Y472569D01*
X168043Y472277D01*
X167960Y471944D01*
X168043Y471611D01*
X168251Y471361D01*
X168626Y471236D01*
X169626D01*
G01X165693Y470194D02*
Y472694D01*
X166193Y472194D01*
G01Y470194D02*
X165193D01*
G01X163510Y470569D02*
X163260Y470361D01*
X162968Y470236D01*
X162593Y470194D01*
X162218Y470277D01*
X161926Y470444D01*
X161718Y470736D01*
X161676Y471069D01*
X161760Y471402D01*
X161968Y471611D01*
X162260Y471777D01*
X162551Y471819D01*
X162843Y471777D01*
X163218Y471611D01*
X163093Y472694D01*
X161968D01*
G01X160410Y470694D02*
X160160Y470402D01*
X159826Y470236D01*
X159451Y470194D01*
X159118Y470236D01*
X158785Y470444D01*
X158576Y470694D01*
X158535Y470944D01*
X158618Y471236D01*
X158910Y471444D01*
X159201Y471527D01*
X159576D01*
G01X159201D02*
X158951Y471652D01*
X158743Y471861D01*
X158660Y472111D01*
X158743Y472361D01*
X158951Y472569D01*
X159326Y472694D01*
X159701Y472652D01*
X160076Y472486D01*
G01X147400Y464800D02*
X144900D01*
G01X147400Y463842D02*
Y465758D01*
G01X144900Y467067D02*
X147400D01*
Y468067D01*
X147275Y468400D01*
X146983Y468650D01*
X146650Y468733D01*
X146317Y468650D01*
X146067Y468442D01*
X145942Y468067D01*
Y467067D01*
G01X145400Y470083D02*
X145108Y470333D01*
X144942Y470667D01*
X144900Y471042D01*
X144942Y471375D01*
X145150Y471708D01*
X145400Y471917D01*
X145650Y471958D01*
X145942Y471875D01*
X146150Y471583D01*
X146233Y471292D01*
Y470917D01*
G01Y471292D02*
X146358Y471542D01*
X146567Y471750D01*
X146817Y471833D01*
X147067Y471750D01*
X147275Y471542D01*
X147400Y471167D01*
X147358Y470792D01*
X147192Y470417D01*
G01X146983Y473308D02*
X147233Y473558D01*
X147358Y473850D01*
X147400Y474183D01*
X147317Y474600D01*
X147108Y474892D01*
X146858Y474975D01*
X146608Y474933D01*
X146400Y474767D01*
X145983Y473933D01*
X145692Y473558D01*
X145275Y473308D01*
X144900Y473225D01*
Y474975D01*
G01Y477117D02*
X145442Y477200D01*
X145900Y477325D01*
X146317Y477492D01*
X146775Y477700D01*
X147400Y478033D01*
Y476367D01*
G01X147000Y456300D02*
X143000D01*
Y463700D01*
G01Y456300D02*
X139000D01*
Y463700D01*
G01X152150Y447290D02*
X148150D01*
Y454690D01*
G01X157680Y447230D02*
X153680D01*
Y454630D01*
G01X148150Y447290D02*
X144150D01*
Y454690D01*
G01X139000Y455800D02*
X135000D01*
Y463200D01*
G01X142500Y447290D02*
X138500D01*
Y454690D01*
G01X166000Y455800D02*
X162000D01*
Y463200D01*
G01X162670Y476606D02*
X165170D01*
Y477647D01*
X165045Y477981D01*
X164878Y478189D01*
X164545Y478272D01*
X164212Y478189D01*
X164003Y477939D01*
X163878Y477647D01*
Y476606D01*
G01Y477647D02*
X162670Y478272D01*
G01X163170Y479622D02*
X162878Y479872D01*
X162712Y480206D01*
X162670Y480581D01*
X162712Y480914D01*
X162920Y481247D01*
X163170Y481456D01*
X163420Y481497D01*
X163712Y481414D01*
X163920Y481122D01*
X164003Y480831D01*
Y480456D01*
G01Y480831D02*
X164128Y481081D01*
X164337Y481289D01*
X164587Y481372D01*
X164837Y481289D01*
X165045Y481081D01*
X165170Y480706D01*
X165128Y480331D01*
X164962Y479956D01*
G01X165170Y483639D02*
X165087Y483306D01*
X164878Y483056D01*
X164628Y482889D01*
X164295Y482764D01*
X163920Y482722D01*
X163545Y482764D01*
X163212Y482889D01*
X162962Y483056D01*
X162753Y483306D01*
X162670Y483639D01*
X162753Y483972D01*
X162962Y484222D01*
X163212Y484389D01*
X163545Y484514D01*
X163920Y484556D01*
X164295Y484514D01*
X164628Y484389D01*
X164878Y484222D01*
X165087Y483972D01*
X165170Y483639D01*
G01X162670Y486739D02*
X165170D01*
X164670Y486239D01*
G01X162670D02*
Y487239D01*
G01X163500Y496300D02*
X159500D01*
Y503700D01*
G01X145509Y506220D02*
X145634Y505970D01*
X145717Y505678D01*
Y505345D01*
X145592Y504970D01*
X145384Y504678D01*
X145134Y504470D01*
X144717Y504303D01*
X144342Y504261D01*
X143967Y504345D01*
X143717Y504470D01*
X143467Y504720D01*
X143300Y505011D01*
X143217Y505303D01*
Y505595D01*
X143300Y505886D01*
X143425Y506136D01*
X143592Y506345D01*
G01X145300Y507611D02*
X145550Y507861D01*
X145675Y508153D01*
X145717Y508486D01*
X145634Y508903D01*
X145425Y509195D01*
X145175Y509278D01*
X144925Y509236D01*
X144717Y509070D01*
X144300Y508236D01*
X144009Y507861D01*
X143592Y507611D01*
X143217Y507528D01*
Y509278D01*
G01Y511503D02*
X145717D01*
X145217Y511003D01*
G01X143217D02*
Y512003D01*
G01X145300Y513811D02*
X145550Y514061D01*
X145675Y514353D01*
X145717Y514686D01*
X145634Y515103D01*
X145425Y515395D01*
X145175Y515478D01*
X144925Y515436D01*
X144717Y515270D01*
X144300Y514436D01*
X144009Y514061D01*
X143592Y513811D01*
X143217Y513728D01*
Y515478D01*
G01X157654Y506127D02*
X157779Y505877D01*
X157862Y505585D01*
Y505252D01*
X157737Y504877D01*
X157529Y504585D01*
X157279Y504377D01*
X156862Y504210D01*
X156487Y504168D01*
X156112Y504252D01*
X155862Y504377D01*
X155612Y504627D01*
X155445Y504918D01*
X155362Y505210D01*
Y505502D01*
X155445Y505793D01*
X155570Y506043D01*
X155737Y506252D01*
G01X157445Y507518D02*
X157695Y507768D01*
X157820Y508060D01*
X157862Y508393D01*
X157779Y508810D01*
X157570Y509102D01*
X157320Y509185D01*
X157070Y509143D01*
X156862Y508977D01*
X156445Y508143D01*
X156154Y507768D01*
X155737Y507518D01*
X155362Y507435D01*
Y509185D01*
G01Y511410D02*
X157862D01*
X157362Y510910D01*
G01X155362D02*
Y511910D01*
G01X156404Y513718D02*
X156695Y514010D01*
X156862Y514260D01*
X156945Y514593D01*
X156862Y514885D01*
X156695Y515093D01*
X156445Y515260D01*
X156154Y515302D01*
X155904Y515260D01*
X155654Y515093D01*
X155445Y514843D01*
X155362Y514552D01*
X155445Y514218D01*
X155695Y513927D01*
X156070Y513760D01*
X156487Y513718D01*
X157029Y513802D01*
X157320Y513927D01*
X157612Y514135D01*
X157820Y514427D01*
X157862Y514718D01*
X157779Y515010D01*
X157570Y515218D01*
G01X153708Y505852D02*
X153833Y505602D01*
X153916Y505310D01*
Y504977D01*
X153791Y504602D01*
X153583Y504310D01*
X153333Y504102D01*
X152916Y503935D01*
X152541Y503893D01*
X152166Y503977D01*
X151916Y504102D01*
X151666Y504352D01*
X151499Y504643D01*
X151416Y504935D01*
Y505227D01*
X151499Y505518D01*
X151624Y505768D01*
X151791Y505977D01*
G01X153499Y507243D02*
X153749Y507493D01*
X153874Y507785D01*
X153916Y508118D01*
X153833Y508535D01*
X153624Y508827D01*
X153374Y508910D01*
X153124Y508868D01*
X152916Y508702D01*
X152499Y507868D01*
X152208Y507493D01*
X151791Y507243D01*
X151416Y507160D01*
Y508910D01*
G01Y511135D02*
X153916D01*
X153416Y510635D01*
G01X151416D02*
Y511635D01*
G01Y514152D02*
X151958Y514235D01*
X152416Y514360D01*
X152833Y514527D01*
X153291Y514735D01*
X153916Y515068D01*
Y513402D01*
G01X149252Y506090D02*
X149377Y505840D01*
X149460Y505548D01*
Y505215D01*
X149335Y504840D01*
X149127Y504548D01*
X148877Y504340D01*
X148460Y504173D01*
X148085Y504131D01*
X147710Y504215D01*
X147460Y504340D01*
X147210Y504590D01*
X147043Y504881D01*
X146960Y505173D01*
Y505465D01*
X147043Y505756D01*
X147168Y506006D01*
X147335Y506215D01*
G01X149043Y507481D02*
X149293Y507731D01*
X149418Y508023D01*
X149460Y508356D01*
X149377Y508773D01*
X149168Y509065D01*
X148918Y509148D01*
X148668Y509106D01*
X148460Y508940D01*
X148043Y508106D01*
X147752Y507731D01*
X147335Y507481D01*
X146960Y507398D01*
Y509148D01*
G01Y511373D02*
X149460D01*
X148960Y510873D01*
G01X146960D02*
Y511873D01*
G01Y514473D02*
X147002Y514765D01*
X147127Y515098D01*
X147335Y515306D01*
X147627Y515390D01*
X147918Y515306D01*
X148168Y515056D01*
X148293Y514681D01*
Y514265D01*
X148377Y514015D01*
X148585Y513806D01*
X148877Y513723D01*
X149168Y513848D01*
X149377Y514140D01*
X149460Y514473D01*
X149377Y514806D01*
X149168Y515098D01*
X148877Y515223D01*
X148585Y515140D01*
X148377Y514931D01*
X148293Y514681D01*
Y514265D01*
X148168Y513890D01*
X147918Y513640D01*
X147627Y513556D01*
X147335Y513640D01*
X147127Y513848D01*
X147002Y514181D01*
X146960Y514473D01*
G01X162266Y536841D02*
Y534341D01*
G01X163224Y536841D02*
X161308D01*
G01X159999Y534341D02*
Y536841D01*
X158999D01*
X158666Y536716D01*
X158416Y536424D01*
X158333Y536091D01*
X158416Y535758D01*
X158624Y535508D01*
X158999Y535383D01*
X159999D01*
G01X156066Y534341D02*
Y536841D01*
X156566Y536341D01*
G01Y534341D02*
X155566D01*
G01X153883Y534716D02*
X153633Y534508D01*
X153341Y534383D01*
X152966Y534341D01*
X152591Y534424D01*
X152299Y534591D01*
X152091Y534883D01*
X152049Y535216D01*
X152133Y535549D01*
X152341Y535758D01*
X152633Y535924D01*
X152924Y535966D01*
X153216Y535924D01*
X153591Y535758D01*
X153466Y536841D01*
X152341D01*
G01X150574Y534633D02*
X150283Y534424D01*
X149949Y534341D01*
X149616Y534424D01*
X149324Y534674D01*
X149116Y535049D01*
X149033Y535424D01*
Y535883D01*
X149116Y536258D01*
X149324Y536591D01*
X149574Y536758D01*
X149866Y536841D01*
X150199Y536758D01*
X150449Y536591D01*
X150616Y536341D01*
X150699Y536008D01*
X150616Y535716D01*
X150408Y535424D01*
X150158Y535258D01*
X149866Y535216D01*
X149533Y535299D01*
X149283Y535508D01*
X149033Y535883D01*
G01X164565Y541175D02*
Y538675D01*
G01X165523Y541175D02*
X163607D01*
G01X162298Y538675D02*
Y541175D01*
X161298D01*
X160965Y541050D01*
X160715Y540758D01*
X160632Y540425D01*
X160715Y540092D01*
X160923Y539842D01*
X161298Y539717D01*
X162298D01*
G01X158365Y538675D02*
Y541175D01*
X158865Y540675D01*
G01Y538675D02*
X157865D01*
G01X155973Y538967D02*
X155682Y538758D01*
X155348Y538675D01*
X155015Y538758D01*
X154723Y539008D01*
X154515Y539383D01*
X154432Y539758D01*
Y540217D01*
X154515Y540592D01*
X154723Y540925D01*
X154973Y541092D01*
X155265Y541175D01*
X155598Y541092D01*
X155848Y540925D01*
X156015Y540675D01*
X156098Y540342D01*
X156015Y540050D01*
X155807Y539758D01*
X155557Y539592D01*
X155265Y539550D01*
X154932Y539633D01*
X154682Y539842D01*
X154432Y540217D01*
G01X152165Y538675D02*
Y541175D01*
X152665Y540675D01*
G01Y538675D02*
X151665D01*
G01X143833Y527592D02*
X144083Y527717D01*
X144375Y527800D01*
X144708D01*
X145083Y527675D01*
X145375Y527467D01*
X145583Y527217D01*
X145750Y526800D01*
X145792Y526425D01*
X145708Y526050D01*
X145583Y525800D01*
X145333Y525550D01*
X145042Y525383D01*
X144750Y525300D01*
X144458D01*
X144167Y525383D01*
X143917Y525508D01*
X143708Y525675D01*
G01X142442Y527383D02*
X142192Y527633D01*
X141900Y527758D01*
X141567Y527800D01*
X141150Y527717D01*
X140858Y527508D01*
X140775Y527258D01*
X140817Y527008D01*
X140983Y526800D01*
X141817Y526383D01*
X142192Y526092D01*
X142442Y525675D01*
X142525Y525300D01*
X140775D01*
G01X138550Y527800D02*
X138883Y527717D01*
X139133Y527508D01*
X139300Y527258D01*
X139425Y526925D01*
X139467Y526550D01*
X139425Y526175D01*
X139300Y525842D01*
X139133Y525592D01*
X138883Y525383D01*
X138550Y525300D01*
X138217Y525383D01*
X137967Y525592D01*
X137800Y525842D01*
X137675Y526175D01*
X137633Y526550D01*
X137675Y526925D01*
X137800Y527258D01*
X137967Y527508D01*
X138217Y527717D01*
X138550Y527800D01*
G01X134950Y525300D02*
Y527800D01*
X136492Y526008D01*
X134408D01*
G01X171133Y531659D02*
X171383Y531784D01*
X171675Y531867D01*
X172008D01*
X172383Y531742D01*
X172675Y531534D01*
X172883Y531284D01*
X173050Y530867D01*
X173092Y530492D01*
X173008Y530117D01*
X172883Y529867D01*
X172633Y529617D01*
X172342Y529450D01*
X172050Y529367D01*
X171758D01*
X171467Y529450D01*
X171217Y529575D01*
X171008Y529742D01*
G01X169742Y531450D02*
X169492Y531700D01*
X169200Y531825D01*
X168867Y531867D01*
X168450Y531784D01*
X168158Y531575D01*
X168075Y531325D01*
X168117Y531075D01*
X168283Y530867D01*
X169117Y530450D01*
X169492Y530159D01*
X169742Y529742D01*
X169825Y529367D01*
X168075D01*
G01X165850Y531867D02*
X166183Y531784D01*
X166433Y531575D01*
X166600Y531325D01*
X166725Y530992D01*
X166767Y530617D01*
X166725Y530242D01*
X166600Y529909D01*
X166433Y529659D01*
X166183Y529450D01*
X165850Y529367D01*
X165517Y529450D01*
X165267Y529659D01*
X165100Y529909D01*
X164975Y530242D01*
X164933Y530617D01*
X164975Y530992D01*
X165100Y531325D01*
X165267Y531575D01*
X165517Y531784D01*
X165850Y531867D01*
G01X163667Y529742D02*
X163417Y529534D01*
X163125Y529409D01*
X162750Y529367D01*
X162375Y529450D01*
X162083Y529617D01*
X161875Y529909D01*
X161833Y530242D01*
X161917Y530575D01*
X162125Y530784D01*
X162417Y530950D01*
X162708Y530992D01*
X163000Y530950D01*
X163375Y530784D01*
X163250Y531867D01*
X162125D01*
G01X155959Y519901D02*
X156084Y519651D01*
X156167Y519359D01*
Y519026D01*
X156042Y518651D01*
X155834Y518359D01*
X155584Y518151D01*
X155167Y517984D01*
X154792Y517942D01*
X154417Y518026D01*
X154167Y518151D01*
X153917Y518401D01*
X153750Y518692D01*
X153667Y518984D01*
Y519276D01*
X153750Y519567D01*
X153875Y519817D01*
X154042Y520026D01*
G01X155750Y521292D02*
X156000Y521542D01*
X156125Y521834D01*
X156167Y522167D01*
X156084Y522584D01*
X155875Y522876D01*
X155625Y522959D01*
X155375Y522917D01*
X155167Y522751D01*
X154750Y521917D01*
X154459Y521542D01*
X154042Y521292D01*
X153667Y521209D01*
Y522959D01*
G01Y525184D02*
X156167D01*
X155667Y524684D01*
G01X153667D02*
Y525684D01*
G01Y528284D02*
X156167D01*
X155667Y527784D01*
G01X153667D02*
Y528784D01*
G01X178631Y570943D02*
Y568443D01*
G01X179589Y570943D02*
X177673D01*
G01X176364Y568443D02*
Y570943D01*
X175364D01*
X175031Y570818D01*
X174781Y570526D01*
X174698Y570193D01*
X174781Y569860D01*
X174989Y569610D01*
X175364Y569485D01*
X176364D01*
G01X173348Y568943D02*
X173098Y568651D01*
X172764Y568485D01*
X172389Y568443D01*
X172056Y568485D01*
X171723Y568693D01*
X171514Y568943D01*
X171473Y569193D01*
X171556Y569485D01*
X171848Y569693D01*
X172139Y569776D01*
X172514D01*
G01X172139D02*
X171889Y569901D01*
X171681Y570110D01*
X171598Y570360D01*
X171681Y570610D01*
X171889Y570818D01*
X172264Y570943D01*
X172639Y570901D01*
X173014Y570735D01*
G01X170123Y570526D02*
X169873Y570776D01*
X169581Y570901D01*
X169248Y570943D01*
X168831Y570860D01*
X168539Y570651D01*
X168456Y570401D01*
X168498Y570151D01*
X168664Y569943D01*
X169498Y569526D01*
X169873Y569235D01*
X170123Y568818D01*
X170206Y568443D01*
X168456D01*
G01X166231D02*
Y570943D01*
X166731Y570443D01*
G01Y568443D02*
X165731D01*
G01X178631Y575278D02*
Y572778D01*
G01X179589Y575278D02*
X177673D01*
G01X176364Y572778D02*
Y575278D01*
X175364D01*
X175031Y575153D01*
X174781Y574861D01*
X174698Y574528D01*
X174781Y574195D01*
X174989Y573945D01*
X175364Y573820D01*
X176364D01*
G01X172431Y572778D02*
Y575278D01*
X172931Y574778D01*
G01Y572778D02*
X171931D01*
G01X168831D02*
Y575278D01*
X170373Y573486D01*
X168289D01*
G01X167148Y573153D02*
X166898Y572945D01*
X166606Y572820D01*
X166231Y572778D01*
X165856Y572861D01*
X165564Y573028D01*
X165356Y573320D01*
X165314Y573653D01*
X165398Y573986D01*
X165606Y574195D01*
X165898Y574361D01*
X166189Y574403D01*
X166481Y574361D01*
X166856Y574195D01*
X166731Y575278D01*
X165606D01*
G01X166306Y549948D02*
X163806D01*
G01X166306Y548990D02*
Y550906D01*
G01X163806Y552215D02*
X166306D01*
Y553215D01*
X166181Y553548D01*
X165889Y553798D01*
X165556Y553881D01*
X165223Y553798D01*
X164973Y553590D01*
X164848Y553215D01*
Y552215D01*
G01X165889Y555356D02*
X166139Y555606D01*
X166264Y555898D01*
X166306Y556231D01*
X166223Y556648D01*
X166014Y556940D01*
X165764Y557023D01*
X165514Y556981D01*
X165306Y556815D01*
X164889Y555981D01*
X164598Y555606D01*
X164181Y555356D01*
X163806Y555273D01*
Y557023D01*
G01X164306Y558331D02*
X164014Y558581D01*
X163848Y558915D01*
X163806Y559290D01*
X163848Y559623D01*
X164056Y559956D01*
X164306Y560165D01*
X164556Y560206D01*
X164848Y560123D01*
X165056Y559831D01*
X165139Y559540D01*
Y559165D01*
G01Y559540D02*
X165264Y559790D01*
X165473Y559998D01*
X165723Y560081D01*
X165973Y559998D01*
X166181Y559790D01*
X166306Y559415D01*
X166264Y559040D01*
X166098Y558665D01*
G01X163806Y562348D02*
X166306D01*
X165806Y561848D01*
G01X163806D02*
Y562848D01*
G01X178454Y566609D02*
Y564109D01*
G01X179412Y566609D02*
X177496D01*
G01X176187Y564109D02*
Y566609D01*
X175187D01*
X174854Y566484D01*
X174604Y566192D01*
X174521Y565859D01*
X174604Y565526D01*
X174812Y565276D01*
X175187Y565151D01*
X176187D01*
G01X173046Y566192D02*
X172796Y566442D01*
X172504Y566567D01*
X172171Y566609D01*
X171754Y566526D01*
X171462Y566317D01*
X171379Y566067D01*
X171421Y565817D01*
X171587Y565609D01*
X172421Y565192D01*
X172796Y564901D01*
X173046Y564484D01*
X173129Y564109D01*
X171379D01*
G01X169946Y566192D02*
X169696Y566442D01*
X169404Y566567D01*
X169071Y566609D01*
X168654Y566526D01*
X168362Y566317D01*
X168279Y566067D01*
X168321Y565817D01*
X168487Y565609D01*
X169321Y565192D01*
X169696Y564901D01*
X169946Y564484D01*
X170029Y564109D01*
X168279D01*
G01X166762Y564401D02*
X166471Y564192D01*
X166137Y564109D01*
X165804Y564192D01*
X165512Y564442D01*
X165304Y564817D01*
X165221Y565192D01*
Y565651D01*
X165304Y566026D01*
X165512Y566359D01*
X165762Y566526D01*
X166054Y566609D01*
X166387Y566526D01*
X166637Y566359D01*
X166804Y566109D01*
X166887Y565776D01*
X166804Y565484D01*
X166596Y565192D01*
X166346Y565026D01*
X166054Y564984D01*
X165721Y565067D01*
X165471Y565276D01*
X165221Y565651D01*
G01X166958Y634509D02*
X167083Y634259D01*
X167166Y633967D01*
Y633634D01*
X167041Y633259D01*
X166833Y632967D01*
X166583Y632759D01*
X166166Y632592D01*
X165791Y632550D01*
X165416Y632634D01*
X165166Y632759D01*
X164916Y633009D01*
X164749Y633300D01*
X164666Y633592D01*
Y633884D01*
X164749Y634175D01*
X164874Y634425D01*
X165041Y634634D01*
G01X164666Y636692D02*
X167166D01*
X166666Y636192D01*
G01X164666D02*
Y637192D01*
G01Y639792D02*
X164708Y640084D01*
X164833Y640417D01*
X165041Y640625D01*
X165333Y640709D01*
X165624Y640625D01*
X165874Y640375D01*
X165999Y640000D01*
Y639584D01*
X166083Y639334D01*
X166291Y639125D01*
X166583Y639042D01*
X166874Y639167D01*
X167083Y639459D01*
X167166Y639792D01*
X167083Y640125D01*
X166874Y640417D01*
X166583Y640542D01*
X166291Y640459D01*
X166083Y640250D01*
X165999Y640000D01*
Y639584D01*
X165874Y639209D01*
X165624Y638959D01*
X165333Y638875D01*
X165041Y638959D01*
X164833Y639167D01*
X164708Y639500D01*
X164666Y639792D01*
G01X166749Y642100D02*
X166999Y642350D01*
X167124Y642642D01*
X167166Y642975D01*
X167083Y643392D01*
X166874Y643684D01*
X166624Y643767D01*
X166374Y643725D01*
X166166Y643559D01*
X165749Y642725D01*
X165458Y642350D01*
X165041Y642100D01*
X164666Y642017D01*
Y643767D01*
G01X138399Y633072D02*
X138524Y632822D01*
X138607Y632530D01*
Y632197D01*
X138482Y631822D01*
X138274Y631530D01*
X138024Y631322D01*
X137607Y631155D01*
X137232Y631113D01*
X136857Y631197D01*
X136607Y631322D01*
X136357Y631572D01*
X136190Y631863D01*
X136107Y632155D01*
Y632447D01*
X136190Y632738D01*
X136315Y632988D01*
X136482Y633197D01*
G01X136107Y635255D02*
X138607D01*
X138107Y634755D01*
G01X136107D02*
Y635755D01*
G01X136399Y637647D02*
X136190Y637938D01*
X136107Y638272D01*
X136190Y638605D01*
X136440Y638897D01*
X136815Y639105D01*
X137190Y639188D01*
X137649D01*
X138024Y639105D01*
X138357Y638897D01*
X138524Y638647D01*
X138607Y638355D01*
X138524Y638022D01*
X138357Y637772D01*
X138107Y637605D01*
X137774Y637522D01*
X137482Y637605D01*
X137190Y637813D01*
X137024Y638063D01*
X136982Y638355D01*
X137065Y638688D01*
X137274Y638938D01*
X137649Y639188D01*
G01X136107Y641372D02*
X136649Y641455D01*
X137107Y641580D01*
X137524Y641747D01*
X137982Y641955D01*
X138607Y642288D01*
Y640622D01*
G01X148505Y634608D02*
X148630Y634358D01*
X148713Y634066D01*
Y633733D01*
X148588Y633358D01*
X148380Y633066D01*
X148130Y632858D01*
X147713Y632691D01*
X147338Y632649D01*
X146963Y632733D01*
X146713Y632858D01*
X146463Y633108D01*
X146296Y633399D01*
X146213Y633691D01*
Y633983D01*
X146296Y634274D01*
X146421Y634524D01*
X146588Y634733D01*
G01X146213Y636791D02*
X148713D01*
X148213Y636291D01*
G01X146213D02*
Y637291D01*
G01Y639808D02*
X146755Y639891D01*
X147213Y640016D01*
X147630Y640183D01*
X148088Y640391D01*
X148713Y640724D01*
Y639058D01*
G01X146213Y642991D02*
X148713D01*
X148213Y642491D01*
G01X146213D02*
Y643491D01*
G01X156958Y634509D02*
X157083Y634259D01*
X157166Y633967D01*
Y633634D01*
X157041Y633259D01*
X156833Y632967D01*
X156583Y632759D01*
X156166Y632592D01*
X155791Y632550D01*
X155416Y632634D01*
X155166Y632759D01*
X154916Y633009D01*
X154749Y633300D01*
X154666Y633592D01*
Y633884D01*
X154749Y634175D01*
X154874Y634425D01*
X155041Y634634D01*
G01X154666Y636692D02*
X157166D01*
X156666Y636192D01*
G01X154666D02*
Y637192D01*
G01Y639709D02*
X155208Y639792D01*
X155666Y639917D01*
X156083Y640084D01*
X156541Y640292D01*
X157166Y640625D01*
Y638959D01*
G01X155166Y641975D02*
X154874Y642225D01*
X154708Y642559D01*
X154666Y642934D01*
X154708Y643267D01*
X154916Y643600D01*
X155166Y643809D01*
X155416Y643850D01*
X155708Y643767D01*
X155916Y643475D01*
X155999Y643184D01*
Y642809D01*
G01Y643184D02*
X156124Y643434D01*
X156333Y643642D01*
X156583Y643725D01*
X156833Y643642D01*
X157041Y643434D01*
X157166Y643059D01*
X157124Y642684D01*
X156958Y642309D01*
G01X161958Y634509D02*
X162083Y634259D01*
X162166Y633967D01*
Y633634D01*
X162041Y633259D01*
X161833Y632967D01*
X161583Y632759D01*
X161166Y632592D01*
X160791Y632550D01*
X160416Y632634D01*
X160166Y632759D01*
X159916Y633009D01*
X159749Y633300D01*
X159666Y633592D01*
Y633884D01*
X159749Y634175D01*
X159874Y634425D01*
X160041Y634634D01*
G01X159666Y636692D02*
X162166D01*
X161666Y636192D01*
G01X159666D02*
Y637192D01*
G01Y639792D02*
X159708Y640084D01*
X159833Y640417D01*
X160041Y640625D01*
X160333Y640709D01*
X160624Y640625D01*
X160874Y640375D01*
X160999Y640000D01*
Y639584D01*
X161083Y639334D01*
X161291Y639125D01*
X161583Y639042D01*
X161874Y639167D01*
X162083Y639459D01*
X162166Y639792D01*
X162083Y640125D01*
X161874Y640417D01*
X161583Y640542D01*
X161291Y640459D01*
X161083Y640250D01*
X160999Y640000D01*
Y639584D01*
X160874Y639209D01*
X160624Y638959D01*
X160333Y638875D01*
X160041Y638959D01*
X159833Y639167D01*
X159708Y639500D01*
X159666Y639792D01*
G01Y642892D02*
X162166D01*
X161666Y642392D01*
G01X159666D02*
Y643392D01*
G01X166000Y789800D02*
X162000D01*
Y797200D01*
G01Y789800D02*
X158000D01*
Y797200D01*
G01X198000Y405900D02*
X184600D01*
G01D02*
Y417300D01*
G01X198000D02*
Y405900D01*
G01X194900Y405300D02*
Y401300D01*
X187500D01*
G01X202500Y406300D02*
X198500D01*
Y413700D01*
G01X199125Y393510D02*
X201625D01*
Y394551D01*
X201500Y394885D01*
X201333Y395093D01*
X201000Y395176D01*
X200667Y395093D01*
X200458Y394843D01*
X200333Y394551D01*
Y393510D01*
G01Y394551D02*
X199125Y395176D01*
G01Y397943D02*
X201625D01*
X199833Y396401D01*
Y398485D01*
G01X201625Y400543D02*
X201542Y400210D01*
X201333Y399960D01*
X201083Y399793D01*
X200750Y399668D01*
X200375Y399626D01*
X200000Y399668D01*
X199667Y399793D01*
X199417Y399960D01*
X199208Y400210D01*
X199125Y400543D01*
X199208Y400876D01*
X199417Y401126D01*
X199667Y401293D01*
X200000Y401418D01*
X200375Y401460D01*
X200750Y401418D01*
X201083Y401293D01*
X201333Y401126D01*
X201542Y400876D01*
X201625Y400543D01*
G01X199125Y403643D02*
X199167Y403935D01*
X199292Y404268D01*
X199500Y404476D01*
X199792Y404560D01*
X200083Y404476D01*
X200333Y404226D01*
X200458Y403851D01*
Y403435D01*
X200542Y403185D01*
X200750Y402976D01*
X201042Y402893D01*
X201333Y403018D01*
X201542Y403310D01*
X201625Y403643D01*
X201542Y403976D01*
X201333Y404268D01*
X201042Y404393D01*
X200750Y404310D01*
X200542Y404101D01*
X200458Y403851D01*
Y403435D01*
X200333Y403060D01*
X200083Y402810D01*
X199792Y402726D01*
X199500Y402810D01*
X199292Y403018D01*
X199167Y403351D01*
X199125Y403643D01*
G01X184300Y405900D02*
X180300D01*
Y413300D01*
G01X172319Y389250D02*
X174819D01*
Y390291D01*
X174694Y390625D01*
X174527Y390833D01*
X174194Y390916D01*
X173861Y390833D01*
X173652Y390583D01*
X173527Y390291D01*
Y389250D01*
G01Y390291D02*
X172319Y390916D01*
G01X172819Y392266D02*
X172527Y392516D01*
X172361Y392850D01*
X172319Y393225D01*
X172361Y393558D01*
X172569Y393891D01*
X172819Y394100D01*
X173069Y394141D01*
X173361Y394058D01*
X173569Y393766D01*
X173652Y393475D01*
Y393100D01*
G01Y393475D02*
X173777Y393725D01*
X173986Y393933D01*
X174236Y394016D01*
X174486Y393933D01*
X174694Y393725D01*
X174819Y393350D01*
X174777Y392975D01*
X174611Y392600D01*
G01X172319Y396283D02*
X174819D01*
X174319Y395783D01*
G01X172319D02*
Y396783D01*
G01Y399883D02*
X174819D01*
X173027Y398341D01*
Y400425D01*
G01X171621Y402587D02*
X174121D01*
Y403628D01*
X173996Y403962D01*
X173829Y404170D01*
X173496Y404253D01*
X173163Y404170D01*
X172954Y403920D01*
X172829Y403628D01*
Y402587D01*
G01Y403628D02*
X171621Y404253D01*
G01Y407020D02*
X174121D01*
X172329Y405478D01*
Y407562D01*
G01X171621Y409537D02*
X172163Y409620D01*
X172621Y409745D01*
X173038Y409912D01*
X173496Y410120D01*
X174121Y410453D01*
Y408787D01*
G01Y412720D02*
X174038Y412387D01*
X173829Y412137D01*
X173579Y411970D01*
X173246Y411845D01*
X172871Y411803D01*
X172496Y411845D01*
X172163Y411970D01*
X171913Y412137D01*
X171704Y412387D01*
X171621Y412720D01*
X171704Y413053D01*
X171913Y413303D01*
X172163Y413470D01*
X172496Y413595D01*
X172871Y413637D01*
X173246Y413595D01*
X173579Y413470D01*
X173829Y413303D01*
X174038Y413053D01*
X174121Y412720D01*
G01X168319Y389250D02*
X170819D01*
Y390291D01*
X170694Y390625D01*
X170527Y390833D01*
X170194Y390916D01*
X169861Y390833D01*
X169652Y390583D01*
X169527Y390291D01*
Y389250D01*
G01Y390291D02*
X168319Y390916D01*
G01Y393683D02*
X170819D01*
X169027Y392141D01*
Y394225D01*
G01X168319Y396283D02*
X170819D01*
X170319Y395783D01*
G01X168319D02*
Y396783D01*
G01Y399383D02*
X170819D01*
X170319Y398883D01*
G01X168319D02*
Y399883D01*
G01X167621Y402587D02*
X170121D01*
Y403628D01*
X169996Y403962D01*
X169829Y404170D01*
X169496Y404253D01*
X169163Y404170D01*
X168954Y403920D01*
X168829Y403628D01*
Y402587D01*
G01Y403628D02*
X167621Y404253D01*
G01Y407020D02*
X170121D01*
X168329Y405478D01*
Y407562D01*
G01X167621Y409537D02*
X168163Y409620D01*
X168621Y409745D01*
X169038Y409912D01*
X169496Y410120D01*
X170121Y410453D01*
Y408787D01*
G01X167621Y412720D02*
X170121D01*
X169621Y412220D01*
G01X167621D02*
Y413220D01*
G01X187500Y438600D02*
X189000Y437100D01*
X186000D01*
X187500Y438600D01*
G01X177600Y428100D02*
X187500D01*
Y438000D01*
G01X204600Y441300D02*
Y440700D01*
X195900D01*
Y440100D01*
X179400D01*
Y446700D01*
X183300D01*
Y462000D01*
G01X184600Y417300D02*
X198000D01*
G01X171966Y443330D02*
X169466D01*
G01X171966Y442372D02*
Y444288D01*
G01X169466Y445597D02*
X171966D01*
Y446597D01*
X171841Y446930D01*
X171549Y447180D01*
X171216Y447263D01*
X170883Y447180D01*
X170633Y446972D01*
X170508Y446597D01*
Y445597D01*
G01X169758Y448822D02*
X169549Y449113D01*
X169466Y449447D01*
X169549Y449780D01*
X169799Y450072D01*
X170174Y450280D01*
X170549Y450363D01*
X171008D01*
X171383Y450280D01*
X171716Y450072D01*
X171883Y449822D01*
X171966Y449530D01*
X171883Y449197D01*
X171716Y448947D01*
X171466Y448780D01*
X171133Y448697D01*
X170841Y448780D01*
X170549Y448988D01*
X170383Y449238D01*
X170341Y449530D01*
X170424Y449863D01*
X170633Y450113D01*
X171008Y450363D01*
G01X169466Y452547D02*
X170008Y452630D01*
X170466Y452755D01*
X170883Y452922D01*
X171341Y453130D01*
X171966Y453463D01*
Y451797D01*
G01X195100Y421800D02*
Y417800D01*
X187700D01*
G01X187600Y449100D02*
X191600D01*
Y441700D01*
G01Y449100D02*
X195600D01*
Y441700D01*
G01X166874Y429258D02*
X169374D01*
Y430299D01*
X169249Y430633D01*
X169082Y430841D01*
X168749Y430924D01*
X168416Y430841D01*
X168207Y430591D01*
X168082Y430299D01*
Y429258D01*
G01Y430299D02*
X166874Y430924D01*
G01Y433691D02*
X169374D01*
X167582Y432149D01*
Y434233D01*
G01X166874Y436791D02*
X169374D01*
X167582Y435249D01*
Y437333D01*
G01X168957Y438599D02*
X169207Y438849D01*
X169332Y439141D01*
X169374Y439474D01*
X169291Y439891D01*
X169082Y440183D01*
X168832Y440266D01*
X168582Y440224D01*
X168374Y440058D01*
X167957Y439224D01*
X167666Y438849D01*
X167249Y438599D01*
X166874Y438516D01*
Y440266D01*
G01X170530Y429450D02*
X173030D01*
Y430491D01*
X172905Y430825D01*
X172738Y431033D01*
X172405Y431116D01*
X172072Y431033D01*
X171863Y430783D01*
X171738Y430491D01*
Y429450D01*
G01Y430491D02*
X170530Y431116D01*
G01Y433883D02*
X173030D01*
X171238Y432341D01*
Y434425D01*
G01X170530Y436983D02*
X173030D01*
X171238Y435441D01*
Y437525D01*
G01X170530Y440083D02*
X173030D01*
X171238Y438541D01*
Y440625D01*
G01X193800Y464700D02*
X197100D01*
G01X184200Y464400D02*
X188700D01*
G01X188200Y480396D02*
Y477896D01*
G01X189158Y480396D02*
X187242D01*
G01X185933Y477896D02*
Y480396D01*
X184933D01*
X184600Y480271D01*
X184350Y479979D01*
X184267Y479646D01*
X184350Y479313D01*
X184558Y479063D01*
X184933Y478938D01*
X185933D01*
G01X182000Y477896D02*
Y480396D01*
X182500Y479896D01*
G01Y477896D02*
X181500D01*
G01X179817Y478271D02*
X179567Y478063D01*
X179275Y477938D01*
X178900Y477896D01*
X178525Y477979D01*
X178233Y478146D01*
X178025Y478438D01*
X177983Y478771D01*
X178067Y479104D01*
X178275Y479313D01*
X178567Y479479D01*
X178858Y479521D01*
X179150Y479479D01*
X179525Y479313D01*
X179400Y480396D01*
X178275D01*
G01X176717Y478271D02*
X176467Y478063D01*
X176175Y477938D01*
X175800Y477896D01*
X175425Y477979D01*
X175133Y478146D01*
X174925Y478438D01*
X174883Y478771D01*
X174967Y479104D01*
X175175Y479313D01*
X175467Y479479D01*
X175758Y479521D01*
X176050Y479479D01*
X176425Y479313D01*
X176300Y480396D01*
X175175D01*
G01X185700Y476883D02*
Y474383D01*
G01X186658Y476883D02*
X184742D01*
G01X183433Y474383D02*
Y476883D01*
X182433D01*
X182100Y476758D01*
X181850Y476466D01*
X181767Y476133D01*
X181850Y475800D01*
X182058Y475550D01*
X182433Y475425D01*
X183433D01*
G01X180292Y476466D02*
X180042Y476716D01*
X179750Y476841D01*
X179417Y476883D01*
X179000Y476800D01*
X178708Y476591D01*
X178625Y476341D01*
X178667Y476091D01*
X178833Y475883D01*
X179667Y475466D01*
X180042Y475175D01*
X180292Y474758D01*
X180375Y474383D01*
X178625D01*
G01X176400D02*
Y476883D01*
X176900Y476383D01*
G01Y474383D02*
X175900D01*
G01X174092Y475425D02*
X173800Y475716D01*
X173550Y475883D01*
X173217Y475966D01*
X172925Y475883D01*
X172717Y475716D01*
X172550Y475466D01*
X172508Y475175D01*
X172550Y474925D01*
X172717Y474675D01*
X172967Y474466D01*
X173258Y474383D01*
X173592Y474466D01*
X173883Y474716D01*
X174050Y475091D01*
X174092Y475508D01*
X174008Y476050D01*
X173883Y476341D01*
X173675Y476633D01*
X173383Y476841D01*
X173092Y476883D01*
X172800Y476800D01*
X172592Y476591D01*
G01X170367Y474450D02*
X167867D01*
G01X170367Y473492D02*
Y475408D01*
G01X167867Y476717D02*
X170367D01*
Y477717D01*
X170242Y478050D01*
X169950Y478300D01*
X169617Y478383D01*
X169284Y478300D01*
X169034Y478092D01*
X168909Y477717D01*
Y476717D01*
G01X168159Y479942D02*
X167950Y480233D01*
X167867Y480567D01*
X167950Y480900D01*
X168200Y481192D01*
X168575Y481400D01*
X168950Y481483D01*
X169409D01*
X169784Y481400D01*
X170117Y481192D01*
X170284Y480942D01*
X170367Y480650D01*
X170284Y480317D01*
X170117Y480067D01*
X169867Y479900D01*
X169534Y479817D01*
X169242Y479900D01*
X168950Y480108D01*
X168784Y480358D01*
X168742Y480650D01*
X168825Y480983D01*
X169034Y481233D01*
X169409Y481483D01*
G01X168367Y482833D02*
X168075Y483083D01*
X167909Y483417D01*
X167867Y483792D01*
X167909Y484125D01*
X168117Y484458D01*
X168367Y484667D01*
X168617Y484708D01*
X168909Y484625D01*
X169117Y484333D01*
X169200Y484042D01*
Y483667D01*
G01Y484042D02*
X169325Y484292D01*
X169534Y484500D01*
X169784Y484583D01*
X170034Y484500D01*
X170242Y484292D01*
X170367Y483917D01*
X170325Y483542D01*
X170159Y483167D01*
G01X183500Y463200D02*
X187500D01*
Y455800D01*
G01X195800Y449200D02*
X199800D01*
Y441800D01*
G01X195650Y453122D02*
X191650D01*
Y460522D01*
G01Y453122D02*
X187650D01*
Y460522D01*
G01X195700Y460035D02*
X199700D01*
Y452635D01*
G01X171930Y455685D02*
X174430D01*
Y456726D01*
X174305Y457060D01*
X174138Y457268D01*
X173805Y457351D01*
X173472Y457268D01*
X173263Y457018D01*
X173138Y456726D01*
Y455685D01*
G01Y456726D02*
X171930Y457351D01*
G01X172305Y458701D02*
X172097Y458951D01*
X171972Y459243D01*
X171930Y459618D01*
X172013Y459993D01*
X172180Y460285D01*
X172472Y460493D01*
X172805Y460535D01*
X173138Y460451D01*
X173347Y460243D01*
X173513Y459951D01*
X173555Y459660D01*
X173513Y459368D01*
X173347Y458993D01*
X174430Y459118D01*
Y460243D01*
G01X172430Y461801D02*
X172138Y462051D01*
X171972Y462385D01*
X171930Y462760D01*
X171972Y463093D01*
X172180Y463426D01*
X172430Y463635D01*
X172680Y463676D01*
X172972Y463593D01*
X173180Y463301D01*
X173263Y463010D01*
Y462635D01*
G01Y463010D02*
X173388Y463260D01*
X173597Y463468D01*
X173847Y463551D01*
X174097Y463468D01*
X174305Y463260D01*
X174430Y462885D01*
X174388Y462510D01*
X174222Y462135D01*
G01X171930Y465735D02*
X172472Y465818D01*
X172930Y465943D01*
X173347Y466110D01*
X173805Y466318D01*
X174430Y466651D01*
Y464985D01*
G01X175500Y463200D02*
X179500D01*
Y455800D01*
G01X196200Y498090D02*
Y495590D01*
G01X197158Y498090D02*
X195242D01*
G01X193933Y495590D02*
Y498090D01*
X192933D01*
X192600Y497965D01*
X192350Y497673D01*
X192267Y497340D01*
X192350Y497007D01*
X192558Y496757D01*
X192933Y496632D01*
X193933D01*
G01X190000Y495590D02*
Y498090D01*
X190500Y497590D01*
G01Y495590D02*
X189500D01*
G01X186983D02*
X186900Y496132D01*
X186775Y496590D01*
X186608Y497007D01*
X186400Y497465D01*
X186067Y498090D01*
X187733D01*
G01X184508Y495882D02*
X184217Y495673D01*
X183883Y495590D01*
X183550Y495673D01*
X183258Y495923D01*
X183050Y496298D01*
X182967Y496673D01*
Y497132D01*
X183050Y497507D01*
X183258Y497840D01*
X183508Y498007D01*
X183800Y498090D01*
X184133Y498007D01*
X184383Y497840D01*
X184550Y497590D01*
X184633Y497257D01*
X184550Y496965D01*
X184342Y496673D01*
X184092Y496507D01*
X183800Y496465D01*
X183467Y496548D01*
X183217Y496757D01*
X182967Y497132D01*
G01X202200Y491189D02*
Y488689D01*
G01X203158Y491189D02*
X201242D01*
G01X199933Y488689D02*
Y491189D01*
X198933D01*
X198600Y491064D01*
X198350Y490772D01*
X198267Y490439D01*
X198350Y490106D01*
X198558Y489856D01*
X198933Y489731D01*
X199933D01*
G01X196000Y488689D02*
Y491189D01*
X196500Y490689D01*
G01Y488689D02*
X195500D01*
G01X192900D02*
X192608Y488731D01*
X192275Y488856D01*
X192067Y489064D01*
X191983Y489356D01*
X192067Y489647D01*
X192317Y489897D01*
X192692Y490022D01*
X193108D01*
X193358Y490106D01*
X193567Y490314D01*
X193650Y490606D01*
X193525Y490897D01*
X193233Y491106D01*
X192900Y491189D01*
X192567Y491106D01*
X192275Y490897D01*
X192150Y490606D01*
X192233Y490314D01*
X192442Y490106D01*
X192692Y490022D01*
X193108D01*
X193483Y489897D01*
X193733Y489647D01*
X193817Y489356D01*
X193733Y489064D01*
X193525Y488856D01*
X193192Y488731D01*
X192900Y488689D01*
G01X189800Y491189D02*
X190133Y491106D01*
X190383Y490897D01*
X190550Y490647D01*
X190675Y490314D01*
X190717Y489939D01*
X190675Y489564D01*
X190550Y489231D01*
X190383Y488981D01*
X190133Y488772D01*
X189800Y488689D01*
X189467Y488772D01*
X189217Y488981D01*
X189050Y489231D01*
X188925Y489564D01*
X188883Y489939D01*
X188925Y490314D01*
X189050Y490647D01*
X189217Y490897D01*
X189467Y491106D01*
X189800Y491189D01*
G01X194584Y515272D02*
X194834Y515397D01*
X195126Y515480D01*
X195459D01*
X195834Y515355D01*
X196126Y515147D01*
X196334Y514897D01*
X196501Y514480D01*
X196543Y514105D01*
X196459Y513730D01*
X196334Y513480D01*
X196084Y513230D01*
X195793Y513063D01*
X195501Y512980D01*
X195209D01*
X194918Y513063D01*
X194668Y513188D01*
X194459Y513355D01*
G01X193193Y515063D02*
X192943Y515313D01*
X192651Y515438D01*
X192318Y515480D01*
X191901Y515397D01*
X191609Y515188D01*
X191526Y514938D01*
X191568Y514688D01*
X191734Y514480D01*
X192568Y514063D01*
X192943Y513772D01*
X193193Y513355D01*
X193276Y512980D01*
X191526D01*
G01X189301Y515480D02*
X189634Y515397D01*
X189884Y515188D01*
X190051Y514938D01*
X190176Y514605D01*
X190218Y514230D01*
X190176Y513855D01*
X190051Y513522D01*
X189884Y513272D01*
X189634Y513063D01*
X189301Y512980D01*
X188968Y513063D01*
X188718Y513272D01*
X188551Y513522D01*
X188426Y513855D01*
X188384Y514230D01*
X188426Y514605D01*
X188551Y514938D01*
X188718Y515188D01*
X188968Y515397D01*
X189301Y515480D01*
G01X186993Y514022D02*
X186701Y514313D01*
X186451Y514480D01*
X186118Y514563D01*
X185826Y514480D01*
X185618Y514313D01*
X185451Y514063D01*
X185409Y513772D01*
X185451Y513522D01*
X185618Y513272D01*
X185868Y513063D01*
X186159Y512980D01*
X186493Y513063D01*
X186784Y513313D01*
X186951Y513688D01*
X186993Y514105D01*
X186909Y514647D01*
X186784Y514938D01*
X186576Y515230D01*
X186284Y515438D01*
X185993Y515480D01*
X185701Y515397D01*
X185493Y515188D01*
G01X181463Y494429D02*
X181713Y494554D01*
X182005Y494637D01*
X182338D01*
X182713Y494512D01*
X183005Y494304D01*
X183213Y494054D01*
X183380Y493637D01*
X183422Y493262D01*
X183338Y492887D01*
X183213Y492637D01*
X182963Y492387D01*
X182672Y492220D01*
X182380Y492137D01*
X182088D01*
X181797Y492220D01*
X181547Y492345D01*
X181338Y492512D01*
G01X180072Y494220D02*
X179822Y494470D01*
X179530Y494595D01*
X179197Y494637D01*
X178780Y494554D01*
X178488Y494345D01*
X178405Y494095D01*
X178447Y493845D01*
X178613Y493637D01*
X179447Y493220D01*
X179822Y492929D01*
X180072Y492512D01*
X180155Y492137D01*
X178405D01*
G01X176180Y494637D02*
X176513Y494554D01*
X176763Y494345D01*
X176930Y494095D01*
X177055Y493762D01*
X177097Y493387D01*
X177055Y493012D01*
X176930Y492679D01*
X176763Y492429D01*
X176513Y492220D01*
X176180Y492137D01*
X175847Y492220D01*
X175597Y492429D01*
X175430Y492679D01*
X175305Y493012D01*
X175263Y493387D01*
X175305Y493762D01*
X175430Y494095D01*
X175597Y494345D01*
X175847Y494554D01*
X176180Y494637D01*
G01X173080Y492137D02*
X172788Y492179D01*
X172455Y492304D01*
X172247Y492512D01*
X172163Y492804D01*
X172247Y493095D01*
X172497Y493345D01*
X172872Y493470D01*
X173288D01*
X173538Y493554D01*
X173747Y493762D01*
X173830Y494054D01*
X173705Y494345D01*
X173413Y494554D01*
X173080Y494637D01*
X172747Y494554D01*
X172455Y494345D01*
X172330Y494054D01*
X172413Y493762D01*
X172622Y493554D01*
X172872Y493470D01*
X173288D01*
X173663Y493345D01*
X173913Y493095D01*
X173997Y492804D01*
X173913Y492512D01*
X173705Y492304D01*
X173372Y492179D01*
X173080Y492137D01*
G01X175733Y487953D02*
X175983Y488078D01*
X176275Y488161D01*
X176608D01*
X176983Y488036D01*
X177275Y487828D01*
X177483Y487578D01*
X177650Y487161D01*
X177692Y486786D01*
X177608Y486411D01*
X177483Y486161D01*
X177233Y485911D01*
X176942Y485744D01*
X176650Y485661D01*
X176358D01*
X176067Y485744D01*
X175817Y485869D01*
X175608Y486036D01*
G01X174342Y487744D02*
X174092Y487994D01*
X173800Y488119D01*
X173467Y488161D01*
X173050Y488078D01*
X172758Y487869D01*
X172675Y487619D01*
X172717Y487369D01*
X172883Y487161D01*
X173717Y486744D01*
X174092Y486453D01*
X174342Y486036D01*
X174425Y485661D01*
X172675D01*
G01X170450D02*
Y488161D01*
X170950Y487661D01*
G01Y485661D02*
X169950D01*
G01X168267Y486036D02*
X168017Y485828D01*
X167725Y485703D01*
X167350Y485661D01*
X166975Y485744D01*
X166683Y485911D01*
X166475Y486203D01*
X166433Y486536D01*
X166517Y486869D01*
X166725Y487078D01*
X167017Y487244D01*
X167308Y487286D01*
X167600Y487244D01*
X167975Y487078D01*
X167850Y488161D01*
X166725D01*
G01X186100Y523067D02*
Y520567D01*
G01X187058Y523067D02*
X185142D01*
G01X183833Y520567D02*
Y523067D01*
X182833D01*
X182500Y522942D01*
X182250Y522650D01*
X182167Y522317D01*
X182250Y521984D01*
X182458Y521734D01*
X182833Y521609D01*
X183833D01*
G01X180817Y521067D02*
X180567Y520775D01*
X180233Y520609D01*
X179858Y520567D01*
X179525Y520609D01*
X179192Y520817D01*
X178983Y521067D01*
X178942Y521317D01*
X179025Y521609D01*
X179317Y521817D01*
X179608Y521900D01*
X179983D01*
G01X179608D02*
X179358Y522025D01*
X179150Y522234D01*
X179067Y522484D01*
X179150Y522734D01*
X179358Y522942D01*
X179733Y523067D01*
X180108Y523025D01*
X180483Y522859D01*
G01X176800Y520567D02*
Y523067D01*
X177300Y522567D01*
G01Y520567D02*
X176300D01*
G01X173783D02*
X173700Y521109D01*
X173575Y521567D01*
X173408Y521984D01*
X173200Y522442D01*
X172867Y523067D01*
X174533D01*
G01X183299Y535699D02*
Y533199D01*
G01X184257Y535699D02*
X182341D01*
G01X181032Y533199D02*
Y535699D01*
X180032D01*
X179699Y535574D01*
X179449Y535282D01*
X179366Y534949D01*
X179449Y534616D01*
X179657Y534366D01*
X180032Y534241D01*
X181032D01*
G01X178016Y533699D02*
X177766Y533407D01*
X177432Y533241D01*
X177057Y533199D01*
X176724Y533241D01*
X176391Y533449D01*
X176182Y533699D01*
X176141Y533949D01*
X176224Y534241D01*
X176516Y534449D01*
X176807Y534532D01*
X177182D01*
G01X176807D02*
X176557Y534657D01*
X176349Y534866D01*
X176266Y535116D01*
X176349Y535366D01*
X176557Y535574D01*
X176932Y535699D01*
X177307Y535657D01*
X177682Y535491D01*
G01X173999Y533199D02*
Y535699D01*
X174499Y535199D01*
G01Y533199D02*
X173499D01*
G01X170899D02*
X170607Y533241D01*
X170274Y533366D01*
X170066Y533574D01*
X169982Y533866D01*
X170066Y534157D01*
X170316Y534407D01*
X170691Y534532D01*
X171107D01*
X171357Y534616D01*
X171566Y534824D01*
X171649Y535116D01*
X171524Y535407D01*
X171232Y535616D01*
X170899Y535699D01*
X170566Y535616D01*
X170274Y535407D01*
X170149Y535116D01*
X170232Y534824D01*
X170441Y534616D01*
X170691Y534532D01*
X171107D01*
X171482Y534407D01*
X171732Y534157D01*
X171816Y533866D01*
X171732Y533574D01*
X171524Y533366D01*
X171191Y533241D01*
X170899Y533199D01*
G01X198615Y526955D02*
Y529455D01*
X197574D01*
X197240Y529330D01*
X197032Y529163D01*
X196949Y528830D01*
X197032Y528497D01*
X197282Y528288D01*
X197574Y528163D01*
X198615D01*
G01X197574D02*
X196949Y526955D01*
G01X194182D02*
Y529455D01*
X195724Y527663D01*
X193640D01*
G01X192374Y527997D02*
X192082Y528288D01*
X191832Y528455D01*
X191499Y528538D01*
X191207Y528455D01*
X190999Y528288D01*
X190832Y528038D01*
X190790Y527747D01*
X190832Y527497D01*
X190999Y527247D01*
X191249Y527038D01*
X191540Y526955D01*
X191874Y527038D01*
X192165Y527288D01*
X192332Y527663D01*
X192374Y528080D01*
X192290Y528622D01*
X192165Y528913D01*
X191957Y529205D01*
X191665Y529413D01*
X191374Y529455D01*
X191082Y529372D01*
X190874Y529163D01*
G01X189190Y527247D02*
X188899Y527038D01*
X188565Y526955D01*
X188232Y527038D01*
X187940Y527288D01*
X187732Y527663D01*
X187649Y528038D01*
Y528497D01*
X187732Y528872D01*
X187940Y529205D01*
X188190Y529372D01*
X188482Y529455D01*
X188815Y529372D01*
X189065Y529205D01*
X189232Y528955D01*
X189315Y528622D01*
X189232Y528330D01*
X189024Y528038D01*
X188774Y527872D01*
X188482Y527830D01*
X188149Y527913D01*
X187899Y528122D01*
X187649Y528497D01*
G01X198571Y530759D02*
Y533259D01*
X197530D01*
X197196Y533134D01*
X196988Y532967D01*
X196905Y532634D01*
X196988Y532301D01*
X197238Y532092D01*
X197530Y531967D01*
X198571D01*
G01X197530D02*
X196905Y530759D01*
G01X195555Y531134D02*
X195305Y530926D01*
X195013Y530801D01*
X194638Y530759D01*
X194263Y530842D01*
X193971Y531009D01*
X193763Y531301D01*
X193721Y531634D01*
X193805Y531967D01*
X194013Y532176D01*
X194305Y532342D01*
X194596Y532384D01*
X194888Y532342D01*
X195263Y532176D01*
X195138Y533259D01*
X194013D01*
G01X192455Y531259D02*
X192205Y530967D01*
X191871Y530801D01*
X191496Y530759D01*
X191163Y530801D01*
X190830Y531009D01*
X190621Y531259D01*
X190580Y531509D01*
X190663Y531801D01*
X190955Y532009D01*
X191246Y532092D01*
X191621D01*
G01X191246D02*
X190996Y532217D01*
X190788Y532426D01*
X190705Y532676D01*
X190788Y532926D01*
X190996Y533134D01*
X191371Y533259D01*
X191746Y533217D01*
X192121Y533051D01*
G01X188438Y533259D02*
X188771Y533176D01*
X189021Y532967D01*
X189188Y532717D01*
X189313Y532384D01*
X189355Y532009D01*
X189313Y531634D01*
X189188Y531301D01*
X189021Y531051D01*
X188771Y530842D01*
X188438Y530759D01*
X188105Y530842D01*
X187855Y531051D01*
X187688Y531301D01*
X187563Y531634D01*
X187521Y532009D01*
X187563Y532384D01*
X187688Y532717D01*
X187855Y532967D01*
X188105Y533176D01*
X188438Y533259D01*
G01X202242Y539137D02*
Y541637D01*
X201201D01*
X200867Y541512D01*
X200659Y541345D01*
X200576Y541012D01*
X200659Y540679D01*
X200909Y540470D01*
X201201Y540345D01*
X202242D01*
G01X201201D02*
X200576Y539137D01*
G01X199226Y539512D02*
X198976Y539304D01*
X198684Y539179D01*
X198309Y539137D01*
X197934Y539220D01*
X197642Y539387D01*
X197434Y539679D01*
X197392Y540012D01*
X197476Y540345D01*
X197684Y540554D01*
X197976Y540720D01*
X198267Y540762D01*
X198559Y540720D01*
X198934Y540554D01*
X198809Y541637D01*
X197684D01*
G01X196126Y539637D02*
X195876Y539345D01*
X195542Y539179D01*
X195167Y539137D01*
X194834Y539179D01*
X194501Y539387D01*
X194292Y539637D01*
X194251Y539887D01*
X194334Y540179D01*
X194626Y540387D01*
X194917Y540470D01*
X195292D01*
G01X194917D02*
X194667Y540595D01*
X194459Y540804D01*
X194376Y541054D01*
X194459Y541304D01*
X194667Y541512D01*
X195042Y541637D01*
X195417Y541595D01*
X195792Y541429D01*
G01X191609Y539137D02*
Y541637D01*
X193151Y539845D01*
X191067D01*
G01X202330Y535118D02*
Y537618D01*
X201289D01*
X200955Y537493D01*
X200747Y537326D01*
X200664Y536993D01*
X200747Y536660D01*
X200997Y536451D01*
X201289Y536326D01*
X202330D01*
G01X201289D02*
X200664Y535118D01*
G01X199314Y535493D02*
X199064Y535285D01*
X198772Y535160D01*
X198397Y535118D01*
X198022Y535201D01*
X197730Y535368D01*
X197522Y535660D01*
X197480Y535993D01*
X197564Y536326D01*
X197772Y536535D01*
X198064Y536701D01*
X198355Y536743D01*
X198647Y536701D01*
X199022Y536535D01*
X198897Y537618D01*
X197772D01*
G01X196214Y535618D02*
X195964Y535326D01*
X195630Y535160D01*
X195255Y535118D01*
X194922Y535160D01*
X194589Y535368D01*
X194380Y535618D01*
X194339Y535868D01*
X194422Y536160D01*
X194714Y536368D01*
X195005Y536451D01*
X195380D01*
G01X195005D02*
X194755Y536576D01*
X194547Y536785D01*
X194464Y537035D01*
X194547Y537285D01*
X194755Y537493D01*
X195130Y537618D01*
X195505Y537576D01*
X195880Y537410D01*
G01X193114Y535618D02*
X192864Y535326D01*
X192530Y535160D01*
X192155Y535118D01*
X191822Y535160D01*
X191489Y535368D01*
X191280Y535618D01*
X191239Y535868D01*
X191322Y536160D01*
X191614Y536368D01*
X191905Y536451D01*
X192280D01*
G01X191905D02*
X191655Y536576D01*
X191447Y536785D01*
X191364Y537035D01*
X191447Y537285D01*
X191655Y537493D01*
X192030Y537618D01*
X192405Y537576D01*
X192780Y537410D01*
G01X187912Y543322D02*
X190412D01*
Y544363D01*
X190287Y544697D01*
X190120Y544905D01*
X189787Y544988D01*
X189454Y544905D01*
X189245Y544655D01*
X189120Y544363D01*
Y543322D01*
G01Y544363D02*
X187912Y544988D01*
G01X188412Y546338D02*
X188120Y546588D01*
X187954Y546922D01*
X187912Y547297D01*
X187954Y547630D01*
X188162Y547963D01*
X188412Y548172D01*
X188662Y548213D01*
X188954Y548130D01*
X189162Y547838D01*
X189245Y547547D01*
Y547172D01*
G01Y547547D02*
X189370Y547797D01*
X189579Y548005D01*
X189829Y548088D01*
X190079Y548005D01*
X190287Y547797D01*
X190412Y547422D01*
X190370Y547047D01*
X190204Y546672D01*
G01X190412Y550355D02*
X190329Y550022D01*
X190120Y549772D01*
X189870Y549605D01*
X189537Y549480D01*
X189162Y549438D01*
X188787Y549480D01*
X188454Y549605D01*
X188204Y549772D01*
X187995Y550022D01*
X187912Y550355D01*
X187995Y550688D01*
X188204Y550938D01*
X188454Y551105D01*
X188787Y551230D01*
X189162Y551272D01*
X189537Y551230D01*
X189870Y551105D01*
X190120Y550938D01*
X190329Y550688D01*
X190412Y550355D01*
G01X187912Y553455D02*
X187954Y553747D01*
X188079Y554080D01*
X188287Y554288D01*
X188579Y554372D01*
X188870Y554288D01*
X189120Y554038D01*
X189245Y553663D01*
Y553247D01*
X189329Y552997D01*
X189537Y552788D01*
X189829Y552705D01*
X190120Y552830D01*
X190329Y553122D01*
X190412Y553455D01*
X190329Y553788D01*
X190120Y554080D01*
X189829Y554205D01*
X189537Y554122D01*
X189329Y553913D01*
X189245Y553663D01*
Y553247D01*
X189120Y552872D01*
X188870Y552622D01*
X188579Y552538D01*
X188287Y552622D01*
X188079Y552830D01*
X187954Y553163D01*
X187912Y553455D01*
G01X182500Y550700D02*
X186500D01*
Y543300D01*
G01X201283Y520567D02*
Y523067D01*
X200242D01*
X199908Y522942D01*
X199700Y522775D01*
X199617Y522442D01*
X199700Y522109D01*
X199950Y521900D01*
X200242Y521775D01*
X201283D01*
G01X200242D02*
X199617Y520567D01*
G01X198267Y521067D02*
X198017Y520775D01*
X197683Y520609D01*
X197308Y520567D01*
X196975Y520609D01*
X196642Y520817D01*
X196433Y521067D01*
X196392Y521317D01*
X196475Y521609D01*
X196767Y521817D01*
X197058Y521900D01*
X197433D01*
G01X197058D02*
X196808Y522025D01*
X196600Y522234D01*
X196517Y522484D01*
X196600Y522734D01*
X196808Y522942D01*
X197183Y523067D01*
X197558Y523025D01*
X197933Y522859D01*
G01X195167Y521067D02*
X194917Y520775D01*
X194583Y520609D01*
X194208Y520567D01*
X193875Y520609D01*
X193542Y520817D01*
X193333Y521067D01*
X193292Y521317D01*
X193375Y521609D01*
X193667Y521817D01*
X193958Y521900D01*
X194333D01*
G01X193958D02*
X193708Y522025D01*
X193500Y522234D01*
X193417Y522484D01*
X193500Y522734D01*
X193708Y522942D01*
X194083Y523067D01*
X194458Y523025D01*
X194833Y522859D01*
G01X191233Y520567D02*
X191150Y521109D01*
X191025Y521567D01*
X190858Y521984D01*
X190650Y522442D01*
X190317Y523067D01*
X191983D01*
G01X176300Y515500D02*
Y519500D01*
X183700D01*
G01X194230Y519165D02*
X194480Y519290D01*
X194772Y519373D01*
X195105D01*
X195480Y519248D01*
X195772Y519040D01*
X195980Y518790D01*
X196147Y518373D01*
X196189Y517998D01*
X196105Y517623D01*
X195980Y517373D01*
X195730Y517123D01*
X195439Y516956D01*
X195147Y516873D01*
X194855D01*
X194564Y516956D01*
X194314Y517081D01*
X194105Y517248D01*
G01X192839Y518956D02*
X192589Y519206D01*
X192297Y519331D01*
X191964Y519373D01*
X191547Y519290D01*
X191255Y519081D01*
X191172Y518831D01*
X191214Y518581D01*
X191380Y518373D01*
X192214Y517956D01*
X192589Y517665D01*
X192839Y517248D01*
X192922Y516873D01*
X191172D01*
G01X188947D02*
Y519373D01*
X189447Y518873D01*
G01Y516873D02*
X188447D01*
G01X185347D02*
Y519373D01*
X186889Y517581D01*
X184805D01*
G01X189955Y558957D02*
Y556457D01*
G01X190913Y558957D02*
X188997D01*
G01X187688Y556457D02*
Y558957D01*
X186688D01*
X186355Y558832D01*
X186105Y558540D01*
X186022Y558207D01*
X186105Y557874D01*
X186313Y557624D01*
X186688Y557499D01*
X187688D01*
G01X184672Y556957D02*
X184422Y556665D01*
X184088Y556499D01*
X183713Y556457D01*
X183380Y556499D01*
X183047Y556707D01*
X182838Y556957D01*
X182797Y557207D01*
X182880Y557499D01*
X183172Y557707D01*
X183463Y557790D01*
X183838D01*
G01X183463D02*
X183213Y557915D01*
X183005Y558124D01*
X182922Y558374D01*
X183005Y558624D01*
X183213Y558832D01*
X183588Y558957D01*
X183963Y558915D01*
X184338Y558749D01*
G01X180655Y556457D02*
Y558957D01*
X181155Y558457D01*
G01Y556457D02*
X180155D01*
G01X178263Y556749D02*
X177972Y556540D01*
X177638Y556457D01*
X177305Y556540D01*
X177013Y556790D01*
X176805Y557165D01*
X176722Y557540D01*
Y557999D01*
X176805Y558374D01*
X177013Y558707D01*
X177263Y558874D01*
X177555Y558957D01*
X177888Y558874D01*
X178138Y558707D01*
X178305Y558457D01*
X178388Y558124D01*
X178305Y557832D01*
X178097Y557540D01*
X177847Y557374D01*
X177555Y557332D01*
X177222Y557415D01*
X176972Y557624D01*
X176722Y557999D01*
G01X190043Y562540D02*
Y560040D01*
G01X191001Y562540D02*
X189085D01*
G01X187776Y560040D02*
Y562540D01*
X186776D01*
X186443Y562415D01*
X186193Y562123D01*
X186110Y561790D01*
X186193Y561457D01*
X186401Y561207D01*
X186776Y561082D01*
X187776D01*
G01X184635Y562123D02*
X184385Y562373D01*
X184093Y562498D01*
X183760Y562540D01*
X183343Y562457D01*
X183051Y562248D01*
X182968Y561998D01*
X183010Y561748D01*
X183176Y561540D01*
X184010Y561123D01*
X184385Y560832D01*
X184635Y560415D01*
X184718Y560040D01*
X182968D01*
G01X181535Y562123D02*
X181285Y562373D01*
X180993Y562498D01*
X180660Y562540D01*
X180243Y562457D01*
X179951Y562248D01*
X179868Y561998D01*
X179910Y561748D01*
X180076Y561540D01*
X180910Y561123D01*
X181285Y560832D01*
X181535Y560415D01*
X181618Y560040D01*
X179868D01*
G01X177643D02*
X177351Y560082D01*
X177018Y560207D01*
X176810Y560415D01*
X176726Y560707D01*
X176810Y560998D01*
X177060Y561248D01*
X177435Y561373D01*
X177851D01*
X178101Y561457D01*
X178310Y561665D01*
X178393Y561957D01*
X178268Y562248D01*
X177976Y562457D01*
X177643Y562540D01*
X177310Y562457D01*
X177018Y562248D01*
X176893Y561957D01*
X176976Y561665D01*
X177185Y561457D01*
X177435Y561373D01*
X177851D01*
X178226Y561248D01*
X178476Y560998D01*
X178560Y560707D01*
X178476Y560415D01*
X178268Y560207D01*
X177935Y560082D01*
X177643Y560040D01*
G01X196005Y579346D02*
X195797Y579679D01*
X195672Y580054D01*
Y580388D01*
X195797Y580721D01*
X196005Y580971D01*
X196297Y581096D01*
X196589Y581013D01*
X196839Y580804D01*
X197005Y580429D01*
X197089Y579929D01*
X197255Y579638D01*
X197547Y579513D01*
X197839Y579596D01*
X198047Y579804D01*
X198172Y580096D01*
Y580388D01*
X198089Y580679D01*
X197880Y580929D01*
G01X195672Y582488D02*
X198172D01*
Y583529D01*
X198047Y583863D01*
X197880Y584071D01*
X197547Y584154D01*
X197214Y584071D01*
X197005Y583821D01*
X196880Y583529D01*
Y582488D01*
G01Y583529D02*
X195672Y584154D01*
G01Y586421D02*
X195714Y586713D01*
X195839Y587046D01*
X196047Y587254D01*
X196339Y587338D01*
X196630Y587254D01*
X196880Y587004D01*
X197005Y586629D01*
Y586213D01*
X197089Y585963D01*
X197297Y585754D01*
X197589Y585671D01*
X197880Y585796D01*
X198089Y586088D01*
X198172Y586421D01*
X198089Y586754D01*
X197880Y587046D01*
X197589Y587171D01*
X197297Y587088D01*
X197089Y586879D01*
X197005Y586629D01*
Y586213D01*
X196880Y585838D01*
X196630Y585588D01*
X196339Y585504D01*
X196047Y585588D01*
X195839Y585796D01*
X195714Y586129D01*
X195672Y586421D01*
G01Y590021D02*
X198172D01*
X196380Y588479D01*
Y590563D01*
G01X195672Y592538D02*
X196214Y592621D01*
X196672Y592746D01*
X197089Y592913D01*
X197547Y593121D01*
X198172Y593454D01*
Y591788D01*
G01X199500Y568800D02*
X195500D01*
Y576200D01*
G01X193500Y579300D02*
X189500D01*
Y586700D01*
G01X190302Y587731D02*
X192802D01*
Y588772D01*
X192677Y589106D01*
X192510Y589314D01*
X192177Y589397D01*
X191844Y589314D01*
X191635Y589064D01*
X191510Y588772D01*
Y587731D01*
G01Y588772D02*
X190302Y589397D01*
G01Y591664D02*
X192802D01*
X192302Y591164D01*
G01X190302D02*
Y592164D01*
G01X190677Y593847D02*
X190469Y594097D01*
X190344Y594389D01*
X190302Y594764D01*
X190385Y595139D01*
X190552Y595431D01*
X190844Y595639D01*
X191177Y595681D01*
X191510Y595597D01*
X191719Y595389D01*
X191885Y595097D01*
X191927Y594806D01*
X191885Y594514D01*
X191719Y594139D01*
X192802Y594264D01*
Y595389D01*
G01X190677Y596947D02*
X190469Y597197D01*
X190344Y597489D01*
X190302Y597864D01*
X190385Y598239D01*
X190552Y598531D01*
X190844Y598739D01*
X191177Y598781D01*
X191510Y598697D01*
X191719Y598489D01*
X191885Y598197D01*
X191927Y597906D01*
X191885Y597614D01*
X191719Y597239D01*
X192802Y597364D01*
Y598489D01*
G01X188161Y709517D02*
X190661D01*
Y710558D01*
X190536Y710892D01*
X190369Y711100D01*
X190036Y711183D01*
X189703Y711100D01*
X189494Y710850D01*
X189369Y710558D01*
Y709517D01*
G01Y710558D02*
X188161Y711183D01*
G01X188453Y712742D02*
X188244Y713033D01*
X188161Y713367D01*
X188244Y713700D01*
X188494Y713992D01*
X188869Y714200D01*
X189244Y714283D01*
X189703D01*
X190078Y714200D01*
X190411Y713992D01*
X190578Y713742D01*
X190661Y713450D01*
X190578Y713117D01*
X190411Y712867D01*
X190161Y712700D01*
X189828Y712617D01*
X189536Y712700D01*
X189244Y712908D01*
X189078Y713158D01*
X189036Y713450D01*
X189119Y713783D01*
X189328Y714033D01*
X189703Y714283D01*
G01X190661Y716550D02*
X190578Y716217D01*
X190369Y715967D01*
X190119Y715800D01*
X189786Y715675D01*
X189411Y715633D01*
X189036Y715675D01*
X188703Y715800D01*
X188453Y715967D01*
X188244Y716217D01*
X188161Y716550D01*
X188244Y716883D01*
X188453Y717133D01*
X188703Y717300D01*
X189036Y717425D01*
X189411Y717467D01*
X189786Y717425D01*
X190119Y717300D01*
X190369Y717133D01*
X190578Y716883D01*
X190661Y716550D01*
G01X190244Y718858D02*
X190494Y719108D01*
X190619Y719400D01*
X190661Y719733D01*
X190578Y720150D01*
X190369Y720442D01*
X190119Y720525D01*
X189869Y720483D01*
X189661Y720317D01*
X189244Y719483D01*
X188953Y719108D01*
X188536Y718858D01*
X188161Y718775D01*
Y720525D01*
G01X201500Y710800D02*
X197500D01*
Y718200D01*
G01X192161Y709517D02*
X194661D01*
Y710558D01*
X194536Y710892D01*
X194369Y711100D01*
X194036Y711183D01*
X193703Y711100D01*
X193494Y710850D01*
X193369Y710558D01*
Y709517D01*
G01Y710558D02*
X192161Y711183D01*
G01X192453Y712742D02*
X192244Y713033D01*
X192161Y713367D01*
X192244Y713700D01*
X192494Y713992D01*
X192869Y714200D01*
X193244Y714283D01*
X193703D01*
X194078Y714200D01*
X194411Y713992D01*
X194578Y713742D01*
X194661Y713450D01*
X194578Y713117D01*
X194411Y712867D01*
X194161Y712700D01*
X193828Y712617D01*
X193536Y712700D01*
X193244Y712908D01*
X193078Y713158D01*
X193036Y713450D01*
X193119Y713783D01*
X193328Y714033D01*
X193703Y714283D01*
G01X194661Y716550D02*
X194578Y716217D01*
X194369Y715967D01*
X194119Y715800D01*
X193786Y715675D01*
X193411Y715633D01*
X193036Y715675D01*
X192703Y715800D01*
X192453Y715967D01*
X192244Y716217D01*
X192161Y716550D01*
X192244Y716883D01*
X192453Y717133D01*
X192703Y717300D01*
X193036Y717425D01*
X193411Y717467D01*
X193786Y717425D01*
X194119Y717300D01*
X194369Y717133D01*
X194578Y716883D01*
X194661Y716550D01*
G01X192161Y719650D02*
X194661D01*
X194161Y719150D01*
G01X192161D02*
Y720150D01*
G01X179461Y732817D02*
X181961D01*
Y733858D01*
X181836Y734192D01*
X181669Y734400D01*
X181336Y734483D01*
X181003Y734400D01*
X180794Y734150D01*
X180669Y733858D01*
Y732817D01*
G01Y733858D02*
X179461Y734483D01*
G01Y736750D02*
X179503Y737042D01*
X179628Y737375D01*
X179836Y737583D01*
X180128Y737667D01*
X180419Y737583D01*
X180669Y737333D01*
X180794Y736958D01*
Y736542D01*
X180878Y736292D01*
X181086Y736083D01*
X181378Y736000D01*
X181669Y736125D01*
X181878Y736417D01*
X181961Y736750D01*
X181878Y737083D01*
X181669Y737375D01*
X181378Y737500D01*
X181086Y737417D01*
X180878Y737208D01*
X180794Y736958D01*
Y736542D01*
X180669Y736167D01*
X180419Y735917D01*
X180128Y735833D01*
X179836Y735917D01*
X179628Y736125D01*
X179503Y736458D01*
X179461Y736750D01*
G01Y739767D02*
X180003Y739850D01*
X180461Y739975D01*
X180878Y740142D01*
X181336Y740350D01*
X181961Y740683D01*
Y739017D01*
G01Y742950D02*
X181878Y742617D01*
X181669Y742367D01*
X181419Y742200D01*
X181086Y742075D01*
X180711Y742033D01*
X180336Y742075D01*
X180003Y742200D01*
X179753Y742367D01*
X179544Y742617D01*
X179461Y742950D01*
X179544Y743283D01*
X179753Y743533D01*
X180003Y743700D01*
X180336Y743825D01*
X180711Y743867D01*
X181086Y743825D01*
X181419Y743700D01*
X181669Y743533D01*
X181878Y743283D01*
X181961Y742950D01*
G01X173300Y734100D02*
X169300D01*
Y741500D01*
G01X175461Y732817D02*
X177961D01*
Y733858D01*
X177836Y734192D01*
X177669Y734400D01*
X177336Y734483D01*
X177003Y734400D01*
X176794Y734150D01*
X176669Y733858D01*
Y732817D01*
G01Y733858D02*
X175461Y734483D01*
G01Y736750D02*
X175503Y737042D01*
X175628Y737375D01*
X175836Y737583D01*
X176128Y737667D01*
X176419Y737583D01*
X176669Y737333D01*
X176794Y736958D01*
Y736542D01*
X176878Y736292D01*
X177086Y736083D01*
X177378Y736000D01*
X177669Y736125D01*
X177878Y736417D01*
X177961Y736750D01*
X177878Y737083D01*
X177669Y737375D01*
X177378Y737500D01*
X177086Y737417D01*
X176878Y737208D01*
X176794Y736958D01*
Y736542D01*
X176669Y736167D01*
X176419Y735917D01*
X176128Y735833D01*
X175836Y735917D01*
X175628Y736125D01*
X175503Y736458D01*
X175461Y736750D01*
G01X176503Y739058D02*
X176794Y739350D01*
X176961Y739600D01*
X177044Y739933D01*
X176961Y740225D01*
X176794Y740433D01*
X176544Y740600D01*
X176253Y740642D01*
X176003Y740600D01*
X175753Y740433D01*
X175544Y740183D01*
X175461Y739892D01*
X175544Y739558D01*
X175794Y739267D01*
X176169Y739100D01*
X176586Y739058D01*
X177128Y739142D01*
X177419Y739267D01*
X177711Y739475D01*
X177919Y739767D01*
X177961Y740058D01*
X177878Y740350D01*
X177669Y740558D01*
G01X175753Y742242D02*
X175544Y742533D01*
X175461Y742867D01*
X175544Y743200D01*
X175794Y743492D01*
X176169Y743700D01*
X176544Y743783D01*
X177003D01*
X177378Y743700D01*
X177711Y743492D01*
X177878Y743242D01*
X177961Y742950D01*
X177878Y742617D01*
X177711Y742367D01*
X177461Y742200D01*
X177128Y742117D01*
X176836Y742200D01*
X176544Y742408D01*
X176378Y742658D01*
X176336Y742950D01*
X176419Y743283D01*
X176628Y743533D01*
X177003Y743783D01*
G01X169300Y734100D02*
X165300D01*
Y741500D01*
G01X188661Y765017D02*
X191161D01*
Y766058D01*
X191036Y766392D01*
X190869Y766600D01*
X190536Y766683D01*
X190203Y766600D01*
X189994Y766350D01*
X189869Y766058D01*
Y765017D01*
G01Y766058D02*
X188661Y766683D01*
G01Y768950D02*
X188703Y769242D01*
X188828Y769575D01*
X189036Y769783D01*
X189328Y769867D01*
X189619Y769783D01*
X189869Y769533D01*
X189994Y769158D01*
Y768742D01*
X190078Y768492D01*
X190286Y768283D01*
X190578Y768200D01*
X190869Y768325D01*
X191078Y768617D01*
X191161Y768950D01*
X191078Y769283D01*
X190869Y769575D01*
X190578Y769700D01*
X190286Y769617D01*
X190078Y769408D01*
X189994Y769158D01*
Y768742D01*
X189869Y768367D01*
X189619Y768117D01*
X189328Y768033D01*
X189036Y768117D01*
X188828Y768325D01*
X188703Y768658D01*
X188661Y768950D01*
G01X188953Y771342D02*
X188744Y771633D01*
X188661Y771967D01*
X188744Y772300D01*
X188994Y772592D01*
X189369Y772800D01*
X189744Y772883D01*
X190203D01*
X190578Y772800D01*
X190911Y772592D01*
X191078Y772342D01*
X191161Y772050D01*
X191078Y771717D01*
X190911Y771467D01*
X190661Y771300D01*
X190328Y771217D01*
X190036Y771300D01*
X189744Y771508D01*
X189578Y771758D01*
X189536Y772050D01*
X189619Y772383D01*
X189828Y772633D01*
X190203Y772883D01*
G01X190744Y774358D02*
X190994Y774608D01*
X191119Y774900D01*
X191161Y775233D01*
X191078Y775650D01*
X190869Y775942D01*
X190619Y776025D01*
X190369Y775983D01*
X190161Y775817D01*
X189744Y774983D01*
X189453Y774608D01*
X189036Y774358D01*
X188661Y774275D01*
Y776025D01*
G01X201500Y766300D02*
X197500D01*
Y773700D01*
G01X192661Y765017D02*
X195161D01*
Y766058D01*
X195036Y766392D01*
X194869Y766600D01*
X194536Y766683D01*
X194203Y766600D01*
X193994Y766350D01*
X193869Y766058D01*
Y765017D01*
G01Y766058D02*
X192661Y766683D01*
G01Y768950D02*
X192703Y769242D01*
X192828Y769575D01*
X193036Y769783D01*
X193328Y769867D01*
X193619Y769783D01*
X193869Y769533D01*
X193994Y769158D01*
Y768742D01*
X194078Y768492D01*
X194286Y768283D01*
X194578Y768200D01*
X194869Y768325D01*
X195078Y768617D01*
X195161Y768950D01*
X195078Y769283D01*
X194869Y769575D01*
X194578Y769700D01*
X194286Y769617D01*
X194078Y769408D01*
X193994Y769158D01*
Y768742D01*
X193869Y768367D01*
X193619Y768117D01*
X193328Y768033D01*
X193036Y768117D01*
X192828Y768325D01*
X192703Y768658D01*
X192661Y768950D01*
G01X192953Y771342D02*
X192744Y771633D01*
X192661Y771967D01*
X192744Y772300D01*
X192994Y772592D01*
X193369Y772800D01*
X193744Y772883D01*
X194203D01*
X194578Y772800D01*
X194911Y772592D01*
X195078Y772342D01*
X195161Y772050D01*
X195078Y771717D01*
X194911Y771467D01*
X194661Y771300D01*
X194328Y771217D01*
X194036Y771300D01*
X193744Y771508D01*
X193578Y771758D01*
X193536Y772050D01*
X193619Y772383D01*
X193828Y772633D01*
X194203Y772883D01*
G01X192661Y775150D02*
X195161D01*
X194661Y774650D01*
G01X192661D02*
Y775650D01*
G01X172161Y788517D02*
X174661D01*
Y789558D01*
X174536Y789892D01*
X174369Y790100D01*
X174036Y790183D01*
X173703Y790100D01*
X173494Y789850D01*
X173369Y789558D01*
Y788517D01*
G01Y789558D02*
X172161Y790183D01*
G01Y792450D02*
X172203Y792742D01*
X172328Y793075D01*
X172536Y793283D01*
X172828Y793367D01*
X173119Y793283D01*
X173369Y793033D01*
X173494Y792658D01*
Y792242D01*
X173578Y791992D01*
X173786Y791783D01*
X174078Y791700D01*
X174369Y791825D01*
X174578Y792117D01*
X174661Y792450D01*
X174578Y792783D01*
X174369Y793075D01*
X174078Y793200D01*
X173786Y793117D01*
X173578Y792908D01*
X173494Y792658D01*
Y792242D01*
X173369Y791867D01*
X173119Y791617D01*
X172828Y791533D01*
X172536Y791617D01*
X172328Y791825D01*
X172203Y792158D01*
X172161Y792450D01*
G01Y795550D02*
X172203Y795842D01*
X172328Y796175D01*
X172536Y796383D01*
X172828Y796467D01*
X173119Y796383D01*
X173369Y796133D01*
X173494Y795758D01*
Y795342D01*
X173578Y795092D01*
X173786Y794883D01*
X174078Y794800D01*
X174369Y794925D01*
X174578Y795217D01*
X174661Y795550D01*
X174578Y795883D01*
X174369Y796175D01*
X174078Y796300D01*
X173786Y796217D01*
X173578Y796008D01*
X173494Y795758D01*
Y795342D01*
X173369Y794967D01*
X173119Y794717D01*
X172828Y794633D01*
X172536Y794717D01*
X172328Y794925D01*
X172203Y795258D01*
X172161Y795550D01*
G01X174244Y797858D02*
X174494Y798108D01*
X174619Y798400D01*
X174661Y798733D01*
X174578Y799150D01*
X174369Y799442D01*
X174119Y799525D01*
X173869Y799483D01*
X173661Y799317D01*
X173244Y798483D01*
X172953Y798108D01*
X172536Y797858D01*
X172161Y797775D01*
Y799525D01*
G01X168161Y788517D02*
X170661D01*
Y789558D01*
X170536Y789892D01*
X170369Y790100D01*
X170036Y790183D01*
X169703Y790100D01*
X169494Y789850D01*
X169369Y789558D01*
Y788517D01*
G01Y789558D02*
X168161Y790183D01*
G01Y792450D02*
X168203Y792742D01*
X168328Y793075D01*
X168536Y793283D01*
X168828Y793367D01*
X169119Y793283D01*
X169369Y793033D01*
X169494Y792658D01*
Y792242D01*
X169578Y791992D01*
X169786Y791783D01*
X170078Y791700D01*
X170369Y791825D01*
X170578Y792117D01*
X170661Y792450D01*
X170578Y792783D01*
X170369Y793075D01*
X170078Y793200D01*
X169786Y793117D01*
X169578Y792908D01*
X169494Y792658D01*
Y792242D01*
X169369Y791867D01*
X169119Y791617D01*
X168828Y791533D01*
X168536Y791617D01*
X168328Y791825D01*
X168203Y792158D01*
X168161Y792450D01*
G01Y795550D02*
X168203Y795842D01*
X168328Y796175D01*
X168536Y796383D01*
X168828Y796467D01*
X169119Y796383D01*
X169369Y796133D01*
X169494Y795758D01*
Y795342D01*
X169578Y795092D01*
X169786Y794883D01*
X170078Y794800D01*
X170369Y794925D01*
X170578Y795217D01*
X170661Y795550D01*
X170578Y795883D01*
X170369Y796175D01*
X170078Y796300D01*
X169786Y796217D01*
X169578Y796008D01*
X169494Y795758D01*
Y795342D01*
X169369Y794967D01*
X169119Y794717D01*
X168828Y794633D01*
X168536Y794717D01*
X168328Y794925D01*
X168203Y795258D01*
X168161Y795550D01*
G01Y798650D02*
X170661D01*
X170161Y798150D01*
G01X168161D02*
Y799150D01*
G01X231500Y106517D02*
X234000D01*
Y107558D01*
X233875Y107892D01*
X233708Y108100D01*
X233375Y108183D01*
X233042Y108100D01*
X232833Y107850D01*
X232708Y107558D01*
Y106517D01*
G01Y107558D02*
X231500Y108183D01*
G01Y110367D02*
X232042Y110450D01*
X232500Y110575D01*
X232917Y110742D01*
X233375Y110950D01*
X234000Y111283D01*
Y109617D01*
G01Y113550D02*
X233917Y113217D01*
X233708Y112967D01*
X233458Y112800D01*
X233125Y112675D01*
X232750Y112633D01*
X232375Y112675D01*
X232042Y112800D01*
X231792Y112967D01*
X231583Y113217D01*
X231500Y113550D01*
X231583Y113883D01*
X231792Y114133D01*
X232042Y114300D01*
X232375Y114425D01*
X232750Y114467D01*
X233125Y114425D01*
X233458Y114300D01*
X233708Y114133D01*
X233917Y113883D01*
X234000Y113550D01*
G01X231500Y116650D02*
X234000D01*
X233500Y116150D01*
G01X231500D02*
Y117150D01*
G01X230600Y104000D02*
X234600D01*
Y96600D01*
G01X219661Y140517D02*
X222161D01*
Y141517D01*
X222036Y141850D01*
X221744Y142100D01*
X221411Y142183D01*
X221078Y142100D01*
X220828Y141892D01*
X220703Y141517D01*
Y140517D01*
G01X221953Y145367D02*
X222078Y145117D01*
X222161Y144825D01*
Y144492D01*
X222036Y144117D01*
X221828Y143825D01*
X221578Y143617D01*
X221161Y143450D01*
X220786Y143408D01*
X220411Y143492D01*
X220161Y143617D01*
X219911Y143867D01*
X219744Y144158D01*
X219661Y144450D01*
Y144742D01*
X219744Y145033D01*
X219869Y145283D01*
X220036Y145492D01*
G01X221744Y146758D02*
X221994Y147008D01*
X222119Y147300D01*
X222161Y147633D01*
X222078Y148050D01*
X221869Y148342D01*
X221619Y148425D01*
X221369Y148383D01*
X221161Y148217D01*
X220744Y147383D01*
X220453Y147008D01*
X220036Y146758D01*
X219661Y146675D01*
Y148425D01*
G01X220703Y149858D02*
X220994Y150150D01*
X221161Y150400D01*
X221244Y150733D01*
X221161Y151025D01*
X220994Y151233D01*
X220744Y151400D01*
X220453Y151442D01*
X220203Y151400D01*
X219953Y151233D01*
X219744Y150983D01*
X219661Y150692D01*
X219744Y150358D01*
X219994Y150067D01*
X220369Y149900D01*
X220786Y149858D01*
X221328Y149942D01*
X221619Y150067D01*
X221911Y150275D01*
X222119Y150567D01*
X222161Y150858D01*
X222078Y151150D01*
X221869Y151358D01*
G01X221161Y127017D02*
X223661D01*
Y128017D01*
X223536Y128350D01*
X223244Y128600D01*
X222911Y128683D01*
X222578Y128600D01*
X222328Y128392D01*
X222203Y128017D01*
Y127017D01*
G01X221161Y130117D02*
X223661D01*
Y131158D01*
X223536Y131492D01*
X223369Y131700D01*
X223036Y131783D01*
X222703Y131700D01*
X222494Y131450D01*
X222369Y131158D01*
Y130117D01*
G01Y131158D02*
X221161Y131783D01*
G01X221661Y133133D02*
X221369Y133383D01*
X221203Y133717D01*
X221161Y134092D01*
X221203Y134425D01*
X221411Y134758D01*
X221661Y134967D01*
X221911Y135008D01*
X222203Y134925D01*
X222411Y134633D01*
X222494Y134342D01*
Y133967D01*
G01Y134342D02*
X222619Y134592D01*
X222828Y134800D01*
X223078Y134883D01*
X223328Y134800D01*
X223536Y134592D01*
X223661Y134217D01*
X223619Y133842D01*
X223453Y133467D01*
G01X223661Y137150D02*
X223578Y136817D01*
X223369Y136567D01*
X223119Y136400D01*
X222786Y136275D01*
X222411Y136233D01*
X222036Y136275D01*
X221703Y136400D01*
X221453Y136567D01*
X221244Y136817D01*
X221161Y137150D01*
X221244Y137483D01*
X221453Y137733D01*
X221703Y137900D01*
X222036Y138025D01*
X222411Y138067D01*
X222786Y138025D01*
X223119Y137900D01*
X223369Y137733D01*
X223578Y137483D01*
X223661Y137150D01*
G01X229161Y127017D02*
X231661D01*
Y128017D01*
X231536Y128350D01*
X231244Y128600D01*
X230911Y128683D01*
X230578Y128600D01*
X230328Y128392D01*
X230203Y128017D01*
Y127017D01*
G01X229161Y130117D02*
X231661D01*
Y131158D01*
X231536Y131492D01*
X231369Y131700D01*
X231036Y131783D01*
X230703Y131700D01*
X230494Y131450D01*
X230369Y131158D01*
Y130117D01*
G01Y131158D02*
X229161Y131783D01*
G01X229661Y133133D02*
X229369Y133383D01*
X229203Y133717D01*
X229161Y134092D01*
X229203Y134425D01*
X229411Y134758D01*
X229661Y134967D01*
X229911Y135008D01*
X230203Y134925D01*
X230411Y134633D01*
X230494Y134342D01*
Y133967D01*
G01Y134342D02*
X230619Y134592D01*
X230828Y134800D01*
X231078Y134883D01*
X231328Y134800D01*
X231536Y134592D01*
X231661Y134217D01*
X231619Y133842D01*
X231453Y133467D01*
G01X229536Y136233D02*
X229328Y136483D01*
X229203Y136775D01*
X229161Y137150D01*
X229244Y137525D01*
X229411Y137817D01*
X229703Y138025D01*
X230036Y138067D01*
X230369Y137983D01*
X230578Y137775D01*
X230744Y137483D01*
X230786Y137192D01*
X230744Y136900D01*
X230578Y136525D01*
X231661Y136650D01*
Y137775D01*
G01X225161Y127017D02*
X227661D01*
Y128017D01*
X227536Y128350D01*
X227244Y128600D01*
X226911Y128683D01*
X226578Y128600D01*
X226328Y128392D01*
X226203Y128017D01*
Y127017D01*
G01X225161Y130117D02*
X227661D01*
Y131158D01*
X227536Y131492D01*
X227369Y131700D01*
X227036Y131783D01*
X226703Y131700D01*
X226494Y131450D01*
X226369Y131158D01*
Y130117D01*
G01Y131158D02*
X225161Y131783D01*
G01X225661Y133133D02*
X225369Y133383D01*
X225203Y133717D01*
X225161Y134092D01*
X225203Y134425D01*
X225411Y134758D01*
X225661Y134967D01*
X225911Y135008D01*
X226203Y134925D01*
X226411Y134633D01*
X226494Y134342D01*
Y133967D01*
G01Y134342D02*
X226619Y134592D01*
X226828Y134800D01*
X227078Y134883D01*
X227328Y134800D01*
X227536Y134592D01*
X227661Y134217D01*
X227619Y133842D01*
X227453Y133467D01*
G01X225161Y137150D02*
X227661D01*
X227161Y136650D01*
G01X225161D02*
Y137650D01*
G01X219861Y154517D02*
X222361D01*
Y155517D01*
X222236Y155850D01*
X221944Y156100D01*
X221611Y156183D01*
X221278Y156100D01*
X221028Y155892D01*
X220903Y155517D01*
Y154517D01*
G01X219861Y157617D02*
X222361D01*
Y158658D01*
X222236Y158992D01*
X222069Y159200D01*
X221736Y159283D01*
X221403Y159200D01*
X221194Y158950D01*
X221069Y158658D01*
Y157617D01*
G01Y158658D02*
X219861Y159283D01*
G01Y161550D02*
X222361D01*
X221861Y161050D01*
G01X219861D02*
Y162050D01*
G01X220153Y163942D02*
X219944Y164233D01*
X219861Y164567D01*
X219944Y164900D01*
X220194Y165192D01*
X220569Y165400D01*
X220944Y165483D01*
X221403D01*
X221778Y165400D01*
X222111Y165192D01*
X222278Y164942D01*
X222361Y164650D01*
X222278Y164317D01*
X222111Y164067D01*
X221861Y163900D01*
X221528Y163817D01*
X221236Y163900D01*
X220944Y164108D01*
X220778Y164358D01*
X220736Y164650D01*
X220819Y164983D01*
X221028Y165233D01*
X221403Y165483D01*
G01X239383Y182300D02*
Y184800D01*
X238383D01*
X238050Y184675D01*
X237800Y184383D01*
X237717Y184050D01*
X237800Y183717D01*
X238008Y183467D01*
X238383Y183342D01*
X239383D01*
G01X234533Y184592D02*
X234783Y184717D01*
X235075Y184800D01*
X235408D01*
X235783Y184675D01*
X236075Y184467D01*
X236283Y184217D01*
X236450Y183800D01*
X236492Y183425D01*
X236408Y183050D01*
X236283Y182800D01*
X236033Y182550D01*
X235742Y182383D01*
X235450Y182300D01*
X235158D01*
X234867Y182383D01*
X234617Y182508D01*
X234408Y182675D01*
G01X233142Y184383D02*
X232892Y184633D01*
X232600Y184758D01*
X232267Y184800D01*
X231850Y184717D01*
X231558Y184508D01*
X231475Y184258D01*
X231517Y184008D01*
X231683Y183800D01*
X232517Y183383D01*
X232892Y183092D01*
X233142Y182675D01*
X233225Y182300D01*
X231475D01*
G01X230042Y184383D02*
X229792Y184633D01*
X229500Y184758D01*
X229167Y184800D01*
X228750Y184717D01*
X228458Y184508D01*
X228375Y184258D01*
X228417Y184008D01*
X228583Y183800D01*
X229417Y183383D01*
X229792Y183092D01*
X230042Y182675D01*
X230125Y182300D01*
X228375D01*
G01X239383Y178100D02*
Y180600D01*
X238383D01*
X238050Y180475D01*
X237800Y180183D01*
X237717Y179850D01*
X237800Y179517D01*
X238008Y179267D01*
X238383Y179142D01*
X239383D01*
G01X234533Y180392D02*
X234783Y180517D01*
X235075Y180600D01*
X235408D01*
X235783Y180475D01*
X236075Y180267D01*
X236283Y180017D01*
X236450Y179600D01*
X236492Y179225D01*
X236408Y178850D01*
X236283Y178600D01*
X236033Y178350D01*
X235742Y178183D01*
X235450Y178100D01*
X235158D01*
X234867Y178183D01*
X234617Y178308D01*
X234408Y178475D01*
G01X233142Y180183D02*
X232892Y180433D01*
X232600Y180558D01*
X232267Y180600D01*
X231850Y180517D01*
X231558Y180308D01*
X231475Y180058D01*
X231517Y179808D01*
X231683Y179600D01*
X232517Y179183D01*
X232892Y178892D01*
X233142Y178475D01*
X233225Y178100D01*
X231475D01*
G01X230167Y178600D02*
X229917Y178308D01*
X229583Y178142D01*
X229208Y178100D01*
X228875Y178142D01*
X228542Y178350D01*
X228333Y178600D01*
X228292Y178850D01*
X228375Y179142D01*
X228667Y179350D01*
X228958Y179433D01*
X229333D01*
G01X228958D02*
X228708Y179558D01*
X228500Y179767D01*
X228417Y180017D01*
X228500Y180267D01*
X228708Y180475D01*
X229083Y180600D01*
X229458Y180558D01*
X229833Y180392D01*
G01X219110Y198154D02*
X221610D01*
Y199195D01*
X221485Y199529D01*
X221318Y199737D01*
X220985Y199820D01*
X220652Y199737D01*
X220443Y199487D01*
X220318Y199195D01*
Y198154D01*
G01Y199195D02*
X219110Y199820D01*
G01X220152Y201295D02*
X220443Y201587D01*
X220610Y201837D01*
X220693Y202170D01*
X220610Y202462D01*
X220443Y202670D01*
X220193Y202837D01*
X219902Y202879D01*
X219652Y202837D01*
X219402Y202670D01*
X219193Y202420D01*
X219110Y202129D01*
X219193Y201795D01*
X219443Y201504D01*
X219818Y201337D01*
X220235Y201295D01*
X220777Y201379D01*
X221068Y201504D01*
X221360Y201712D01*
X221568Y202004D01*
X221610Y202295D01*
X221527Y202587D01*
X221318Y202795D01*
G01X219110Y205187D02*
X219152Y205479D01*
X219277Y205812D01*
X219485Y206020D01*
X219777Y206104D01*
X220068Y206020D01*
X220318Y205770D01*
X220443Y205395D01*
Y204979D01*
X220527Y204729D01*
X220735Y204520D01*
X221027Y204437D01*
X221318Y204562D01*
X221527Y204854D01*
X221610Y205187D01*
X221527Y205520D01*
X221318Y205812D01*
X221027Y205937D01*
X220735Y205854D01*
X220527Y205645D01*
X220443Y205395D01*
Y204979D01*
X220318Y204604D01*
X220068Y204354D01*
X219777Y204270D01*
X219485Y204354D01*
X219277Y204562D01*
X219152Y204895D01*
X219110Y205187D01*
G01X220152Y207495D02*
X220443Y207787D01*
X220610Y208037D01*
X220693Y208370D01*
X220610Y208662D01*
X220443Y208870D01*
X220193Y209037D01*
X219902Y209079D01*
X219652Y209037D01*
X219402Y208870D01*
X219193Y208620D01*
X219110Y208329D01*
X219193Y207995D01*
X219443Y207704D01*
X219818Y207537D01*
X220235Y207495D01*
X220777Y207579D01*
X221068Y207704D01*
X221360Y207912D01*
X221568Y208204D01*
X221610Y208495D01*
X221527Y208787D01*
X221318Y208995D01*
G01X208086Y206800D02*
X212086D01*
Y199400D01*
G01X215600Y198154D02*
X218100D01*
Y199195D01*
X217975Y199529D01*
X217808Y199737D01*
X217475Y199820D01*
X217142Y199737D01*
X216933Y199487D01*
X216808Y199195D01*
Y198154D01*
G01Y199195D02*
X215600Y199820D01*
G01X216642Y201295D02*
X216933Y201587D01*
X217100Y201837D01*
X217183Y202170D01*
X217100Y202462D01*
X216933Y202670D01*
X216683Y202837D01*
X216392Y202879D01*
X216142Y202837D01*
X215892Y202670D01*
X215683Y202420D01*
X215600Y202129D01*
X215683Y201795D01*
X215933Y201504D01*
X216308Y201337D01*
X216725Y201295D01*
X217267Y201379D01*
X217558Y201504D01*
X217850Y201712D01*
X218058Y202004D01*
X218100Y202295D01*
X218017Y202587D01*
X217808Y202795D01*
G01X215600Y205687D02*
X218100D01*
X216308Y204145D01*
Y206229D01*
G01X215892Y207579D02*
X215683Y207870D01*
X215600Y208204D01*
X215683Y208537D01*
X215933Y208829D01*
X216308Y209037D01*
X216683Y209120D01*
X217142D01*
X217517Y209037D01*
X217850Y208829D01*
X218017Y208579D01*
X218100Y208287D01*
X218017Y207954D01*
X217850Y207704D01*
X217600Y207537D01*
X217267Y207454D01*
X216975Y207537D01*
X216683Y207745D01*
X216517Y207995D01*
X216475Y208287D01*
X216558Y208620D01*
X216767Y208870D01*
X217142Y209120D01*
G01X204076Y206800D02*
X208076D01*
Y199400D01*
G01X211777Y401298D02*
Y399506D01*
X211610Y399131D01*
X211277Y398881D01*
X210860Y398798D01*
X210443Y398881D01*
X210110Y399131D01*
X209943Y399506D01*
Y401298D01*
G01X208677Y399298D02*
X208427Y399006D01*
X208093Y398840D01*
X207718Y398798D01*
X207385Y398840D01*
X207052Y399048D01*
X206843Y399298D01*
X206802Y399548D01*
X206885Y399840D01*
X207177Y400048D01*
X207468Y400131D01*
X207843D01*
G01X207468D02*
X207218Y400256D01*
X207010Y400465D01*
X206927Y400715D01*
X207010Y400965D01*
X207218Y401173D01*
X207593Y401298D01*
X207968Y401256D01*
X208343Y401090D01*
G01X205368Y399090D02*
X205077Y398881D01*
X204743Y398798D01*
X204410Y398881D01*
X204118Y399131D01*
X203910Y399506D01*
X203827Y399881D01*
Y400340D01*
X203910Y400715D01*
X204118Y401048D01*
X204368Y401215D01*
X204660Y401298D01*
X204993Y401215D01*
X205243Y401048D01*
X205410Y400798D01*
X205493Y400465D01*
X205410Y400173D01*
X205202Y399881D01*
X204952Y399715D01*
X204660Y399673D01*
X204327Y399756D01*
X204077Y399965D01*
X203827Y400340D01*
G01X220922Y414400D02*
Y412608D01*
X220755Y412233D01*
X220422Y411983D01*
X220005Y411900D01*
X219588Y411983D01*
X219255Y412233D01*
X219088Y412608D01*
Y414400D01*
G01X217822Y412400D02*
X217572Y412108D01*
X217238Y411942D01*
X216863Y411900D01*
X216530Y411942D01*
X216197Y412150D01*
X215988Y412400D01*
X215947Y412650D01*
X216030Y412942D01*
X216322Y413150D01*
X216613Y413233D01*
X216988D01*
G01X216613D02*
X216363Y413358D01*
X216155Y413567D01*
X216072Y413817D01*
X216155Y414067D01*
X216363Y414275D01*
X216738Y414400D01*
X217113Y414358D01*
X217488Y414192D01*
G01X214597Y413983D02*
X214347Y414233D01*
X214055Y414358D01*
X213722Y414400D01*
X213305Y414317D01*
X213013Y414108D01*
X212930Y413858D01*
X212972Y413608D01*
X213138Y413400D01*
X213972Y412983D01*
X214347Y412692D01*
X214597Y412275D01*
X214680Y411900D01*
X212930D01*
G01X211959Y393425D02*
Y395925D01*
X210918D01*
X210584Y395800D01*
X210376Y395633D01*
X210293Y395300D01*
X210376Y394967D01*
X210626Y394758D01*
X210918Y394633D01*
X211959D01*
G01X210918D02*
X210293Y393425D01*
G01X208818Y394467D02*
X208526Y394758D01*
X208276Y394925D01*
X207943Y395008D01*
X207651Y394925D01*
X207443Y394758D01*
X207276Y394508D01*
X207234Y394217D01*
X207276Y393967D01*
X207443Y393717D01*
X207693Y393508D01*
X207984Y393425D01*
X208318Y393508D01*
X208609Y393758D01*
X208776Y394133D01*
X208818Y394550D01*
X208734Y395092D01*
X208609Y395383D01*
X208401Y395675D01*
X208109Y395883D01*
X207818Y395925D01*
X207526Y395842D01*
X207318Y395633D01*
G01X205718Y394467D02*
X205426Y394758D01*
X205176Y394925D01*
X204843Y395008D01*
X204551Y394925D01*
X204343Y394758D01*
X204176Y394508D01*
X204134Y394217D01*
X204176Y393967D01*
X204343Y393717D01*
X204593Y393508D01*
X204884Y393425D01*
X205218Y393508D01*
X205509Y393758D01*
X205676Y394133D01*
X205718Y394550D01*
X205634Y395092D01*
X205509Y395383D01*
X205301Y395675D01*
X205009Y395883D01*
X204718Y395925D01*
X204426Y395842D01*
X204218Y395633D01*
G01X213741Y394348D02*
X216241D01*
Y395389D01*
X216116Y395723D01*
X215949Y395931D01*
X215616Y396014D01*
X215283Y395931D01*
X215074Y395681D01*
X214949Y395389D01*
Y394348D01*
G01Y395389D02*
X213741Y396014D01*
G01X214241Y397364D02*
X213949Y397614D01*
X213783Y397948D01*
X213741Y398323D01*
X213783Y398656D01*
X213991Y398989D01*
X214241Y399198D01*
X214491Y399239D01*
X214783Y399156D01*
X214991Y398864D01*
X215074Y398573D01*
Y398198D01*
G01Y398573D02*
X215199Y398823D01*
X215408Y399031D01*
X215658Y399114D01*
X215908Y399031D01*
X216116Y398823D01*
X216241Y398448D01*
X216199Y398073D01*
X216033Y397698D01*
G01X214241Y400464D02*
X213949Y400714D01*
X213783Y401048D01*
X213741Y401423D01*
X213783Y401756D01*
X213991Y402089D01*
X214241Y402298D01*
X214491Y402339D01*
X214783Y402256D01*
X214991Y401964D01*
X215074Y401673D01*
Y401298D01*
G01Y401673D02*
X215199Y401923D01*
X215408Y402131D01*
X215658Y402214D01*
X215908Y402131D01*
X216116Y401923D01*
X216241Y401548D01*
X216199Y401173D01*
X216033Y400798D01*
G01X213741Y404481D02*
X216241D01*
X215741Y403981D01*
G01X213741D02*
Y404981D01*
G01X220859Y407743D02*
Y410243D01*
X219818D01*
X219484Y410118D01*
X219276Y409951D01*
X219193Y409618D01*
X219276Y409285D01*
X219526Y409076D01*
X219818Y408951D01*
X220859D01*
G01X219818D02*
X219193Y407743D01*
G01X217843Y408118D02*
X217593Y407910D01*
X217301Y407785D01*
X216926Y407743D01*
X216551Y407826D01*
X216259Y407993D01*
X216051Y408285D01*
X216009Y408618D01*
X216093Y408951D01*
X216301Y409160D01*
X216593Y409326D01*
X216884Y409368D01*
X217176Y409326D01*
X217551Y409160D01*
X217426Y410243D01*
X216301D01*
G01X214618Y409826D02*
X214368Y410076D01*
X214076Y410201D01*
X213743Y410243D01*
X213326Y410160D01*
X213034Y409951D01*
X212951Y409701D01*
X212993Y409451D01*
X213159Y409243D01*
X213993Y408826D01*
X214368Y408535D01*
X214618Y408118D01*
X214701Y407743D01*
X212951D01*
G01X208563Y407611D02*
X211063D01*
Y408652D01*
X210938Y408986D01*
X210771Y409194D01*
X210438Y409277D01*
X210105Y409194D01*
X209896Y408944D01*
X209771Y408652D01*
Y407611D01*
G01Y408652D02*
X208563Y409277D01*
G01X209063Y410627D02*
X208771Y410877D01*
X208605Y411211D01*
X208563Y411586D01*
X208605Y411919D01*
X208813Y412252D01*
X209063Y412461D01*
X209313Y412502D01*
X209605Y412419D01*
X209813Y412127D01*
X209896Y411836D01*
Y411461D01*
G01Y411836D02*
X210021Y412086D01*
X210230Y412294D01*
X210480Y412377D01*
X210730Y412294D01*
X210938Y412086D01*
X211063Y411711D01*
X211021Y411336D01*
X210855Y410961D01*
G01X210646Y413852D02*
X210896Y414102D01*
X211021Y414394D01*
X211063Y414727D01*
X210980Y415144D01*
X210771Y415436D01*
X210521Y415519D01*
X210271Y415477D01*
X210063Y415311D01*
X209646Y414477D01*
X209355Y414102D01*
X208938Y413852D01*
X208563Y413769D01*
Y415519D01*
G01X208938Y416827D02*
X208730Y417077D01*
X208605Y417369D01*
X208563Y417744D01*
X208646Y418119D01*
X208813Y418411D01*
X209105Y418619D01*
X209438Y418661D01*
X209771Y418577D01*
X209980Y418369D01*
X210146Y418077D01*
X210188Y417786D01*
X210146Y417494D01*
X209980Y417119D01*
X211063Y417244D01*
Y418369D01*
G01X211573Y403121D02*
Y405621D01*
X210532D01*
X210198Y405496D01*
X209990Y405329D01*
X209907Y404996D01*
X209990Y404663D01*
X210240Y404454D01*
X210532Y404329D01*
X211573D01*
G01X210532D02*
X209907Y403121D01*
G01X208432Y404163D02*
X208140Y404454D01*
X207890Y404621D01*
X207557Y404704D01*
X207265Y404621D01*
X207057Y404454D01*
X206890Y404204D01*
X206848Y403913D01*
X206890Y403663D01*
X207057Y403413D01*
X207307Y403204D01*
X207598Y403121D01*
X207932Y403204D01*
X208223Y403454D01*
X208390Y403829D01*
X208432Y404246D01*
X208348Y404788D01*
X208223Y405079D01*
X208015Y405371D01*
X207723Y405579D01*
X207432Y405621D01*
X207140Y405538D01*
X206932Y405329D01*
G01X204623Y403121D02*
X204540Y403663D01*
X204415Y404121D01*
X204248Y404538D01*
X204040Y404996D01*
X203707Y405621D01*
X205373D01*
G01X204938Y439545D02*
X218338D01*
G01D02*
Y428145D01*
G01D02*
X204938D01*
G01D02*
Y439545D01*
G01X220741Y415730D02*
Y418230D01*
X219700D01*
X219366Y418105D01*
X219158Y417938D01*
X219075Y417605D01*
X219158Y417272D01*
X219408Y417063D01*
X219700Y416938D01*
X220741D01*
G01X219700D02*
X219075Y415730D01*
G01X216308D02*
Y418230D01*
X217850Y416438D01*
X215766D01*
G01X213708Y418230D02*
X214041Y418147D01*
X214291Y417938D01*
X214458Y417688D01*
X214583Y417355D01*
X214625Y416980D01*
X214583Y416605D01*
X214458Y416272D01*
X214291Y416022D01*
X214041Y415813D01*
X213708Y415730D01*
X213375Y415813D01*
X213125Y416022D01*
X212958Y416272D01*
X212833Y416605D01*
X212791Y416980D01*
X212833Y417355D01*
X212958Y417688D01*
X213125Y417938D01*
X213375Y418147D01*
X213708Y418230D01*
G01X208938Y439845D02*
Y443845D01*
X216338D01*
G01X205838Y423445D02*
Y427445D01*
X213238D01*
G01X200638Y439545D02*
X204638D01*
Y432145D01*
G01X231088Y416282D02*
X233588D01*
Y417323D01*
X233463Y417657D01*
X233296Y417865D01*
X232963Y417948D01*
X232630Y417865D01*
X232421Y417615D01*
X232296Y417323D01*
Y416282D01*
G01Y417323D02*
X231088Y417948D01*
G01X231588Y419298D02*
X231296Y419548D01*
X231130Y419882D01*
X231088Y420257D01*
X231130Y420590D01*
X231338Y420923D01*
X231588Y421132D01*
X231838Y421173D01*
X232130Y421090D01*
X232338Y420798D01*
X232421Y420507D01*
Y420132D01*
G01Y420507D02*
X232546Y420757D01*
X232755Y420965D01*
X233005Y421048D01*
X233255Y420965D01*
X233463Y420757D01*
X233588Y420382D01*
X233546Y420007D01*
X233380Y419632D01*
G01X233171Y422523D02*
X233421Y422773D01*
X233546Y423065D01*
X233588Y423398D01*
X233505Y423815D01*
X233296Y424107D01*
X233046Y424190D01*
X232796Y424148D01*
X232588Y423982D01*
X232171Y423148D01*
X231880Y422773D01*
X231463Y422523D01*
X231088Y422440D01*
Y424190D01*
G01Y426332D02*
X231630Y426415D01*
X232088Y426540D01*
X232505Y426707D01*
X232963Y426915D01*
X233588Y427248D01*
Y425582D01*
G01X218838Y437345D02*
X222838D01*
Y429945D01*
G01X199800Y449200D02*
X203800D01*
Y441800D01*
G01X228678Y419743D02*
Y422243D01*
X227637D01*
X227303Y422118D01*
X227095Y421951D01*
X227012Y421618D01*
X227095Y421285D01*
X227345Y421076D01*
X227637Y420951D01*
X228678D01*
G01X227637D02*
X227012Y419743D01*
G01X224245D02*
Y422243D01*
X225787Y420451D01*
X223703D01*
G01X222562Y420243D02*
X222312Y419951D01*
X221978Y419785D01*
X221603Y419743D01*
X221270Y419785D01*
X220937Y419993D01*
X220728Y420243D01*
X220687Y420493D01*
X220770Y420785D01*
X221062Y420993D01*
X221353Y421076D01*
X221728D01*
G01X221353D02*
X221103Y421201D01*
X220895Y421410D01*
X220812Y421660D01*
X220895Y421910D01*
X221103Y422118D01*
X221478Y422243D01*
X221853Y422201D01*
X222228Y422035D01*
G01X219337Y420785D02*
X219045Y421076D01*
X218795Y421243D01*
X218462Y421326D01*
X218170Y421243D01*
X217962Y421076D01*
X217795Y420826D01*
X217753Y420535D01*
X217795Y420285D01*
X217962Y420035D01*
X218212Y419826D01*
X218503Y419743D01*
X218837Y419826D01*
X219128Y420076D01*
X219295Y420451D01*
X219337Y420868D01*
X219253Y421410D01*
X219128Y421701D01*
X218920Y421993D01*
X218628Y422201D01*
X218337Y422243D01*
X218045Y422160D01*
X217837Y421951D01*
G01X215692Y419855D02*
Y422355D01*
X214651D01*
X214317Y422230D01*
X214109Y422063D01*
X214026Y421730D01*
X214109Y421397D01*
X214359Y421188D01*
X214651Y421063D01*
X215692D01*
G01X214651D02*
X214026Y419855D01*
G01X211259D02*
Y422355D01*
X212801Y420563D01*
X210717D01*
G01X209576Y420355D02*
X209326Y420063D01*
X208992Y419897D01*
X208617Y419855D01*
X208284Y419897D01*
X207951Y420105D01*
X207742Y420355D01*
X207701Y420605D01*
X207784Y420897D01*
X208076Y421105D01*
X208367Y421188D01*
X208742D01*
G01X208367D02*
X208117Y421313D01*
X207909Y421522D01*
X207826Y421772D01*
X207909Y422022D01*
X208117Y422230D01*
X208492Y422355D01*
X208867Y422313D01*
X209242Y422147D01*
G01X205642Y419855D02*
X205559Y420397D01*
X205434Y420855D01*
X205267Y421272D01*
X205059Y421730D01*
X204726Y422355D01*
X206392D01*
G01X223833Y433418D02*
X226333D01*
Y434459D01*
X226208Y434793D01*
X226041Y435001D01*
X225708Y435084D01*
X225375Y435001D01*
X225166Y434751D01*
X225041Y434459D01*
Y433418D01*
G01Y434459D02*
X223833Y435084D01*
G01X224208Y436434D02*
X224000Y436684D01*
X223875Y436976D01*
X223833Y437351D01*
X223916Y437726D01*
X224083Y438018D01*
X224375Y438226D01*
X224708Y438268D01*
X225041Y438184D01*
X225250Y437976D01*
X225416Y437684D01*
X225458Y437393D01*
X225416Y437101D01*
X225250Y436726D01*
X226333Y436851D01*
Y437976D01*
G01X224333Y439534D02*
X224041Y439784D01*
X223875Y440118D01*
X223833Y440493D01*
X223875Y440826D01*
X224083Y441159D01*
X224333Y441368D01*
X224583Y441409D01*
X224875Y441326D01*
X225083Y441034D01*
X225166Y440743D01*
Y440368D01*
G01Y440743D02*
X225291Y440993D01*
X225500Y441201D01*
X225750Y441284D01*
X226000Y441201D01*
X226208Y440993D01*
X226333Y440618D01*
X226291Y440243D01*
X226125Y439868D01*
G01X223833Y443551D02*
X226333D01*
X225833Y443051D01*
G01X223833D02*
Y444051D01*
G01X227833Y433418D02*
X230333D01*
Y434459D01*
X230208Y434793D01*
X230041Y435001D01*
X229708Y435084D01*
X229375Y435001D01*
X229166Y434751D01*
X229041Y434459D01*
Y433418D01*
G01Y434459D02*
X227833Y435084D01*
G01Y437851D02*
X230333D01*
X228541Y436309D01*
Y438393D01*
G01X228125Y439743D02*
X227916Y440034D01*
X227833Y440368D01*
X227916Y440701D01*
X228166Y440993D01*
X228541Y441201D01*
X228916Y441284D01*
X229375D01*
X229750Y441201D01*
X230083Y440993D01*
X230250Y440743D01*
X230333Y440451D01*
X230250Y440118D01*
X230083Y439868D01*
X229833Y439701D01*
X229500Y439618D01*
X229208Y439701D01*
X228916Y439909D01*
X228750Y440159D01*
X228708Y440451D01*
X228791Y440784D01*
X229000Y441034D01*
X229375Y441284D01*
G01X230333Y443551D02*
X230250Y443218D01*
X230041Y442968D01*
X229791Y442801D01*
X229458Y442676D01*
X229083Y442634D01*
X228708Y442676D01*
X228375Y442801D01*
X228125Y442968D01*
X227916Y443218D01*
X227833Y443551D01*
X227916Y443884D01*
X228125Y444134D01*
X228375Y444301D01*
X228708Y444426D01*
X229083Y444468D01*
X229458Y444426D01*
X229791Y444301D01*
X230041Y444134D01*
X230250Y443884D01*
X230333Y443551D01*
G01X204000Y461700D02*
X204600D01*
Y458400D01*
G01Y455400D02*
Y447900D01*
G01X228572Y464313D02*
X232572D01*
Y456913D01*
G01X232571Y464317D02*
X228571D01*
Y471717D01*
G01X228483Y478660D02*
Y481160D01*
X227442D01*
X227108Y481035D01*
X226900Y480868D01*
X226817Y480535D01*
X226900Y480202D01*
X227150Y479993D01*
X227442Y479868D01*
X228483D01*
G01X227442D02*
X226817Y478660D01*
G01X225342Y480743D02*
X225092Y480993D01*
X224800Y481118D01*
X224467Y481160D01*
X224050Y481077D01*
X223758Y480868D01*
X223675Y480618D01*
X223717Y480368D01*
X223883Y480160D01*
X224717Y479743D01*
X225092Y479452D01*
X225342Y479035D01*
X225425Y478660D01*
X223675D01*
G01X220950D02*
Y481160D01*
X222492Y479368D01*
X220408D01*
G01X219142Y479702D02*
X218850Y479993D01*
X218600Y480160D01*
X218267Y480243D01*
X217975Y480160D01*
X217767Y479993D01*
X217600Y479743D01*
X217558Y479452D01*
X217600Y479202D01*
X217767Y478952D01*
X218017Y478743D01*
X218308Y478660D01*
X218642Y478743D01*
X218933Y478993D01*
X219100Y479368D01*
X219142Y479785D01*
X219058Y480327D01*
X218933Y480618D01*
X218725Y480910D01*
X218433Y481118D01*
X218142Y481160D01*
X217850Y481077D01*
X217642Y480868D01*
G01X216202Y481619D02*
Y477619D01*
X208802D01*
G01X229443Y475829D02*
Y479829D01*
X236843D01*
G01X228483Y475137D02*
Y477637D01*
X227442D01*
X227108Y477512D01*
X226900Y477345D01*
X226817Y477012D01*
X226900Y476679D01*
X227150Y476470D01*
X227442Y476345D01*
X228483D01*
G01X227442D02*
X226817Y475137D01*
G01X225342Y477220D02*
X225092Y477470D01*
X224800Y477595D01*
X224467Y477637D01*
X224050Y477554D01*
X223758Y477345D01*
X223675Y477095D01*
X223717Y476845D01*
X223883Y476637D01*
X224717Y476220D01*
X225092Y475929D01*
X225342Y475512D01*
X225425Y475137D01*
X223675D01*
G01X220950D02*
Y477637D01*
X222492Y475845D01*
X220408D01*
G01X218433Y475137D02*
X218350Y475679D01*
X218225Y476137D01*
X218058Y476554D01*
X217850Y477012D01*
X217517Y477637D01*
X219183D01*
G01X216202Y477619D02*
Y473619D01*
X208802D01*
G01X199700Y460035D02*
X203700D01*
Y452635D01*
G01X212400Y446200D02*
Y450200D01*
X219800D01*
G01X212226Y450165D02*
Y446165D01*
X204826D01*
G01X229443Y471829D02*
Y475829D01*
X236843D01*
G01X208300Y459500D02*
X212300D01*
Y452100D01*
G01Y459500D02*
X216300D01*
Y452100D01*
G01X233386Y450426D02*
Y452926D01*
X232345D01*
X232011Y452801D01*
X231803Y452634D01*
X231720Y452301D01*
X231803Y451968D01*
X232053Y451759D01*
X232345Y451634D01*
X233386D01*
G01X232345D02*
X231720Y450426D01*
G01X230245Y452509D02*
X229995Y452759D01*
X229703Y452884D01*
X229370Y452926D01*
X228953Y452843D01*
X228661Y452634D01*
X228578Y452384D01*
X228620Y452134D01*
X228786Y451926D01*
X229620Y451509D01*
X229995Y451218D01*
X230245Y450801D01*
X230328Y450426D01*
X228578D01*
G01X225853D02*
Y452926D01*
X227395Y451134D01*
X225311D01*
G01X224170Y450926D02*
X223920Y450634D01*
X223586Y450468D01*
X223211Y450426D01*
X222878Y450468D01*
X222545Y450676D01*
X222336Y450926D01*
X222295Y451176D01*
X222378Y451468D01*
X222670Y451676D01*
X222961Y451759D01*
X223336D01*
G01X222961D02*
X222711Y451884D01*
X222503Y452093D01*
X222420Y452343D01*
X222503Y452593D01*
X222711Y452801D01*
X223086Y452926D01*
X223461Y452884D01*
X223836Y452718D01*
G01X228238Y468300D02*
Y464300D01*
X220838D01*
G01X233386Y446426D02*
Y448926D01*
X232345D01*
X232011Y448801D01*
X231803Y448634D01*
X231720Y448301D01*
X231803Y447968D01*
X232053Y447759D01*
X232345Y447634D01*
X233386D01*
G01X232345D02*
X231720Y446426D01*
G01X230245Y448509D02*
X229995Y448759D01*
X229703Y448884D01*
X229370Y448926D01*
X228953Y448843D01*
X228661Y448634D01*
X228578Y448384D01*
X228620Y448134D01*
X228786Y447926D01*
X229620Y447509D01*
X229995Y447218D01*
X230245Y446801D01*
X230328Y446426D01*
X228578D01*
G01X225853D02*
Y448926D01*
X227395Y447134D01*
X225311D01*
G01X224045Y448509D02*
X223795Y448759D01*
X223503Y448884D01*
X223170Y448926D01*
X222753Y448843D01*
X222461Y448634D01*
X222378Y448384D01*
X222420Y448134D01*
X222586Y447926D01*
X223420Y447509D01*
X223795Y447218D01*
X224045Y446801D01*
X224128Y446426D01*
X222378D01*
G01X228238Y464300D02*
Y460300D01*
X220838D01*
G01X228483Y485974D02*
Y488474D01*
X227442D01*
X227108Y488349D01*
X226900Y488182D01*
X226817Y487849D01*
X226900Y487516D01*
X227150Y487307D01*
X227442Y487182D01*
X228483D01*
G01X227442D02*
X226817Y485974D01*
G01X224050D02*
Y488474D01*
X225592Y486682D01*
X223508D01*
G01X222242Y487016D02*
X221950Y487307D01*
X221700Y487474D01*
X221367Y487557D01*
X221075Y487474D01*
X220867Y487307D01*
X220700Y487057D01*
X220658Y486766D01*
X220700Y486516D01*
X220867Y486266D01*
X221117Y486057D01*
X221408Y485974D01*
X221742Y486057D01*
X222033Y486307D01*
X222200Y486682D01*
X222242Y487099D01*
X222158Y487641D01*
X222033Y487932D01*
X221825Y488224D01*
X221533Y488432D01*
X221242Y488474D01*
X220950Y488391D01*
X220742Y488182D01*
G01X219142Y487016D02*
X218850Y487307D01*
X218600Y487474D01*
X218267Y487557D01*
X217975Y487474D01*
X217767Y487307D01*
X217600Y487057D01*
X217558Y486766D01*
X217600Y486516D01*
X217767Y486266D01*
X218017Y486057D01*
X218308Y485974D01*
X218642Y486057D01*
X218933Y486307D01*
X219100Y486682D01*
X219142Y487099D01*
X219058Y487641D01*
X218933Y487932D01*
X218725Y488224D01*
X218433Y488432D01*
X218142Y488474D01*
X217850Y488391D01*
X217642Y488182D01*
G01X216423Y489704D02*
Y485704D01*
X209023D01*
G01X228483Y482309D02*
Y484809D01*
X227442D01*
X227108Y484684D01*
X226900Y484517D01*
X226817Y484184D01*
X226900Y483851D01*
X227150Y483642D01*
X227442Y483517D01*
X228483D01*
G01X227442D02*
X226817Y482309D01*
G01X224050D02*
Y484809D01*
X225592Y483017D01*
X223508D01*
G01X222242Y483351D02*
X221950Y483642D01*
X221700Y483809D01*
X221367Y483892D01*
X221075Y483809D01*
X220867Y483642D01*
X220700Y483392D01*
X220658Y483101D01*
X220700Y482851D01*
X220867Y482601D01*
X221117Y482392D01*
X221408Y482309D01*
X221742Y482392D01*
X222033Y482642D01*
X222200Y483017D01*
X222242Y483434D01*
X222158Y483976D01*
X222033Y484267D01*
X221825Y484559D01*
X221533Y484767D01*
X221242Y484809D01*
X220950Y484726D01*
X220742Y484517D01*
G01X218433Y482309D02*
X218350Y482851D01*
X218225Y483309D01*
X218058Y483726D01*
X217850Y484184D01*
X217517Y484809D01*
X219183D01*
G01X216423Y485704D02*
Y481704D01*
X209023D01*
G01X199200Y500800D02*
Y504800D01*
X206600D01*
G01X199200D02*
Y508800D01*
X206600D01*
G01X228183Y495263D02*
Y497763D01*
X227142D01*
X226808Y497638D01*
X226600Y497471D01*
X226517Y497138D01*
X226600Y496805D01*
X226850Y496596D01*
X227142Y496471D01*
X228183D01*
G01X227142D02*
X226517Y495263D01*
G01X225167Y495763D02*
X224917Y495471D01*
X224583Y495305D01*
X224208Y495263D01*
X223875Y495305D01*
X223542Y495513D01*
X223333Y495763D01*
X223292Y496013D01*
X223375Y496305D01*
X223667Y496513D01*
X223958Y496596D01*
X224333D01*
G01X223958D02*
X223708Y496721D01*
X223500Y496930D01*
X223417Y497180D01*
X223500Y497430D01*
X223708Y497638D01*
X224083Y497763D01*
X224458Y497721D01*
X224833Y497555D01*
G01X222067Y495763D02*
X221817Y495471D01*
X221483Y495305D01*
X221108Y495263D01*
X220775Y495305D01*
X220442Y495513D01*
X220233Y495763D01*
X220192Y496013D01*
X220275Y496305D01*
X220567Y496513D01*
X220858Y496596D01*
X221233D01*
G01X220858D02*
X220608Y496721D01*
X220400Y496930D01*
X220317Y497180D01*
X220400Y497430D01*
X220608Y497638D01*
X220983Y497763D01*
X221358Y497721D01*
X221733Y497555D01*
G01X218967Y495638D02*
X218717Y495430D01*
X218425Y495305D01*
X218050Y495263D01*
X217675Y495346D01*
X217383Y495513D01*
X217175Y495805D01*
X217133Y496138D01*
X217217Y496471D01*
X217425Y496680D01*
X217717Y496846D01*
X218008Y496888D01*
X218300Y496846D01*
X218675Y496680D01*
X218550Y497763D01*
X217425D01*
G01X215450Y497744D02*
Y493744D01*
X208050D01*
G01X229443Y483929D02*
Y487929D01*
X236843D01*
G01X229443D02*
Y491929D01*
X236843D01*
G01X229400Y504000D02*
Y508000D01*
X236800D01*
G01X229400Y500000D02*
Y504000D01*
X236800D01*
G01X228357Y491698D02*
Y494198D01*
X227316D01*
X226982Y494073D01*
X226774Y493906D01*
X226691Y493573D01*
X226774Y493240D01*
X227024Y493031D01*
X227316Y492906D01*
X228357D01*
G01X227316D02*
X226691Y491698D01*
G01X224507D02*
X224424Y492240D01*
X224299Y492698D01*
X224132Y493115D01*
X223924Y493573D01*
X223591Y494198D01*
X225257D01*
G01X222032Y491990D02*
X221741Y491781D01*
X221407Y491698D01*
X221074Y491781D01*
X220782Y492031D01*
X220574Y492406D01*
X220491Y492781D01*
Y493240D01*
X220574Y493615D01*
X220782Y493948D01*
X221032Y494115D01*
X221324Y494198D01*
X221657Y494115D01*
X221907Y493948D01*
X222074Y493698D01*
X222157Y493365D01*
X222074Y493073D01*
X221866Y492781D01*
X221616Y492615D01*
X221324Y492573D01*
X220991Y492656D01*
X220741Y492865D01*
X220491Y493240D01*
G01X218932Y491990D02*
X218641Y491781D01*
X218307Y491698D01*
X217974Y491781D01*
X217682Y492031D01*
X217474Y492406D01*
X217391Y492781D01*
Y493240D01*
X217474Y493615D01*
X217682Y493948D01*
X217932Y494115D01*
X218224Y494198D01*
X218557Y494115D01*
X218807Y493948D01*
X218974Y493698D01*
X219057Y493365D01*
X218974Y493073D01*
X218766Y492781D01*
X218516Y492615D01*
X218224Y492573D01*
X217891Y492656D01*
X217641Y492865D01*
X217391Y493240D01*
G01X215450Y493744D02*
Y489744D01*
X208050D01*
G01X199200Y508900D02*
Y512900D01*
X206600D01*
G01X199200D02*
Y516900D01*
X206600D01*
G01X215200Y527500D02*
Y523500D01*
X207800D01*
G01X215200D02*
Y519500D01*
X207800D01*
G01X215200Y536500D02*
Y532500D01*
X207800D01*
G01X215200D02*
Y528500D01*
X207800D01*
G01Y540500D02*
Y544500D01*
X215200D01*
G01X207800Y536500D02*
Y540500D01*
X215200D01*
G01X223000Y532800D02*
X219000D01*
Y540200D01*
G01X223000D02*
X227000D01*
Y532800D01*
G01X231000Y516300D02*
X227000D01*
Y523700D01*
G01X223000D02*
X227000D01*
Y516300D01*
G01Y523800D02*
X223000D01*
Y531200D01*
G01X231000Y523800D02*
X227000D01*
Y531200D01*
G01X207800Y544500D02*
Y548500D01*
X215200D01*
G01X218414Y557580D02*
Y560080D01*
X217373D01*
X217039Y559955D01*
X216831Y559788D01*
X216748Y559455D01*
X216831Y559122D01*
X217081Y558913D01*
X217373Y558788D01*
X218414D01*
G01X217373D02*
X216748Y557580D01*
G01X215398Y558080D02*
X215148Y557788D01*
X214814Y557622D01*
X214439Y557580D01*
X214106Y557622D01*
X213773Y557830D01*
X213564Y558080D01*
X213523Y558330D01*
X213606Y558622D01*
X213898Y558830D01*
X214189Y558913D01*
X214564D01*
G01X214189D02*
X213939Y559038D01*
X213731Y559247D01*
X213648Y559497D01*
X213731Y559747D01*
X213939Y559955D01*
X214314Y560080D01*
X214689Y560038D01*
X215064Y559872D01*
G01X211381Y557580D02*
Y560080D01*
X211881Y559580D01*
G01Y557580D02*
X210881D01*
G01X209073Y558622D02*
X208781Y558913D01*
X208531Y559080D01*
X208198Y559163D01*
X207906Y559080D01*
X207698Y558913D01*
X207531Y558663D01*
X207489Y558372D01*
X207531Y558122D01*
X207698Y557872D01*
X207948Y557663D01*
X208239Y557580D01*
X208573Y557663D01*
X208864Y557913D01*
X209031Y558288D01*
X209073Y558705D01*
X208989Y559247D01*
X208864Y559538D01*
X208656Y559830D01*
X208364Y560038D01*
X208073Y560080D01*
X207781Y559997D01*
X207573Y559788D01*
G01X218281Y553467D02*
Y555967D01*
X217240D01*
X216906Y555842D01*
X216698Y555675D01*
X216615Y555342D01*
X216698Y555009D01*
X216948Y554800D01*
X217240Y554675D01*
X218281D01*
G01X217240D02*
X216615Y553467D01*
G01X215265Y553967D02*
X215015Y553675D01*
X214681Y553509D01*
X214306Y553467D01*
X213973Y553509D01*
X213640Y553717D01*
X213431Y553967D01*
X213390Y554217D01*
X213473Y554509D01*
X213765Y554717D01*
X214056Y554800D01*
X214431D01*
G01X214056D02*
X213806Y554925D01*
X213598Y555134D01*
X213515Y555384D01*
X213598Y555634D01*
X213806Y555842D01*
X214181Y555967D01*
X214556Y555925D01*
X214931Y555759D01*
G01X211248Y553467D02*
Y555967D01*
X211748Y555467D01*
G01Y553467D02*
X210748D01*
G01X208148D02*
X207856Y553509D01*
X207523Y553634D01*
X207315Y553842D01*
X207231Y554134D01*
X207315Y554425D01*
X207565Y554675D01*
X207940Y554800D01*
X208356D01*
X208606Y554884D01*
X208815Y555092D01*
X208898Y555384D01*
X208773Y555675D01*
X208481Y555884D01*
X208148Y555967D01*
X207815Y555884D01*
X207523Y555675D01*
X207398Y555384D01*
X207481Y555092D01*
X207690Y554884D01*
X207940Y554800D01*
X208356D01*
X208731Y554675D01*
X208981Y554425D01*
X209065Y554134D01*
X208981Y553842D01*
X208773Y553634D01*
X208440Y553509D01*
X208148Y553467D01*
G01X223014Y569036D02*
Y571536D01*
X221973D01*
X221639Y571411D01*
X221431Y571244D01*
X221348Y570911D01*
X221431Y570578D01*
X221681Y570369D01*
X221973Y570244D01*
X223014D01*
G01X221973D02*
X221348Y569036D01*
G01X219998Y569536D02*
X219748Y569244D01*
X219414Y569078D01*
X219039Y569036D01*
X218706Y569078D01*
X218373Y569286D01*
X218164Y569536D01*
X218123Y569786D01*
X218206Y570078D01*
X218498Y570286D01*
X218789Y570369D01*
X219164D01*
G01X218789D02*
X218539Y570494D01*
X218331Y570703D01*
X218248Y570953D01*
X218331Y571203D01*
X218539Y571411D01*
X218914Y571536D01*
X219289Y571494D01*
X219664Y571328D01*
G01X216773Y571119D02*
X216523Y571369D01*
X216231Y571494D01*
X215898Y571536D01*
X215481Y571453D01*
X215189Y571244D01*
X215106Y570994D01*
X215148Y570744D01*
X215314Y570536D01*
X216148Y570119D01*
X216523Y569828D01*
X216773Y569411D01*
X216856Y569036D01*
X215106D01*
G01X213673Y571119D02*
X213423Y571369D01*
X213131Y571494D01*
X212798Y571536D01*
X212381Y571453D01*
X212089Y571244D01*
X212006Y570994D01*
X212048Y570744D01*
X212214Y570536D01*
X213048Y570119D01*
X213423Y569828D01*
X213673Y569411D01*
X213756Y569036D01*
X212006D01*
G01X218370Y564835D02*
Y567335D01*
X217329D01*
X216995Y567210D01*
X216787Y567043D01*
X216704Y566710D01*
X216787Y566377D01*
X217037Y566168D01*
X217329Y566043D01*
X218370D01*
G01X217329D02*
X216704Y564835D01*
G01X215354Y565335D02*
X215104Y565043D01*
X214770Y564877D01*
X214395Y564835D01*
X214062Y564877D01*
X213729Y565085D01*
X213520Y565335D01*
X213479Y565585D01*
X213562Y565877D01*
X213854Y566085D01*
X214145Y566168D01*
X214520D01*
G01X214145D02*
X213895Y566293D01*
X213687Y566502D01*
X213604Y566752D01*
X213687Y567002D01*
X213895Y567210D01*
X214270Y567335D01*
X214645Y567293D01*
X215020Y567127D01*
G01X211420Y564835D02*
X211337Y565377D01*
X211212Y565835D01*
X211045Y566252D01*
X210837Y566710D01*
X210504Y567335D01*
X212170D01*
G01X209154Y565335D02*
X208904Y565043D01*
X208570Y564877D01*
X208195Y564835D01*
X207862Y564877D01*
X207529Y565085D01*
X207320Y565335D01*
X207279Y565585D01*
X207362Y565877D01*
X207654Y566085D01*
X207945Y566168D01*
X208320D01*
G01X207945D02*
X207695Y566293D01*
X207487Y566502D01*
X207404Y566752D01*
X207487Y567002D01*
X207695Y567210D01*
X208070Y567335D01*
X208445Y567293D01*
X208820Y567127D01*
G01X222809Y576451D02*
Y578951D01*
X221768D01*
X221434Y578826D01*
X221226Y578659D01*
X221143Y578326D01*
X221226Y577993D01*
X221476Y577784D01*
X221768Y577659D01*
X222809D01*
G01X221768D02*
X221143Y576451D01*
G01X218876D02*
Y578951D01*
X219376Y578451D01*
G01Y576451D02*
X218376D01*
G01X215276D02*
Y578951D01*
X216818Y577159D01*
X214734D01*
G01X212676Y576451D02*
X212384Y576493D01*
X212051Y576618D01*
X211843Y576826D01*
X211759Y577118D01*
X211843Y577409D01*
X212093Y577659D01*
X212468Y577784D01*
X212884D01*
X213134Y577868D01*
X213343Y578076D01*
X213426Y578368D01*
X213301Y578659D01*
X213009Y578868D01*
X212676Y578951D01*
X212343Y578868D01*
X212051Y578659D01*
X211926Y578368D01*
X212009Y578076D01*
X212218Y577868D01*
X212468Y577784D01*
X212884D01*
X213259Y577659D01*
X213509Y577409D01*
X213593Y577118D01*
X213509Y576826D01*
X213301Y576618D01*
X212968Y576493D01*
X212676Y576451D01*
G01X223032Y572781D02*
Y575281D01*
X221991D01*
X221657Y575156D01*
X221449Y574989D01*
X221366Y574656D01*
X221449Y574323D01*
X221699Y574114D01*
X221991Y573989D01*
X223032D01*
G01X221991D02*
X221366Y572781D01*
G01X219099D02*
Y575281D01*
X219599Y574781D01*
G01Y572781D02*
X218599D01*
G01X216916Y573156D02*
X216666Y572948D01*
X216374Y572823D01*
X215999Y572781D01*
X215624Y572864D01*
X215332Y573031D01*
X215124Y573323D01*
X215082Y573656D01*
X215166Y573989D01*
X215374Y574198D01*
X215666Y574364D01*
X215957Y574406D01*
X216249Y574364D01*
X216624Y574198D01*
X216499Y575281D01*
X215374D01*
G01X213691Y574864D02*
X213441Y575114D01*
X213149Y575239D01*
X212816Y575281D01*
X212399Y575198D01*
X212107Y574989D01*
X212024Y574739D01*
X212066Y574489D01*
X212232Y574281D01*
X213066Y573864D01*
X213441Y573573D01*
X213691Y573156D01*
X213774Y572781D01*
X212024D01*
G01X238587Y569251D02*
Y571751D01*
X237546D01*
X237212Y571626D01*
X237004Y571459D01*
X236921Y571126D01*
X237004Y570793D01*
X237254Y570584D01*
X237546Y570459D01*
X238587D01*
G01X237546D02*
X236921Y569251D01*
G01X235571Y569751D02*
X235321Y569459D01*
X234987Y569293D01*
X234612Y569251D01*
X234279Y569293D01*
X233946Y569501D01*
X233737Y569751D01*
X233696Y570001D01*
X233779Y570293D01*
X234071Y570501D01*
X234362Y570584D01*
X234737D01*
G01X234362D02*
X234112Y570709D01*
X233904Y570918D01*
X233821Y571168D01*
X233904Y571418D01*
X234112Y571626D01*
X234487Y571751D01*
X234862Y571709D01*
X235237Y571543D01*
G01X231554Y569251D02*
Y571751D01*
X232054Y571251D01*
G01Y569251D02*
X231054D01*
G01X228454Y571751D02*
X228787Y571668D01*
X229037Y571459D01*
X229204Y571209D01*
X229329Y570876D01*
X229371Y570501D01*
X229329Y570126D01*
X229204Y569793D01*
X229037Y569543D01*
X228787Y569334D01*
X228454Y569251D01*
X228121Y569334D01*
X227871Y569543D01*
X227704Y569793D01*
X227579Y570126D01*
X227537Y570501D01*
X227579Y570876D01*
X227704Y571209D01*
X227871Y571459D01*
X228121Y571668D01*
X228454Y571751D01*
G01X228200Y552500D02*
Y548500D01*
X220800D01*
G01X238587Y577251D02*
Y579751D01*
X237546D01*
X237212Y579626D01*
X237004Y579459D01*
X236921Y579126D01*
X237004Y578793D01*
X237254Y578584D01*
X237546Y578459D01*
X238587D01*
G01X237546D02*
X236921Y577251D01*
G01X235571Y577626D02*
X235321Y577418D01*
X235029Y577293D01*
X234654Y577251D01*
X234279Y577334D01*
X233987Y577501D01*
X233779Y577793D01*
X233737Y578126D01*
X233821Y578459D01*
X234029Y578668D01*
X234321Y578834D01*
X234612Y578876D01*
X234904Y578834D01*
X235279Y578668D01*
X235154Y579751D01*
X234029D01*
G01X231554Y577251D02*
X231262Y577293D01*
X230929Y577418D01*
X230721Y577626D01*
X230637Y577918D01*
X230721Y578209D01*
X230971Y578459D01*
X231346Y578584D01*
X231762D01*
X232012Y578668D01*
X232221Y578876D01*
X232304Y579168D01*
X232179Y579459D01*
X231887Y579668D01*
X231554Y579751D01*
X231221Y579668D01*
X230929Y579459D01*
X230804Y579168D01*
X230887Y578876D01*
X231096Y578668D01*
X231346Y578584D01*
X231762D01*
X232137Y578459D01*
X232387Y578209D01*
X232471Y577918D01*
X232387Y577626D01*
X232179Y577418D01*
X231846Y577293D01*
X231554Y577251D01*
G01X227954D02*
Y579751D01*
X229496Y577959D01*
X227412D01*
G01X228200Y560500D02*
Y556500D01*
X220800D01*
G01X222854Y580034D02*
Y582534D01*
X221813D01*
X221479Y582409D01*
X221271Y582242D01*
X221188Y581909D01*
X221271Y581576D01*
X221521Y581367D01*
X221813Y581242D01*
X222854D01*
G01X221813D02*
X221188Y580034D01*
G01X218921D02*
Y582534D01*
X219421Y582034D01*
G01Y580034D02*
X218421D01*
G01X215321D02*
Y582534D01*
X216863Y580742D01*
X214779D01*
G01X213429Y580326D02*
X213138Y580117D01*
X212804Y580034D01*
X212471Y580117D01*
X212179Y580367D01*
X211971Y580742D01*
X211888Y581117D01*
Y581576D01*
X211971Y581951D01*
X212179Y582284D01*
X212429Y582451D01*
X212721Y582534D01*
X213054Y582451D01*
X213304Y582284D01*
X213471Y582034D01*
X213554Y581701D01*
X213471Y581409D01*
X213263Y581117D01*
X213013Y580951D01*
X212721Y580909D01*
X212388Y580992D01*
X212138Y581201D01*
X211888Y581576D01*
G01X238587Y573251D02*
Y575751D01*
X237546D01*
X237212Y575626D01*
X237004Y575459D01*
X236921Y575126D01*
X237004Y574793D01*
X237254Y574584D01*
X237546Y574459D01*
X238587D01*
G01X237546D02*
X236921Y573251D01*
G01X235446Y575334D02*
X235196Y575584D01*
X234904Y575709D01*
X234571Y575751D01*
X234154Y575668D01*
X233862Y575459D01*
X233779Y575209D01*
X233821Y574959D01*
X233987Y574751D01*
X234821Y574334D01*
X235196Y574043D01*
X235446Y573626D01*
X235529Y573251D01*
X233779D01*
G01X232346Y575334D02*
X232096Y575584D01*
X231804Y575709D01*
X231471Y575751D01*
X231054Y575668D01*
X230762Y575459D01*
X230679Y575209D01*
X230721Y574959D01*
X230887Y574751D01*
X231721Y574334D01*
X232096Y574043D01*
X232346Y573626D01*
X232429Y573251D01*
X230679D01*
G01X228454Y575751D02*
X228787Y575668D01*
X229037Y575459D01*
X229204Y575209D01*
X229329Y574876D01*
X229371Y574501D01*
X229329Y574126D01*
X229204Y573793D01*
X229037Y573543D01*
X228787Y573334D01*
X228454Y573251D01*
X228121Y573334D01*
X227871Y573543D01*
X227704Y573793D01*
X227579Y574126D01*
X227537Y574501D01*
X227579Y574876D01*
X227704Y575209D01*
X227871Y575459D01*
X228121Y575668D01*
X228454Y575751D01*
G01X228200Y556500D02*
Y552500D01*
X220800D01*
G01X200005Y579346D02*
X199797Y579679D01*
X199672Y580054D01*
Y580388D01*
X199797Y580721D01*
X200005Y580971D01*
X200297Y581096D01*
X200589Y581013D01*
X200839Y580804D01*
X201005Y580429D01*
X201089Y579929D01*
X201255Y579638D01*
X201547Y579513D01*
X201839Y579596D01*
X202047Y579804D01*
X202172Y580096D01*
Y580388D01*
X202089Y580679D01*
X201880Y580929D01*
G01X199672Y582488D02*
X202172D01*
Y583529D01*
X202047Y583863D01*
X201880Y584071D01*
X201547Y584154D01*
X201214Y584071D01*
X201005Y583821D01*
X200880Y583529D01*
Y582488D01*
G01Y583529D02*
X199672Y584154D01*
G01Y586421D02*
X199714Y586713D01*
X199839Y587046D01*
X200047Y587254D01*
X200339Y587338D01*
X200630Y587254D01*
X200880Y587004D01*
X201005Y586629D01*
Y586213D01*
X201089Y585963D01*
X201297Y585754D01*
X201589Y585671D01*
X201880Y585796D01*
X202089Y586088D01*
X202172Y586421D01*
X202089Y586754D01*
X201880Y587046D01*
X201589Y587171D01*
X201297Y587088D01*
X201089Y586879D01*
X201005Y586629D01*
Y586213D01*
X200880Y585838D01*
X200630Y585588D01*
X200339Y585504D01*
X200047Y585588D01*
X199839Y585796D01*
X199714Y586129D01*
X199672Y586421D01*
G01Y590021D02*
X202172D01*
X200380Y588479D01*
Y590563D01*
G01X199964Y591913D02*
X199755Y592204D01*
X199672Y592538D01*
X199755Y592871D01*
X200005Y593163D01*
X200380Y593371D01*
X200755Y593454D01*
X201214D01*
X201589Y593371D01*
X201922Y593163D01*
X202089Y592913D01*
X202172Y592621D01*
X202089Y592288D01*
X201922Y592038D01*
X201672Y591871D01*
X201339Y591788D01*
X201047Y591871D01*
X200755Y592079D01*
X200589Y592329D01*
X200547Y592621D01*
X200630Y592954D01*
X200839Y593204D01*
X201214Y593454D01*
G01X203500Y568800D02*
X199500D01*
Y576200D01*
G01X207800Y548500D02*
Y552500D01*
X215200D01*
G01X235646Y555541D02*
X235771Y555291D01*
X235854Y554999D01*
Y554666D01*
X235729Y554291D01*
X235521Y553999D01*
X235271Y553791D01*
X234854Y553624D01*
X234479Y553582D01*
X234104Y553666D01*
X233854Y553791D01*
X233604Y554041D01*
X233437Y554332D01*
X233354Y554624D01*
Y554916D01*
X233437Y555207D01*
X233562Y555457D01*
X233729Y555666D01*
G01X233354Y557724D02*
X233396Y558016D01*
X233521Y558349D01*
X233729Y558557D01*
X234021Y558641D01*
X234312Y558557D01*
X234562Y558307D01*
X234687Y557932D01*
Y557516D01*
X234771Y557266D01*
X234979Y557057D01*
X235271Y556974D01*
X235562Y557099D01*
X235771Y557391D01*
X235854Y557724D01*
X235771Y558057D01*
X235562Y558349D01*
X235271Y558474D01*
X234979Y558391D01*
X234771Y558182D01*
X234687Y557932D01*
Y557516D01*
X234562Y557141D01*
X234312Y556891D01*
X234021Y556807D01*
X233729Y556891D01*
X233521Y557099D01*
X233396Y557432D01*
X233354Y557724D01*
G01X235854Y560824D02*
X235771Y560491D01*
X235562Y560241D01*
X235312Y560074D01*
X234979Y559949D01*
X234604Y559907D01*
X234229Y559949D01*
X233896Y560074D01*
X233646Y560241D01*
X233437Y560491D01*
X233354Y560824D01*
X233437Y561157D01*
X233646Y561407D01*
X233896Y561574D01*
X234229Y561699D01*
X234604Y561741D01*
X234979Y561699D01*
X235312Y561574D01*
X235562Y561407D01*
X235771Y561157D01*
X235854Y560824D01*
G01X233354Y563924D02*
X233396Y564216D01*
X233521Y564549D01*
X233729Y564757D01*
X234021Y564841D01*
X234312Y564757D01*
X234562Y564507D01*
X234687Y564132D01*
Y563716D01*
X234771Y563466D01*
X234979Y563257D01*
X235271Y563174D01*
X235562Y563299D01*
X235771Y563591D01*
X235854Y563924D01*
X235771Y564257D01*
X235562Y564549D01*
X235271Y564674D01*
X234979Y564591D01*
X234771Y564382D01*
X234687Y564132D01*
Y563716D01*
X234562Y563341D01*
X234312Y563091D01*
X234021Y563007D01*
X233729Y563091D01*
X233521Y563299D01*
X233396Y563632D01*
X233354Y563924D01*
G01Y567024D02*
X235854D01*
X235354Y566524D01*
G01X233354D02*
Y567524D01*
G01X223074Y584038D02*
X222741Y583830D01*
X222366Y583705D01*
X222032D01*
X221699Y583830D01*
X221449Y584038D01*
X221324Y584330D01*
X221407Y584622D01*
X221616Y584872D01*
X221991Y585038D01*
X222491Y585122D01*
X222782Y585288D01*
X222907Y585580D01*
X222824Y585872D01*
X222616Y586080D01*
X222324Y586205D01*
X222032D01*
X221741Y586122D01*
X221491Y585913D01*
G01X219932Y583705D02*
Y586205D01*
X218891D01*
X218557Y586080D01*
X218349Y585913D01*
X218266Y585580D01*
X218349Y585247D01*
X218599Y585038D01*
X218891Y584913D01*
X219932D01*
G01X218891D02*
X218266Y583705D01*
G01X215999D02*
X215707Y583747D01*
X215374Y583872D01*
X215166Y584080D01*
X215082Y584372D01*
X215166Y584663D01*
X215416Y584913D01*
X215791Y585038D01*
X216207D01*
X216457Y585122D01*
X216666Y585330D01*
X216749Y585622D01*
X216624Y585913D01*
X216332Y586122D01*
X215999Y586205D01*
X215666Y586122D01*
X215374Y585913D01*
X215249Y585622D01*
X215332Y585330D01*
X215541Y585122D01*
X215791Y585038D01*
X216207D01*
X216582Y584913D01*
X216832Y584663D01*
X216916Y584372D01*
X216832Y584080D01*
X216624Y583872D01*
X216291Y583747D01*
X215999Y583705D01*
G01X213816Y584080D02*
X213566Y583872D01*
X213274Y583747D01*
X212899Y583705D01*
X212524Y583788D01*
X212232Y583955D01*
X212024Y584247D01*
X211982Y584580D01*
X212066Y584913D01*
X212274Y585122D01*
X212566Y585288D01*
X212857Y585330D01*
X213149Y585288D01*
X213524Y585122D01*
X213399Y586205D01*
X212274D01*
G01X210591Y585788D02*
X210341Y586038D01*
X210049Y586163D01*
X209716Y586205D01*
X209299Y586122D01*
X209007Y585913D01*
X208924Y585663D01*
X208966Y585413D01*
X209132Y585205D01*
X209966Y584788D01*
X210341Y584497D01*
X210591Y584080D01*
X210674Y583705D01*
X208924D01*
G01X205500Y710800D02*
X201500D01*
Y718200D01*
G01X205500Y766300D02*
X201500D01*
Y773700D01*
G01X248795Y105975D02*
X251295D01*
Y107016D01*
X251170Y107350D01*
X251003Y107558D01*
X250670Y107641D01*
X250337Y107558D01*
X250128Y107308D01*
X250003Y107016D01*
Y105975D01*
G01Y107016D02*
X248795Y107641D01*
G01Y109825D02*
X249337Y109908D01*
X249795Y110033D01*
X250212Y110200D01*
X250670Y110408D01*
X251295Y110741D01*
Y109075D01*
G01Y113008D02*
X251212Y112675D01*
X251003Y112425D01*
X250753Y112258D01*
X250420Y112133D01*
X250045Y112091D01*
X249670Y112133D01*
X249337Y112258D01*
X249087Y112425D01*
X248878Y112675D01*
X248795Y113008D01*
X248878Y113341D01*
X249087Y113591D01*
X249337Y113758D01*
X249670Y113883D01*
X250045Y113925D01*
X250420Y113883D01*
X250753Y113758D01*
X251003Y113591D01*
X251212Y113341D01*
X251295Y113008D01*
G01Y116108D02*
X251212Y115775D01*
X251003Y115525D01*
X250753Y115358D01*
X250420Y115233D01*
X250045Y115191D01*
X249670Y115233D01*
X249337Y115358D01*
X249087Y115525D01*
X248878Y115775D01*
X248795Y116108D01*
X248878Y116441D01*
X249087Y116691D01*
X249337Y116858D01*
X249670Y116983D01*
X250045Y117025D01*
X250420Y116983D01*
X250753Y116858D01*
X251003Y116691D01*
X251212Y116441D01*
X251295Y116108D01*
G01X247995Y104158D02*
X251995D01*
Y96758D01*
G01X235700Y106417D02*
X238200D01*
Y107458D01*
X238075Y107792D01*
X237908Y108000D01*
X237575Y108083D01*
X237242Y108000D01*
X237033Y107750D01*
X236908Y107458D01*
Y106417D01*
G01Y107458D02*
X235700Y108083D01*
G01X236075Y109433D02*
X235867Y109683D01*
X235742Y109975D01*
X235700Y110350D01*
X235783Y110725D01*
X235950Y111017D01*
X236242Y111225D01*
X236575Y111267D01*
X236908Y111183D01*
X237117Y110975D01*
X237283Y110683D01*
X237325Y110392D01*
X237283Y110100D01*
X237117Y109725D01*
X238200Y109850D01*
Y110975D01*
G01X235700Y113367D02*
X236242Y113450D01*
X236700Y113575D01*
X237117Y113742D01*
X237575Y113950D01*
X238200Y114283D01*
Y112617D01*
G01X235700Y116550D02*
X238200D01*
X237700Y116050D01*
G01X235700D02*
Y117050D01*
G01X234800Y103900D02*
X238800D01*
Y96500D01*
G01X239500Y130300D02*
X235500D01*
Y137700D01*
G01X247500Y130300D02*
X243500D01*
Y137700D01*
G01Y130300D02*
X239500D01*
Y137700D01*
G01X266759Y149418D02*
X269259D01*
Y150418D01*
X269134Y150751D01*
X268842Y151001D01*
X268509Y151084D01*
X268176Y151001D01*
X267926Y150793D01*
X267801Y150418D01*
Y149418D01*
G01X269051Y154268D02*
X269176Y154018D01*
X269259Y153726D01*
Y153393D01*
X269134Y153018D01*
X268926Y152726D01*
X268676Y152518D01*
X268259Y152351D01*
X267884Y152309D01*
X267509Y152393D01*
X267259Y152518D01*
X267009Y152768D01*
X266842Y153059D01*
X266759Y153351D01*
Y153643D01*
X266842Y153934D01*
X266967Y154184D01*
X267134Y154393D01*
G01X268842Y155659D02*
X269092Y155909D01*
X269217Y156201D01*
X269259Y156534D01*
X269176Y156951D01*
X268967Y157243D01*
X268717Y157326D01*
X268467Y157284D01*
X268259Y157118D01*
X267842Y156284D01*
X267551Y155909D01*
X267134Y155659D01*
X266759Y155576D01*
Y157326D01*
G01Y159551D02*
X266801Y159843D01*
X266926Y160176D01*
X267134Y160384D01*
X267426Y160468D01*
X267717Y160384D01*
X267967Y160134D01*
X268092Y159759D01*
Y159343D01*
X268176Y159093D01*
X268384Y158884D01*
X268676Y158801D01*
X268967Y158926D01*
X269176Y159218D01*
X269259Y159551D01*
X269176Y159884D01*
X268967Y160176D01*
X268676Y160301D01*
X268384Y160218D01*
X268176Y160009D01*
X268092Y159759D01*
Y159343D01*
X267967Y158968D01*
X267717Y158718D01*
X267426Y158634D01*
X267134Y158718D01*
X266926Y158926D01*
X266801Y159259D01*
X266759Y159551D01*
G01X277083Y171500D02*
Y174000D01*
X276083D01*
X275750Y173875D01*
X275500Y173583D01*
X275417Y173250D01*
X275500Y172917D01*
X275708Y172667D01*
X276083Y172542D01*
X277083D01*
G01X273983Y171500D02*
Y174000D01*
X272942D01*
X272608Y173875D01*
X272400Y173708D01*
X272317Y173375D01*
X272400Y173042D01*
X272650Y172833D01*
X272942Y172708D01*
X273983D01*
G01X272942D02*
X272317Y171500D01*
G01X270842Y173583D02*
X270592Y173833D01*
X270300Y173958D01*
X269967Y174000D01*
X269550Y173917D01*
X269258Y173708D01*
X269175Y173458D01*
X269217Y173208D01*
X269383Y173000D01*
X270217Y172583D01*
X270592Y172292D01*
X270842Y171875D01*
X270925Y171500D01*
X269175D01*
G01X266950D02*
X266658Y171542D01*
X266325Y171667D01*
X266117Y171875D01*
X266033Y172167D01*
X266117Y172458D01*
X266367Y172708D01*
X266742Y172833D01*
X267158D01*
X267408Y172917D01*
X267617Y173125D01*
X267700Y173417D01*
X267575Y173708D01*
X267283Y173917D01*
X266950Y174000D01*
X266617Y173917D01*
X266325Y173708D01*
X266200Y173417D01*
X266283Y173125D01*
X266492Y172917D01*
X266742Y172833D01*
X267158D01*
X267533Y172708D01*
X267783Y172458D01*
X267867Y172167D01*
X267783Y171875D01*
X267575Y171667D01*
X267242Y171542D01*
X266950Y171500D01*
G01X271200Y162500D02*
X264800D01*
G01D02*
Y169500D01*
G01D02*
X273500D01*
G01X255975Y443252D02*
Y441460D01*
X255808Y441085D01*
X255475Y440835D01*
X255058Y440752D01*
X254641Y440835D01*
X254308Y441085D01*
X254141Y441460D01*
Y443252D01*
G01X251958Y440752D02*
Y443252D01*
X252458Y442752D01*
G01Y440752D02*
X251458D01*
G01X249775Y441252D02*
X249525Y440960D01*
X249191Y440794D01*
X248816Y440752D01*
X248483Y440794D01*
X248150Y441002D01*
X247941Y441252D01*
X247900Y441502D01*
X247983Y441794D01*
X248275Y442002D01*
X248566Y442085D01*
X248941D01*
G01X248566D02*
X248316Y442210D01*
X248108Y442419D01*
X248025Y442669D01*
X248108Y442919D01*
X248316Y443127D01*
X248691Y443252D01*
X249066Y443210D01*
X249441Y443044D01*
G01X240952Y437085D02*
X243452D01*
Y438126D01*
X243327Y438460D01*
X243160Y438668D01*
X242827Y438751D01*
X242494Y438668D01*
X242285Y438418D01*
X242160Y438126D01*
Y437085D01*
G01Y438126D02*
X240952Y438751D01*
G01Y441018D02*
X243452D01*
X242952Y440518D01*
G01X240952D02*
Y441518D01*
G01X241244Y443410D02*
X241035Y443701D01*
X240952Y444035D01*
X241035Y444368D01*
X241285Y444660D01*
X241660Y444868D01*
X242035Y444951D01*
X242494D01*
X242869Y444868D01*
X243202Y444660D01*
X243369Y444410D01*
X243452Y444118D01*
X243369Y443785D01*
X243202Y443535D01*
X242952Y443368D01*
X242619Y443285D01*
X242327Y443368D01*
X242035Y443576D01*
X241869Y443826D01*
X241827Y444118D01*
X241910Y444451D01*
X242119Y444701D01*
X242494Y444951D01*
G01X255868Y437166D02*
Y439666D01*
X254827D01*
X254493Y439541D01*
X254285Y439374D01*
X254202Y439041D01*
X254285Y438708D01*
X254535Y438499D01*
X254827Y438374D01*
X255868D01*
G01X254827D02*
X254202Y437166D01*
G01X252852Y437666D02*
X252602Y437374D01*
X252268Y437208D01*
X251893Y437166D01*
X251560Y437208D01*
X251227Y437416D01*
X251018Y437666D01*
X250977Y437916D01*
X251060Y438208D01*
X251352Y438416D01*
X251643Y438499D01*
X252018D01*
G01X251643D02*
X251393Y438624D01*
X251185Y438833D01*
X251102Y439083D01*
X251185Y439333D01*
X251393Y439541D01*
X251768Y439666D01*
X252143Y439624D01*
X252518Y439458D01*
G01X248835Y439666D02*
X249168Y439583D01*
X249418Y439374D01*
X249585Y439124D01*
X249710Y438791D01*
X249752Y438416D01*
X249710Y438041D01*
X249585Y437708D01*
X249418Y437458D01*
X249168Y437249D01*
X248835Y437166D01*
X248502Y437249D01*
X248252Y437458D01*
X248085Y437708D01*
X247960Y438041D01*
X247918Y438416D01*
X247960Y438791D01*
X248085Y439124D01*
X248252Y439374D01*
X248502Y439583D01*
X248835Y439666D01*
G01X245735D02*
X246068Y439583D01*
X246318Y439374D01*
X246485Y439124D01*
X246610Y438791D01*
X246652Y438416D01*
X246610Y438041D01*
X246485Y437708D01*
X246318Y437458D01*
X246068Y437249D01*
X245735Y437166D01*
X245402Y437249D01*
X245152Y437458D01*
X244985Y437708D01*
X244860Y438041D01*
X244818Y438416D01*
X244860Y438791D01*
X244985Y439124D01*
X245152Y439374D01*
X245402Y439583D01*
X245735Y439666D01*
G01X235693Y427626D02*
X238193D01*
Y428667D01*
X238068Y429001D01*
X237901Y429209D01*
X237568Y429292D01*
X237235Y429209D01*
X237026Y428959D01*
X236901Y428667D01*
Y427626D01*
G01Y428667D02*
X235693Y429292D01*
G01Y432059D02*
X238193D01*
X236401Y430517D01*
Y432601D01*
G01X235693Y434576D02*
X236235Y434659D01*
X236693Y434784D01*
X237110Y434951D01*
X237568Y435159D01*
X238193Y435492D01*
Y433826D01*
G01X236068Y436842D02*
X235860Y437092D01*
X235735Y437384D01*
X235693Y437759D01*
X235776Y438134D01*
X235943Y438426D01*
X236235Y438634D01*
X236568Y438676D01*
X236901Y438592D01*
X237110Y438384D01*
X237276Y438092D01*
X237318Y437801D01*
X237276Y437509D01*
X237110Y437134D01*
X238193Y437259D01*
Y438384D01*
G01X235399Y441028D02*
X237899D01*
Y442069D01*
X237774Y442403D01*
X237607Y442611D01*
X237274Y442694D01*
X236941Y442611D01*
X236732Y442361D01*
X236607Y442069D01*
Y441028D01*
G01Y442069D02*
X235399Y442694D01*
G01X235774Y444044D02*
X235566Y444294D01*
X235441Y444586D01*
X235399Y444961D01*
X235482Y445336D01*
X235649Y445628D01*
X235941Y445836D01*
X236274Y445878D01*
X236607Y445794D01*
X236816Y445586D01*
X236982Y445294D01*
X237024Y445003D01*
X236982Y444711D01*
X236816Y444336D01*
X237899Y444461D01*
Y445586D01*
G01X237482Y447269D02*
X237732Y447519D01*
X237857Y447811D01*
X237899Y448144D01*
X237816Y448561D01*
X237607Y448853D01*
X237357Y448936D01*
X237107Y448894D01*
X236899Y448728D01*
X236482Y447894D01*
X236191Y447519D01*
X235774Y447269D01*
X235399Y447186D01*
Y448936D01*
G01X237899Y451161D02*
X237816Y450828D01*
X237607Y450578D01*
X237357Y450411D01*
X237024Y450286D01*
X236649Y450244D01*
X236274Y450286D01*
X235941Y450411D01*
X235691Y450578D01*
X235482Y450828D01*
X235399Y451161D01*
X235482Y451494D01*
X235691Y451744D01*
X235941Y451911D01*
X236274Y452036D01*
X236649Y452078D01*
X237024Y452036D01*
X237357Y451911D01*
X237607Y451744D01*
X237816Y451494D01*
X237899Y451161D01*
G01X237700Y457900D02*
Y471300D01*
G01D02*
X249100D01*
G01D02*
Y457900D01*
G01D02*
X237700D01*
G01X248800Y475500D02*
Y479500D01*
X256200D01*
G01X237100Y460800D02*
X233100D01*
Y468200D01*
G01X255200Y462567D02*
X257700D01*
Y463608D01*
X257575Y463942D01*
X257408Y464150D01*
X257075Y464233D01*
X256742Y464150D01*
X256533Y463900D01*
X256408Y463608D01*
Y462567D01*
G01Y463608D02*
X255200Y464233D01*
G01X257283Y465708D02*
X257533Y465958D01*
X257658Y466250D01*
X257700Y466583D01*
X257617Y467000D01*
X257408Y467292D01*
X257158Y467375D01*
X256908Y467333D01*
X256700Y467167D01*
X256283Y466333D01*
X255992Y465958D01*
X255575Y465708D01*
X255200Y465625D01*
Y467375D01*
G01Y469600D02*
X257700D01*
X257200Y469100D01*
G01X255200D02*
Y470100D01*
G01X253800Y461000D02*
X249800D01*
Y468400D01*
G01X245200Y480000D02*
Y476000D01*
X237800D01*
G01X238200Y453600D02*
Y457600D01*
X245600D01*
G01X238200Y471600D02*
Y475600D01*
X245600D01*
G01X267238Y479600D02*
Y475600D01*
X259838D01*
G01X274028Y484871D02*
Y487371D01*
X272987D01*
X272653Y487246D01*
X272445Y487079D01*
X272362Y486746D01*
X272445Y486413D01*
X272695Y486204D01*
X272987Y486079D01*
X274028D01*
G01X272987D02*
X272362Y484871D01*
G01X270887Y486954D02*
X270637Y487204D01*
X270345Y487329D01*
X270012Y487371D01*
X269595Y487288D01*
X269303Y487079D01*
X269220Y486829D01*
X269262Y486579D01*
X269428Y486371D01*
X270262Y485954D01*
X270637Y485663D01*
X270887Y485246D01*
X270970Y484871D01*
X269220D01*
G01X266495D02*
Y487371D01*
X268037Y485579D01*
X265953D01*
G01X263395Y484871D02*
Y487371D01*
X264937Y485579D01*
X262853D01*
G01X274028Y488871D02*
Y491371D01*
X272987D01*
X272653Y491246D01*
X272445Y491079D01*
X272362Y490746D01*
X272445Y490413D01*
X272695Y490204D01*
X272987Y490079D01*
X274028D01*
G01X272987D02*
X272362Y488871D01*
G01X270887Y490954D02*
X270637Y491204D01*
X270345Y491329D01*
X270012Y491371D01*
X269595Y491288D01*
X269303Y491079D01*
X269220Y490829D01*
X269262Y490579D01*
X269428Y490371D01*
X270262Y489954D01*
X270637Y489663D01*
X270887Y489246D01*
X270970Y488871D01*
X269220D01*
G01X266495D02*
Y491371D01*
X268037Y489579D01*
X265953D01*
G01X264812Y489246D02*
X264562Y489038D01*
X264270Y488913D01*
X263895Y488871D01*
X263520Y488954D01*
X263228Y489121D01*
X263020Y489413D01*
X262978Y489746D01*
X263062Y490079D01*
X263270Y490288D01*
X263562Y490454D01*
X263853Y490496D01*
X264145Y490454D01*
X264520Y490288D01*
X264395Y491371D01*
X263270D01*
G01X248800Y479500D02*
Y483500D01*
X256200D01*
G01X273028Y493371D02*
Y495871D01*
X271987D01*
X271653Y495746D01*
X271445Y495579D01*
X271362Y495246D01*
X271445Y494913D01*
X271695Y494704D01*
X271987Y494579D01*
X273028D01*
G01X271987D02*
X271362Y493371D01*
G01X269887Y495454D02*
X269637Y495704D01*
X269345Y495829D01*
X269012Y495871D01*
X268595Y495788D01*
X268303Y495579D01*
X268220Y495329D01*
X268262Y495079D01*
X268428Y494871D01*
X269262Y494454D01*
X269637Y494163D01*
X269887Y493746D01*
X269970Y493371D01*
X268220D01*
G01X265495D02*
Y495871D01*
X267037Y494079D01*
X264953D01*
G01X263603Y493663D02*
X263312Y493454D01*
X262978Y493371D01*
X262645Y493454D01*
X262353Y493704D01*
X262145Y494079D01*
X262062Y494454D01*
Y494913D01*
X262145Y495288D01*
X262353Y495621D01*
X262603Y495788D01*
X262895Y495871D01*
X263228Y495788D01*
X263478Y495621D01*
X263645Y495371D01*
X263728Y495038D01*
X263645Y494746D01*
X263437Y494454D01*
X263187Y494288D01*
X262895Y494246D01*
X262562Y494329D01*
X262312Y494538D01*
X262062Y494913D01*
G01X247800Y484000D02*
Y488000D01*
X255200D01*
G01X273028Y497371D02*
Y499871D01*
X271987D01*
X271653Y499746D01*
X271445Y499579D01*
X271362Y499246D01*
X271445Y498913D01*
X271695Y498704D01*
X271987Y498579D01*
X273028D01*
G01X271987D02*
X271362Y497371D01*
G01X269887Y499454D02*
X269637Y499704D01*
X269345Y499829D01*
X269012Y499871D01*
X268595Y499788D01*
X268303Y499579D01*
X268220Y499329D01*
X268262Y499079D01*
X268428Y498871D01*
X269262Y498454D01*
X269637Y498163D01*
X269887Y497746D01*
X269970Y497371D01*
X268220D01*
G01X266912Y497746D02*
X266662Y497538D01*
X266370Y497413D01*
X265995Y497371D01*
X265620Y497454D01*
X265328Y497621D01*
X265120Y497913D01*
X265078Y498246D01*
X265162Y498579D01*
X265370Y498788D01*
X265662Y498954D01*
X265953Y498996D01*
X266245Y498954D01*
X266620Y498788D01*
X266495Y499871D01*
X265370D01*
G01X262895Y497371D02*
Y499871D01*
X263395Y499371D01*
G01Y497371D02*
X262395D01*
G01X247800Y488000D02*
Y492000D01*
X255200D01*
G01X273028Y501471D02*
Y503971D01*
X271987D01*
X271653Y503846D01*
X271445Y503679D01*
X271362Y503346D01*
X271445Y503013D01*
X271695Y502804D01*
X271987Y502679D01*
X273028D01*
G01X271987D02*
X271362Y501471D01*
G01X269887Y503554D02*
X269637Y503804D01*
X269345Y503929D01*
X269012Y503971D01*
X268595Y503888D01*
X268303Y503679D01*
X268220Y503429D01*
X268262Y503179D01*
X268428Y502971D01*
X269262Y502554D01*
X269637Y502263D01*
X269887Y501846D01*
X269970Y501471D01*
X268220D01*
G01X265995D02*
X265703Y501513D01*
X265370Y501638D01*
X265162Y501846D01*
X265078Y502138D01*
X265162Y502429D01*
X265412Y502679D01*
X265787Y502804D01*
X266203D01*
X266453Y502888D01*
X266662Y503096D01*
X266745Y503388D01*
X266620Y503679D01*
X266328Y503888D01*
X265995Y503971D01*
X265662Y503888D01*
X265370Y503679D01*
X265245Y503388D01*
X265328Y503096D01*
X265537Y502888D01*
X265787Y502804D01*
X266203D01*
X266578Y502679D01*
X266828Y502429D01*
X266912Y502138D01*
X266828Y501846D01*
X266620Y501638D01*
X266287Y501513D01*
X265995Y501471D01*
G01X262895Y503971D02*
X263228Y503888D01*
X263478Y503679D01*
X263645Y503429D01*
X263770Y503096D01*
X263812Y502721D01*
X263770Y502346D01*
X263645Y502013D01*
X263478Y501763D01*
X263228Y501554D01*
X262895Y501471D01*
X262562Y501554D01*
X262312Y501763D01*
X262145Y502013D01*
X262020Y502346D01*
X261978Y502721D01*
X262020Y503096D01*
X262145Y503429D01*
X262312Y503679D01*
X262562Y503888D01*
X262895Y503971D01*
G01X255200Y496100D02*
Y492100D01*
X247800D01*
G01X245200Y492000D02*
Y488000D01*
X237800D01*
G01X245200D02*
Y484000D01*
X237800D01*
G01X245200D02*
Y480000D01*
X237800D01*
G01X255826Y512928D02*
Y515428D01*
X254785D01*
X254451Y515303D01*
X254243Y515136D01*
X254160Y514803D01*
X254243Y514470D01*
X254493Y514261D01*
X254785Y514136D01*
X255826D01*
G01X254785D02*
X254160Y512928D01*
G01X251393D02*
Y515428D01*
X252935Y513636D01*
X250851D01*
G01X249710Y513303D02*
X249460Y513095D01*
X249168Y512970D01*
X248793Y512928D01*
X248418Y513011D01*
X248126Y513178D01*
X247918Y513470D01*
X247876Y513803D01*
X247960Y514136D01*
X248168Y514345D01*
X248460Y514511D01*
X248751Y514553D01*
X249043Y514511D01*
X249418Y514345D01*
X249293Y515428D01*
X248168D01*
G01X246485Y513970D02*
X246193Y514261D01*
X245943Y514428D01*
X245610Y514511D01*
X245318Y514428D01*
X245110Y514261D01*
X244943Y514011D01*
X244901Y513720D01*
X244943Y513470D01*
X245110Y513220D01*
X245360Y513011D01*
X245651Y512928D01*
X245985Y513011D01*
X246276Y513261D01*
X246443Y513636D01*
X246485Y514053D01*
X246401Y514595D01*
X246276Y514886D01*
X246068Y515178D01*
X245776Y515386D01*
X245485Y515428D01*
X245193Y515345D01*
X244985Y515136D01*
G01X255487Y509192D02*
Y511692D01*
X254446D01*
X254112Y511567D01*
X253904Y511400D01*
X253821Y511067D01*
X253904Y510734D01*
X254154Y510525D01*
X254446Y510400D01*
X255487D01*
G01X254446D02*
X253821Y509192D01*
G01X251054D02*
Y511692D01*
X252596Y509900D01*
X250512D01*
G01X249371Y509567D02*
X249121Y509359D01*
X248829Y509234D01*
X248454Y509192D01*
X248079Y509275D01*
X247787Y509442D01*
X247579Y509734D01*
X247537Y510067D01*
X247621Y510400D01*
X247829Y510609D01*
X248121Y510775D01*
X248412Y510817D01*
X248704Y510775D01*
X249079Y510609D01*
X248954Y511692D01*
X247829D01*
G01X245437Y509192D02*
X245354Y509734D01*
X245229Y510192D01*
X245062Y510609D01*
X244854Y511067D01*
X244521Y511692D01*
X246187D01*
G01X268583Y512700D02*
Y515200D01*
X267542D01*
X267208Y515075D01*
X267000Y514908D01*
X266917Y514575D01*
X267000Y514242D01*
X267250Y514033D01*
X267542Y513908D01*
X268583D01*
G01X267542D02*
X266917Y512700D01*
G01X264150D02*
Y515200D01*
X265692Y513408D01*
X263608D01*
G01X262342Y514783D02*
X262092Y515033D01*
X261800Y515158D01*
X261467Y515200D01*
X261050Y515117D01*
X260758Y514908D01*
X260675Y514658D01*
X260717Y514408D01*
X260883Y514200D01*
X261717Y513783D01*
X262092Y513492D01*
X262342Y513075D01*
X262425Y512700D01*
X260675D01*
G01X258450Y515200D02*
X258783Y515117D01*
X259033Y514908D01*
X259200Y514658D01*
X259325Y514325D01*
X259367Y513950D01*
X259325Y513575D01*
X259200Y513242D01*
X259033Y512992D01*
X258783Y512783D01*
X258450Y512700D01*
X258117Y512783D01*
X257867Y512992D01*
X257700Y513242D01*
X257575Y513575D01*
X257533Y513950D01*
X257575Y514325D01*
X257700Y514658D01*
X257867Y514908D01*
X258117Y515117D01*
X258450Y515200D01*
G01X249000Y503600D02*
X253000D01*
Y496200D01*
G01X267238Y483600D02*
Y479600D01*
X259838D01*
G01X244295Y520499D02*
X246795D01*
Y521540D01*
X246670Y521874D01*
X246503Y522082D01*
X246170Y522165D01*
X245837Y522082D01*
X245628Y521832D01*
X245503Y521540D01*
Y520499D01*
G01Y521540D02*
X244295Y522165D01*
G01X244670Y523515D02*
X244462Y523765D01*
X244337Y524057D01*
X244295Y524432D01*
X244378Y524807D01*
X244545Y525099D01*
X244837Y525307D01*
X245170Y525349D01*
X245503Y525265D01*
X245712Y525057D01*
X245878Y524765D01*
X245920Y524474D01*
X245878Y524182D01*
X245712Y523807D01*
X246795Y523932D01*
Y525057D01*
G01X244295Y527449D02*
X244837Y527532D01*
X245295Y527657D01*
X245712Y527824D01*
X246170Y528032D01*
X246795Y528365D01*
Y526699D01*
G01X245337Y529840D02*
X245628Y530132D01*
X245795Y530382D01*
X245878Y530715D01*
X245795Y531007D01*
X245628Y531215D01*
X245378Y531382D01*
X245087Y531424D01*
X244837Y531382D01*
X244587Y531215D01*
X244378Y530965D01*
X244295Y530674D01*
X244378Y530340D01*
X244628Y530049D01*
X245003Y529882D01*
X245420Y529840D01*
X245962Y529924D01*
X246253Y530049D01*
X246545Y530257D01*
X246753Y530549D01*
X246795Y530840D01*
X246712Y531132D01*
X246503Y531340D01*
G01X244295Y533732D02*
X244337Y534024D01*
X244462Y534357D01*
X244670Y534565D01*
X244962Y534649D01*
X245253Y534565D01*
X245503Y534315D01*
X245628Y533940D01*
Y533524D01*
X245712Y533274D01*
X245920Y533065D01*
X246212Y532982D01*
X246503Y533107D01*
X246712Y533399D01*
X246795Y533732D01*
X246712Y534065D01*
X246503Y534357D01*
X246212Y534482D01*
X245920Y534399D01*
X245712Y534190D01*
X245628Y533940D01*
Y533524D01*
X245503Y533149D01*
X245253Y532899D01*
X244962Y532815D01*
X244670Y532899D01*
X244462Y533107D01*
X244337Y533440D01*
X244295Y533732D01*
G01X240295Y520499D02*
X242795D01*
Y521540D01*
X242670Y521874D01*
X242503Y522082D01*
X242170Y522165D01*
X241837Y522082D01*
X241628Y521832D01*
X241503Y521540D01*
Y520499D01*
G01Y521540D02*
X240295Y522165D01*
G01X240670Y523515D02*
X240462Y523765D01*
X240337Y524057D01*
X240295Y524432D01*
X240378Y524807D01*
X240545Y525099D01*
X240837Y525307D01*
X241170Y525349D01*
X241503Y525265D01*
X241712Y525057D01*
X241878Y524765D01*
X241920Y524474D01*
X241878Y524182D01*
X241712Y523807D01*
X242795Y523932D01*
Y525057D01*
G01X240295Y527449D02*
X240837Y527532D01*
X241295Y527657D01*
X241712Y527824D01*
X242170Y528032D01*
X242795Y528365D01*
Y526699D01*
G01X240295Y530549D02*
X240837Y530632D01*
X241295Y530757D01*
X241712Y530924D01*
X242170Y531132D01*
X242795Y531465D01*
Y529799D01*
G01Y533732D02*
X242712Y533399D01*
X242503Y533149D01*
X242253Y532982D01*
X241920Y532857D01*
X241545Y532815D01*
X241170Y532857D01*
X240837Y532982D01*
X240587Y533149D01*
X240378Y533399D01*
X240295Y533732D01*
X240378Y534065D01*
X240587Y534315D01*
X240837Y534482D01*
X241170Y534607D01*
X241545Y534649D01*
X241920Y534607D01*
X242253Y534482D01*
X242503Y534315D01*
X242712Y534065D01*
X242795Y533732D01*
G01X240530Y536844D02*
X243030D01*
Y537885D01*
X242905Y538219D01*
X242738Y538427D01*
X242405Y538510D01*
X242072Y538427D01*
X241863Y538177D01*
X241738Y537885D01*
Y536844D01*
G01Y537885D02*
X240530Y538510D01*
G01X240905Y539860D02*
X240697Y540110D01*
X240572Y540402D01*
X240530Y540777D01*
X240613Y541152D01*
X240780Y541444D01*
X241072Y541652D01*
X241405Y541694D01*
X241738Y541610D01*
X241947Y541402D01*
X242113Y541110D01*
X242155Y540819D01*
X242113Y540527D01*
X241947Y540152D01*
X243030Y540277D01*
Y541402D01*
G01X240530Y543794D02*
X241072Y543877D01*
X241530Y544002D01*
X241947Y544169D01*
X242405Y544377D01*
X243030Y544710D01*
Y543044D01*
G01X240530Y546894D02*
X241072Y546977D01*
X241530Y547102D01*
X241947Y547269D01*
X242405Y547477D01*
X243030Y547810D01*
Y546144D01*
G01X240530Y550077D02*
X243030D01*
X242530Y549577D01*
G01X240530D02*
Y550577D01*
G01X244530Y536844D02*
X247030D01*
Y537885D01*
X246905Y538219D01*
X246738Y538427D01*
X246405Y538510D01*
X246072Y538427D01*
X245863Y538177D01*
X245738Y537885D01*
Y536844D01*
G01Y537885D02*
X244530Y538510D01*
G01Y541277D02*
X247030D01*
X245238Y539735D01*
Y541819D01*
G01X245030Y542960D02*
X244738Y543210D01*
X244572Y543544D01*
X244530Y543919D01*
X244572Y544252D01*
X244780Y544585D01*
X245030Y544794D01*
X245280Y544835D01*
X245572Y544752D01*
X245780Y544460D01*
X245863Y544169D01*
Y543794D01*
G01Y544169D02*
X245988Y544419D01*
X246197Y544627D01*
X246447Y544710D01*
X246697Y544627D01*
X246905Y544419D01*
X247030Y544044D01*
X246988Y543669D01*
X246822Y543294D01*
G01X244530Y547477D02*
X247030D01*
X245238Y545935D01*
Y548019D01*
G01X238587Y522249D02*
X238712Y521999D01*
X238795Y521707D01*
Y521374D01*
X238670Y520999D01*
X238462Y520707D01*
X238212Y520499D01*
X237795Y520332D01*
X237420Y520290D01*
X237045Y520374D01*
X236795Y520499D01*
X236545Y520749D01*
X236378Y521040D01*
X236295Y521332D01*
Y521624D01*
X236378Y521915D01*
X236503Y522165D01*
X236670Y522374D01*
G01X236295Y524432D02*
X236337Y524724D01*
X236462Y525057D01*
X236670Y525265D01*
X236962Y525349D01*
X237253Y525265D01*
X237503Y525015D01*
X237628Y524640D01*
Y524224D01*
X237712Y523974D01*
X237920Y523765D01*
X238212Y523682D01*
X238503Y523807D01*
X238712Y524099D01*
X238795Y524432D01*
X238712Y524765D01*
X238503Y525057D01*
X238212Y525182D01*
X237920Y525099D01*
X237712Y524890D01*
X237628Y524640D01*
Y524224D01*
X237503Y523849D01*
X237253Y523599D01*
X236962Y523515D01*
X236670Y523599D01*
X236462Y523807D01*
X236337Y524140D01*
X236295Y524432D01*
G01X238795Y527532D02*
X238712Y527199D01*
X238503Y526949D01*
X238253Y526782D01*
X237920Y526657D01*
X237545Y526615D01*
X237170Y526657D01*
X236837Y526782D01*
X236587Y526949D01*
X236378Y527199D01*
X236295Y527532D01*
X236378Y527865D01*
X236587Y528115D01*
X236837Y528282D01*
X237170Y528407D01*
X237545Y528449D01*
X237920Y528407D01*
X238253Y528282D01*
X238503Y528115D01*
X238712Y527865D01*
X238795Y527532D01*
G01X236295Y530632D02*
X236337Y530924D01*
X236462Y531257D01*
X236670Y531465D01*
X236962Y531549D01*
X237253Y531465D01*
X237503Y531215D01*
X237628Y530840D01*
Y530424D01*
X237712Y530174D01*
X237920Y529965D01*
X238212Y529882D01*
X238503Y530007D01*
X238712Y530299D01*
X238795Y530632D01*
X238712Y530965D01*
X238503Y531257D01*
X238212Y531382D01*
X237920Y531299D01*
X237712Y531090D01*
X237628Y530840D01*
Y530424D01*
X237503Y530049D01*
X237253Y529799D01*
X236962Y529715D01*
X236670Y529799D01*
X236462Y530007D01*
X236337Y530340D01*
X236295Y530632D01*
G01Y533649D02*
X236837Y533732D01*
X237295Y533857D01*
X237712Y534024D01*
X238170Y534232D01*
X238795Y534565D01*
Y532899D01*
G01X238822Y538594D02*
X238947Y538344D01*
X239030Y538052D01*
Y537719D01*
X238905Y537344D01*
X238697Y537052D01*
X238447Y536844D01*
X238030Y536677D01*
X237655Y536635D01*
X237280Y536719D01*
X237030Y536844D01*
X236780Y537094D01*
X236613Y537385D01*
X236530Y537677D01*
Y537969D01*
X236613Y538260D01*
X236738Y538510D01*
X236905Y538719D01*
G01X236530Y540777D02*
X236572Y541069D01*
X236697Y541402D01*
X236905Y541610D01*
X237197Y541694D01*
X237488Y541610D01*
X237738Y541360D01*
X237863Y540985D01*
Y540569D01*
X237947Y540319D01*
X238155Y540110D01*
X238447Y540027D01*
X238738Y540152D01*
X238947Y540444D01*
X239030Y540777D01*
X238947Y541110D01*
X238738Y541402D01*
X238447Y541527D01*
X238155Y541444D01*
X237947Y541235D01*
X237863Y540985D01*
Y540569D01*
X237738Y540194D01*
X237488Y539944D01*
X237197Y539860D01*
X236905Y539944D01*
X236697Y540152D01*
X236572Y540485D01*
X236530Y540777D01*
G01X239030Y543877D02*
X238947Y543544D01*
X238738Y543294D01*
X238488Y543127D01*
X238155Y543002D01*
X237780Y542960D01*
X237405Y543002D01*
X237072Y543127D01*
X236822Y543294D01*
X236613Y543544D01*
X236530Y543877D01*
X236613Y544210D01*
X236822Y544460D01*
X237072Y544627D01*
X237405Y544752D01*
X237780Y544794D01*
X238155Y544752D01*
X238488Y544627D01*
X238738Y544460D01*
X238947Y544210D01*
X239030Y543877D01*
G01X236530Y546977D02*
X236572Y547269D01*
X236697Y547602D01*
X236905Y547810D01*
X237197Y547894D01*
X237488Y547810D01*
X237738Y547560D01*
X237863Y547185D01*
Y546769D01*
X237947Y546519D01*
X238155Y546310D01*
X238447Y546227D01*
X238738Y546352D01*
X238947Y546644D01*
X239030Y546977D01*
X238947Y547310D01*
X238738Y547602D01*
X238447Y547727D01*
X238155Y547644D01*
X237947Y547435D01*
X237863Y547185D01*
Y546769D01*
X237738Y546394D01*
X237488Y546144D01*
X237197Y546060D01*
X236905Y546144D01*
X236697Y546352D01*
X236572Y546685D01*
X236530Y546977D01*
G01Y550077D02*
X236572Y550369D01*
X236697Y550702D01*
X236905Y550910D01*
X237197Y550994D01*
X237488Y550910D01*
X237738Y550660D01*
X237863Y550285D01*
Y549869D01*
X237947Y549619D01*
X238155Y549410D01*
X238447Y549327D01*
X238738Y549452D01*
X238947Y549744D01*
X239030Y550077D01*
X238947Y550410D01*
X238738Y550702D01*
X238447Y550827D01*
X238155Y550744D01*
X237947Y550535D01*
X237863Y550285D01*
Y549869D01*
X237738Y549494D01*
X237488Y549244D01*
X237197Y549160D01*
X236905Y549244D01*
X236697Y549452D01*
X236572Y549785D01*
X236530Y550077D01*
G01X264983Y578461D02*
Y580961D01*
X263942D01*
X263608Y580836D01*
X263400Y580669D01*
X263317Y580336D01*
X263400Y580003D01*
X263650Y579794D01*
X263942Y579669D01*
X264983D01*
G01X263942D02*
X263317Y578461D01*
G01X261842Y580544D02*
X261592Y580794D01*
X261300Y580919D01*
X260967Y580961D01*
X260550Y580878D01*
X260258Y580669D01*
X260175Y580419D01*
X260217Y580169D01*
X260383Y579961D01*
X261217Y579544D01*
X261592Y579253D01*
X261842Y578836D01*
X261925Y578461D01*
X260175D01*
G01X257950Y580961D02*
X258283Y580878D01*
X258533Y580669D01*
X258700Y580419D01*
X258825Y580086D01*
X258867Y579711D01*
X258825Y579336D01*
X258700Y579003D01*
X258533Y578753D01*
X258283Y578544D01*
X257950Y578461D01*
X257617Y578544D01*
X257367Y578753D01*
X257200Y579003D01*
X257075Y579336D01*
X257033Y579711D01*
X257075Y580086D01*
X257200Y580419D01*
X257367Y580669D01*
X257617Y580878D01*
X257950Y580961D01*
G01X254850Y578461D02*
X254558Y578503D01*
X254225Y578628D01*
X254017Y578836D01*
X253933Y579128D01*
X254017Y579419D01*
X254267Y579669D01*
X254642Y579794D01*
X255058D01*
X255308Y579878D01*
X255517Y580086D01*
X255600Y580378D01*
X255475Y580669D01*
X255183Y580878D01*
X254850Y580961D01*
X254517Y580878D01*
X254225Y580669D01*
X254100Y580378D01*
X254183Y580086D01*
X254392Y579878D01*
X254642Y579794D01*
X255058D01*
X255433Y579669D01*
X255683Y579419D01*
X255767Y579128D01*
X255683Y578836D01*
X255475Y578628D01*
X255142Y578503D01*
X254850Y578461D01*
G01X237354Y553791D02*
X239854D01*
Y554832D01*
X239729Y555166D01*
X239562Y555374D01*
X239229Y555457D01*
X238896Y555374D01*
X238687Y555124D01*
X238562Y554832D01*
Y553791D01*
G01Y554832D02*
X237354Y555457D01*
G01X237854Y556807D02*
X237562Y557057D01*
X237396Y557391D01*
X237354Y557766D01*
X237396Y558099D01*
X237604Y558432D01*
X237854Y558641D01*
X238104Y558682D01*
X238396Y558599D01*
X238604Y558307D01*
X238687Y558016D01*
Y557641D01*
G01Y558016D02*
X238812Y558266D01*
X239021Y558474D01*
X239271Y558557D01*
X239521Y558474D01*
X239729Y558266D01*
X239854Y557891D01*
X239812Y557516D01*
X239646Y557141D01*
G01X237354Y560824D02*
X239854D01*
X239354Y560324D01*
G01X237354D02*
Y561324D01*
G01X239854Y563924D02*
X239771Y563591D01*
X239562Y563341D01*
X239312Y563174D01*
X238979Y563049D01*
X238604Y563007D01*
X238229Y563049D01*
X237896Y563174D01*
X237646Y563341D01*
X237437Y563591D01*
X237354Y563924D01*
X237437Y564257D01*
X237646Y564507D01*
X237896Y564674D01*
X238229Y564799D01*
X238604Y564841D01*
X238979Y564799D01*
X239312Y564674D01*
X239562Y564507D01*
X239771Y564257D01*
X239854Y563924D01*
G01Y567024D02*
X239771Y566691D01*
X239562Y566441D01*
X239312Y566274D01*
X238979Y566149D01*
X238604Y566107D01*
X238229Y566149D01*
X237896Y566274D01*
X237646Y566441D01*
X237437Y566691D01*
X237354Y567024D01*
X237437Y567357D01*
X237646Y567607D01*
X237896Y567774D01*
X238229Y567899D01*
X238604Y567941D01*
X238979Y567899D01*
X239312Y567774D01*
X239562Y567607D01*
X239771Y567357D01*
X239854Y567024D01*
G01X241354Y553791D02*
X243854D01*
Y554832D01*
X243729Y555166D01*
X243562Y555374D01*
X243229Y555457D01*
X242896Y555374D01*
X242687Y555124D01*
X242562Y554832D01*
Y553791D01*
G01Y554832D02*
X241354Y555457D01*
G01X241729Y556807D02*
X241521Y557057D01*
X241396Y557349D01*
X241354Y557724D01*
X241437Y558099D01*
X241604Y558391D01*
X241896Y558599D01*
X242229Y558641D01*
X242562Y558557D01*
X242771Y558349D01*
X242937Y558057D01*
X242979Y557766D01*
X242937Y557474D01*
X242771Y557099D01*
X243854Y557224D01*
Y558349D01*
G01X241354Y560741D02*
X241896Y560824D01*
X242354Y560949D01*
X242771Y561116D01*
X243229Y561324D01*
X243854Y561657D01*
Y559991D01*
G01X242396Y563132D02*
X242687Y563424D01*
X242854Y563674D01*
X242937Y564007D01*
X242854Y564299D01*
X242687Y564507D01*
X242437Y564674D01*
X242146Y564716D01*
X241896Y564674D01*
X241646Y564507D01*
X241437Y564257D01*
X241354Y563966D01*
X241437Y563632D01*
X241687Y563341D01*
X242062Y563174D01*
X242479Y563132D01*
X243021Y563216D01*
X243312Y563341D01*
X243604Y563549D01*
X243812Y563841D01*
X243854Y564132D01*
X243771Y564424D01*
X243562Y564632D01*
G01X241854Y566107D02*
X241562Y566357D01*
X241396Y566691D01*
X241354Y567066D01*
X241396Y567399D01*
X241604Y567732D01*
X241854Y567941D01*
X242104Y567982D01*
X242396Y567899D01*
X242604Y567607D01*
X242687Y567316D01*
Y566941D01*
G01Y567316D02*
X242812Y567566D01*
X243021Y567774D01*
X243271Y567857D01*
X243521Y567774D01*
X243729Y567566D01*
X243854Y567191D01*
X243812Y566816D01*
X243646Y566441D01*
G01X265700Y590500D02*
Y586500D01*
X258300D01*
G01X264883Y582061D02*
Y584561D01*
X263842D01*
X263508Y584436D01*
X263300Y584269D01*
X263217Y583936D01*
X263300Y583603D01*
X263550Y583394D01*
X263842Y583269D01*
X264883D01*
G01X263842D02*
X263217Y582061D01*
G01X261742Y584144D02*
X261492Y584394D01*
X261200Y584519D01*
X260867Y584561D01*
X260450Y584478D01*
X260158Y584269D01*
X260075Y584019D01*
X260117Y583769D01*
X260283Y583561D01*
X261117Y583144D01*
X261492Y582853D01*
X261742Y582436D01*
X261825Y582061D01*
X260075D01*
G01X257850D02*
Y584561D01*
X258350Y584061D01*
G01Y582061D02*
X257350D01*
G01X255542Y584144D02*
X255292Y584394D01*
X255000Y584519D01*
X254667Y584561D01*
X254250Y584478D01*
X253958Y584269D01*
X253875Y584019D01*
X253917Y583769D01*
X254083Y583561D01*
X254917Y583144D01*
X255292Y582853D01*
X255542Y582436D01*
X255625Y582061D01*
X253875D01*
G01X265700Y595000D02*
Y591000D01*
X258300D01*
G01X267818Y737110D02*
X266026D01*
X265651Y737277D01*
X265401Y737610D01*
X265318Y738027D01*
X265401Y738444D01*
X265651Y738777D01*
X266026Y738944D01*
X267818D01*
G01X265318Y741044D02*
X265860Y741127D01*
X266318Y741252D01*
X266735Y741419D01*
X267193Y741627D01*
X267818Y741960D01*
Y740294D01*
G01X265693Y743310D02*
X265485Y743560D01*
X265360Y743852D01*
X265318Y744227D01*
X265401Y744602D01*
X265568Y744894D01*
X265860Y745102D01*
X266193Y745144D01*
X266526Y745060D01*
X266735Y744852D01*
X266901Y744560D01*
X266943Y744269D01*
X266901Y743977D01*
X266735Y743602D01*
X267818Y743727D01*
Y744852D01*
G01X259745Y732813D02*
X262245D01*
Y733854D01*
X262120Y734188D01*
X261953Y734396D01*
X261620Y734479D01*
X261287Y734396D01*
X261078Y734146D01*
X260953Y733854D01*
Y732813D01*
G01Y733854D02*
X259745Y734479D01*
G01X261828Y735954D02*
X262078Y736204D01*
X262203Y736496D01*
X262245Y736829D01*
X262162Y737246D01*
X261953Y737538D01*
X261703Y737621D01*
X261453Y737579D01*
X261245Y737413D01*
X260828Y736579D01*
X260537Y736204D01*
X260120Y735954D01*
X259745Y735871D01*
Y737621D01*
G01Y739846D02*
X262245D01*
X261745Y739346D01*
G01X259745D02*
Y740346D01*
G01X262245Y742946D02*
X262162Y742613D01*
X261953Y742363D01*
X261703Y742196D01*
X261370Y742071D01*
X260995Y742029D01*
X260620Y742071D01*
X260287Y742196D01*
X260037Y742363D01*
X259828Y742613D01*
X259745Y742946D01*
X259828Y743279D01*
X260037Y743529D01*
X260287Y743696D01*
X260620Y743821D01*
X260995Y743863D01*
X261370Y743821D01*
X261703Y743696D01*
X261953Y743529D01*
X262162Y743279D01*
X262245Y742946D01*
G01X253376Y738517D02*
X255876D01*
Y739558D01*
X255751Y739892D01*
X255584Y740100D01*
X255251Y740183D01*
X254918Y740100D01*
X254709Y739850D01*
X254584Y739558D01*
Y738517D01*
G01Y739558D02*
X253376Y740183D01*
G01X253876Y741533D02*
X253584Y741783D01*
X253418Y742117D01*
X253376Y742492D01*
X253418Y742825D01*
X253626Y743158D01*
X253876Y743367D01*
X254126Y743408D01*
X254418Y743325D01*
X254626Y743033D01*
X254709Y742742D01*
Y742367D01*
G01Y742742D02*
X254834Y742992D01*
X255043Y743200D01*
X255293Y743283D01*
X255543Y743200D01*
X255751Y742992D01*
X255876Y742617D01*
X255834Y742242D01*
X255668Y741867D01*
G01X255459Y744758D02*
X255709Y745008D01*
X255834Y745300D01*
X255876Y745633D01*
X255793Y746050D01*
X255584Y746342D01*
X255334Y746425D01*
X255084Y746383D01*
X254876Y746217D01*
X254459Y745383D01*
X254168Y745008D01*
X253751Y744758D01*
X253376Y744675D01*
Y746425D01*
G01X253876Y747733D02*
X253584Y747983D01*
X253418Y748317D01*
X253376Y748692D01*
X253418Y749025D01*
X253626Y749358D01*
X253876Y749567D01*
X254126Y749608D01*
X254418Y749525D01*
X254626Y749233D01*
X254709Y748942D01*
Y748567D01*
G01Y748942D02*
X254834Y749192D01*
X255043Y749400D01*
X255293Y749483D01*
X255543Y749400D01*
X255751Y749192D01*
X255876Y748817D01*
X255834Y748442D01*
X255668Y748067D01*
G01X253751Y750833D02*
X253543Y751083D01*
X253418Y751375D01*
X253376Y751750D01*
X253459Y752125D01*
X253626Y752417D01*
X253918Y752625D01*
X254251Y752667D01*
X254584Y752583D01*
X254793Y752375D01*
X254959Y752083D01*
X255001Y751792D01*
X254959Y751500D01*
X254793Y751125D01*
X255876Y751250D01*
Y752375D01*
G01X265500Y754200D02*
X269500D01*
Y746800D01*
G01X261000Y757700D02*
X265000D01*
Y750300D01*
G01X269186Y764651D02*
X269436Y764776D01*
X269728Y764859D01*
X270061D01*
X270436Y764734D01*
X270728Y764526D01*
X270936Y764276D01*
X271103Y763859D01*
X271145Y763484D01*
X271061Y763109D01*
X270936Y762859D01*
X270686Y762609D01*
X270395Y762442D01*
X270103Y762359D01*
X269811D01*
X269520Y762442D01*
X269270Y762567D01*
X269061Y762734D01*
G01X267003Y762359D02*
X266711Y762401D01*
X266378Y762526D01*
X266170Y762734D01*
X266086Y763026D01*
X266170Y763317D01*
X266420Y763567D01*
X266795Y763692D01*
X267211D01*
X267461Y763776D01*
X267670Y763984D01*
X267753Y764276D01*
X267628Y764567D01*
X267336Y764776D01*
X267003Y764859D01*
X266670Y764776D01*
X266378Y764567D01*
X266253Y764276D01*
X266336Y763984D01*
X266545Y763776D01*
X266795Y763692D01*
X267211D01*
X267586Y763567D01*
X267836Y763317D01*
X267920Y763026D01*
X267836Y762734D01*
X267628Y762526D01*
X267295Y762401D01*
X267003Y762359D01*
G01X263903Y764859D02*
X264236Y764776D01*
X264486Y764567D01*
X264653Y764317D01*
X264778Y763984D01*
X264820Y763609D01*
X264778Y763234D01*
X264653Y762901D01*
X264486Y762651D01*
X264236Y762442D01*
X263903Y762359D01*
X263570Y762442D01*
X263320Y762651D01*
X263153Y762901D01*
X263028Y763234D01*
X262986Y763609D01*
X263028Y763984D01*
X263153Y764317D01*
X263320Y764567D01*
X263570Y764776D01*
X263903Y764859D01*
G01X261511Y762651D02*
X261220Y762442D01*
X260886Y762359D01*
X260553Y762442D01*
X260261Y762692D01*
X260053Y763067D01*
X259970Y763442D01*
Y763901D01*
X260053Y764276D01*
X260261Y764609D01*
X260511Y764776D01*
X260803Y764859D01*
X261136Y764776D01*
X261386Y764609D01*
X261553Y764359D01*
X261636Y764026D01*
X261553Y763734D01*
X261345Y763442D01*
X261095Y763276D01*
X260803Y763234D01*
X260470Y763317D01*
X260220Y763526D01*
X259970Y763901D01*
G01X257703Y762359D02*
Y764859D01*
X258203Y764359D01*
G01Y762359D02*
X257203D01*
G01X297661Y142017D02*
X300161D01*
Y143017D01*
X300036Y143350D01*
X299744Y143600D01*
X299411Y143683D01*
X299078Y143600D01*
X298828Y143392D01*
X298703Y143017D01*
Y142017D01*
G01X297661Y145117D02*
X300161D01*
Y146158D01*
X300036Y146492D01*
X299869Y146700D01*
X299536Y146783D01*
X299203Y146700D01*
X298994Y146450D01*
X298869Y146158D01*
Y145117D01*
G01Y146158D02*
X297661Y146783D01*
G01X299744Y148258D02*
X299994Y148508D01*
X300119Y148800D01*
X300161Y149133D01*
X300078Y149550D01*
X299869Y149842D01*
X299619Y149925D01*
X299369Y149883D01*
X299161Y149717D01*
X298744Y148883D01*
X298453Y148508D01*
X298036Y148258D01*
X297661Y148175D01*
Y149925D01*
G01X298703Y151358D02*
X298994Y151650D01*
X299161Y151900D01*
X299244Y152233D01*
X299161Y152525D01*
X298994Y152733D01*
X298744Y152900D01*
X298453Y152942D01*
X298203Y152900D01*
X297953Y152733D01*
X297744Y152483D01*
X297661Y152192D01*
X297744Y151858D01*
X297994Y151567D01*
X298369Y151400D01*
X298786Y151358D01*
X299328Y151442D01*
X299619Y151567D01*
X299911Y151775D01*
X300119Y152067D01*
X300161Y152358D01*
X300078Y152650D01*
X299869Y152858D01*
G01X278200Y169500D02*
Y162500D01*
G01D02*
X270400D01*
G01X278200Y169500D02*
X273000D01*
G01X293983Y159961D02*
Y162461D01*
X292983D01*
X292650Y162336D01*
X292400Y162044D01*
X292317Y161711D01*
X292400Y161378D01*
X292608Y161128D01*
X292983Y161003D01*
X293983D01*
G01X289133Y162253D02*
X289383Y162378D01*
X289675Y162461D01*
X290008D01*
X290383Y162336D01*
X290675Y162128D01*
X290883Y161878D01*
X291050Y161461D01*
X291092Y161086D01*
X291008Y160711D01*
X290883Y160461D01*
X290633Y160211D01*
X290342Y160044D01*
X290050Y159961D01*
X289758D01*
X289467Y160044D01*
X289217Y160169D01*
X289008Y160336D01*
G01X287742Y162044D02*
X287492Y162294D01*
X287200Y162419D01*
X286867Y162461D01*
X286450Y162378D01*
X286158Y162169D01*
X286075Y161919D01*
X286117Y161669D01*
X286283Y161461D01*
X287117Y161044D01*
X287492Y160753D01*
X287742Y160336D01*
X287825Y159961D01*
X286075D01*
G01X283933D02*
X283850Y160503D01*
X283725Y160961D01*
X283558Y161378D01*
X283350Y161836D01*
X283017Y162461D01*
X284683D01*
G01X291983Y155561D02*
Y158061D01*
X290983D01*
X290650Y157936D01*
X290400Y157644D01*
X290317Y157311D01*
X290400Y156978D01*
X290608Y156728D01*
X290983Y156603D01*
X291983D01*
G01X288883Y155561D02*
Y158061D01*
X287842D01*
X287508Y157936D01*
X287300Y157769D01*
X287217Y157436D01*
X287300Y157103D01*
X287550Y156894D01*
X287842Y156769D01*
X288883D01*
G01X287842D02*
X287217Y155561D01*
G01X285742Y157644D02*
X285492Y157894D01*
X285200Y158019D01*
X284867Y158061D01*
X284450Y157978D01*
X284158Y157769D01*
X284075Y157519D01*
X284117Y157269D01*
X284283Y157061D01*
X285117Y156644D01*
X285492Y156353D01*
X285742Y155936D01*
X285825Y155561D01*
X284075D01*
G01X281850Y158061D02*
X282183Y157978D01*
X282433Y157769D01*
X282600Y157519D01*
X282725Y157186D01*
X282767Y156811D01*
X282725Y156436D01*
X282600Y156103D01*
X282433Y155853D01*
X282183Y155644D01*
X281850Y155561D01*
X281517Y155644D01*
X281267Y155853D01*
X281100Y156103D01*
X280975Y156436D01*
X280933Y156811D01*
X280975Y157186D01*
X281100Y157519D01*
X281267Y157769D01*
X281517Y157978D01*
X281850Y158061D01*
G01X288500Y151200D02*
X292500D01*
Y143800D01*
G01X292371Y484099D02*
Y486599D01*
X291330D01*
X290996Y486474D01*
X290788Y486307D01*
X290705Y485974D01*
X290788Y485641D01*
X291038Y485432D01*
X291330Y485307D01*
X292371D01*
G01X291330D02*
X290705Y484099D01*
G01X289355Y484599D02*
X289105Y484307D01*
X288771Y484141D01*
X288396Y484099D01*
X288063Y484141D01*
X287730Y484349D01*
X287521Y484599D01*
X287480Y484849D01*
X287563Y485141D01*
X287855Y485349D01*
X288146Y485432D01*
X288521D01*
G01X288146D02*
X287896Y485557D01*
X287688Y485766D01*
X287605Y486016D01*
X287688Y486266D01*
X287896Y486474D01*
X288271Y486599D01*
X288646Y486557D01*
X289021Y486391D01*
G01X285338Y486599D02*
X285671Y486516D01*
X285921Y486307D01*
X286088Y486057D01*
X286213Y485724D01*
X286255Y485349D01*
X286213Y484974D01*
X286088Y484641D01*
X285921Y484391D01*
X285671Y484182D01*
X285338Y484099D01*
X285005Y484182D01*
X284755Y484391D01*
X284588Y484641D01*
X284463Y484974D01*
X284421Y485349D01*
X284463Y485724D01*
X284588Y486057D01*
X284755Y486307D01*
X285005Y486516D01*
X285338Y486599D01*
G01X283030Y485141D02*
X282738Y485432D01*
X282488Y485599D01*
X282155Y485682D01*
X281863Y485599D01*
X281655Y485432D01*
X281488Y485182D01*
X281446Y484891D01*
X281488Y484641D01*
X281655Y484391D01*
X281905Y484182D01*
X282196Y484099D01*
X282530Y484182D01*
X282821Y484432D01*
X282988Y484807D01*
X283030Y485224D01*
X282946Y485766D01*
X282821Y486057D01*
X282613Y486349D01*
X282321Y486557D01*
X282030Y486599D01*
X281738Y486516D01*
X281530Y486307D01*
G01X292532Y492772D02*
Y495272D01*
X291491D01*
X291157Y495147D01*
X290949Y494980D01*
X290866Y494647D01*
X290949Y494314D01*
X291199Y494105D01*
X291491Y493980D01*
X292532D01*
G01X291491D02*
X290866Y492772D01*
G01X289391Y494855D02*
X289141Y495105D01*
X288849Y495230D01*
X288516Y495272D01*
X288099Y495189D01*
X287807Y494980D01*
X287724Y494730D01*
X287766Y494480D01*
X287932Y494272D01*
X288766Y493855D01*
X289141Y493564D01*
X289391Y493147D01*
X289474Y492772D01*
X287724D01*
G01X286291Y493814D02*
X285999Y494105D01*
X285749Y494272D01*
X285416Y494355D01*
X285124Y494272D01*
X284916Y494105D01*
X284749Y493855D01*
X284707Y493564D01*
X284749Y493314D01*
X284916Y493064D01*
X285166Y492855D01*
X285457Y492772D01*
X285791Y492855D01*
X286082Y493105D01*
X286249Y493480D01*
X286291Y493897D01*
X286207Y494439D01*
X286082Y494730D01*
X285874Y495022D01*
X285582Y495230D01*
X285291Y495272D01*
X284999Y495189D01*
X284791Y494980D01*
G01X283191Y494855D02*
X282941Y495105D01*
X282649Y495230D01*
X282316Y495272D01*
X281899Y495189D01*
X281607Y494980D01*
X281524Y494730D01*
X281566Y494480D01*
X281732Y494272D01*
X282566Y493855D01*
X282941Y493564D01*
X283191Y493147D01*
X283274Y492772D01*
X281524D01*
G01X292532Y488772D02*
Y491272D01*
X291491D01*
X291157Y491147D01*
X290949Y490980D01*
X290866Y490647D01*
X290949Y490314D01*
X291199Y490105D01*
X291491Y489980D01*
X292532D01*
G01X291491D02*
X290866Y488772D01*
G01X289391Y490855D02*
X289141Y491105D01*
X288849Y491230D01*
X288516Y491272D01*
X288099Y491189D01*
X287807Y490980D01*
X287724Y490730D01*
X287766Y490480D01*
X287932Y490272D01*
X288766Y489855D01*
X289141Y489564D01*
X289391Y489147D01*
X289474Y488772D01*
X287724D01*
G01X286291Y489814D02*
X285999Y490105D01*
X285749Y490272D01*
X285416Y490355D01*
X285124Y490272D01*
X284916Y490105D01*
X284749Y489855D01*
X284707Y489564D01*
X284749Y489314D01*
X284916Y489064D01*
X285166Y488855D01*
X285457Y488772D01*
X285791Y488855D01*
X286082Y489105D01*
X286249Y489480D01*
X286291Y489897D01*
X286207Y490439D01*
X286082Y490730D01*
X285874Y491022D01*
X285582Y491230D01*
X285291Y491272D01*
X284999Y491189D01*
X284791Y490980D01*
G01X282399Y488772D02*
Y491272D01*
X282899Y490772D01*
G01Y488772D02*
X281899D01*
G01X293276Y520905D02*
Y523405D01*
X292235D01*
X291901Y523280D01*
X291693Y523113D01*
X291610Y522780D01*
X291693Y522447D01*
X291943Y522238D01*
X292235Y522113D01*
X293276D01*
G01X292235D02*
X291610Y520905D01*
G01X290260Y521280D02*
X290010Y521072D01*
X289718Y520947D01*
X289343Y520905D01*
X288968Y520988D01*
X288676Y521155D01*
X288468Y521447D01*
X288426Y521780D01*
X288510Y522113D01*
X288718Y522322D01*
X289010Y522488D01*
X289301Y522530D01*
X289593Y522488D01*
X289968Y522322D01*
X289843Y523405D01*
X288718D01*
G01X286951Y521197D02*
X286660Y520988D01*
X286326Y520905D01*
X285993Y520988D01*
X285701Y521238D01*
X285493Y521613D01*
X285410Y521988D01*
Y522447D01*
X285493Y522822D01*
X285701Y523155D01*
X285951Y523322D01*
X286243Y523405D01*
X286576Y523322D01*
X286826Y523155D01*
X286993Y522905D01*
X287076Y522572D01*
X286993Y522280D01*
X286785Y521988D01*
X286535Y521822D01*
X286243Y521780D01*
X285910Y521863D01*
X285660Y522072D01*
X285410Y522447D01*
G01X283143Y520905D02*
X282851Y520947D01*
X282518Y521072D01*
X282310Y521280D01*
X282226Y521572D01*
X282310Y521863D01*
X282560Y522113D01*
X282935Y522238D01*
X283351D01*
X283601Y522322D01*
X283810Y522530D01*
X283893Y522822D01*
X283768Y523113D01*
X283476Y523322D01*
X283143Y523405D01*
X282810Y523322D01*
X282518Y523113D01*
X282393Y522822D01*
X282476Y522530D01*
X282685Y522322D01*
X282935Y522238D01*
X283351D01*
X283726Y522113D01*
X283976Y521863D01*
X284060Y521572D01*
X283976Y521280D01*
X283768Y521072D01*
X283435Y520947D01*
X283143Y520905D01*
G01X293276Y532905D02*
Y535405D01*
X292235D01*
X291901Y535280D01*
X291693Y535113D01*
X291610Y534780D01*
X291693Y534447D01*
X291943Y534238D01*
X292235Y534113D01*
X293276D01*
G01X292235D02*
X291610Y532905D01*
G01X290260Y533280D02*
X290010Y533072D01*
X289718Y532947D01*
X289343Y532905D01*
X288968Y532988D01*
X288676Y533155D01*
X288468Y533447D01*
X288426Y533780D01*
X288510Y534113D01*
X288718Y534322D01*
X289010Y534488D01*
X289301Y534530D01*
X289593Y534488D01*
X289968Y534322D01*
X289843Y535405D01*
X288718D01*
G01X286326Y532905D02*
X286243Y533447D01*
X286118Y533905D01*
X285951Y534322D01*
X285743Y534780D01*
X285410Y535405D01*
X287076D01*
G01X283143Y532905D02*
X282851Y532947D01*
X282518Y533072D01*
X282310Y533280D01*
X282226Y533572D01*
X282310Y533863D01*
X282560Y534113D01*
X282935Y534238D01*
X283351D01*
X283601Y534322D01*
X283810Y534530D01*
X283893Y534822D01*
X283768Y535113D01*
X283476Y535322D01*
X283143Y535405D01*
X282810Y535322D01*
X282518Y535113D01*
X282393Y534822D01*
X282476Y534530D01*
X282685Y534322D01*
X282935Y534238D01*
X283351D01*
X283726Y534113D01*
X283976Y533863D01*
X284060Y533572D01*
X283976Y533280D01*
X283768Y533072D01*
X283435Y532947D01*
X283143Y532905D01*
G01X293276Y528905D02*
Y531405D01*
X292235D01*
X291901Y531280D01*
X291693Y531113D01*
X291610Y530780D01*
X291693Y530447D01*
X291943Y530238D01*
X292235Y530113D01*
X293276D01*
G01X292235D02*
X291610Y528905D01*
G01X290260Y529280D02*
X290010Y529072D01*
X289718Y528947D01*
X289343Y528905D01*
X288968Y528988D01*
X288676Y529155D01*
X288468Y529447D01*
X288426Y529780D01*
X288510Y530113D01*
X288718Y530322D01*
X289010Y530488D01*
X289301Y530530D01*
X289593Y530488D01*
X289968Y530322D01*
X289843Y531405D01*
X288718D01*
G01X286326Y528905D02*
X286243Y529447D01*
X286118Y529905D01*
X285951Y530322D01*
X285743Y530780D01*
X285410Y531405D01*
X287076D01*
G01X283851Y529197D02*
X283560Y528988D01*
X283226Y528905D01*
X282893Y528988D01*
X282601Y529238D01*
X282393Y529613D01*
X282310Y529988D01*
Y530447D01*
X282393Y530822D01*
X282601Y531155D01*
X282851Y531322D01*
X283143Y531405D01*
X283476Y531322D01*
X283726Y531155D01*
X283893Y530905D01*
X283976Y530572D01*
X283893Y530280D01*
X283685Y529988D01*
X283435Y529822D01*
X283143Y529780D01*
X282810Y529863D01*
X282560Y530072D01*
X282310Y530447D01*
G01X293276Y524905D02*
Y527405D01*
X292235D01*
X291901Y527280D01*
X291693Y527113D01*
X291610Y526780D01*
X291693Y526447D01*
X291943Y526238D01*
X292235Y526113D01*
X293276D01*
G01X292235D02*
X291610Y524905D01*
G01X290260Y525280D02*
X290010Y525072D01*
X289718Y524947D01*
X289343Y524905D01*
X288968Y524988D01*
X288676Y525155D01*
X288468Y525447D01*
X288426Y525780D01*
X288510Y526113D01*
X288718Y526322D01*
X289010Y526488D01*
X289301Y526530D01*
X289593Y526488D01*
X289968Y526322D01*
X289843Y527405D01*
X288718D01*
G01X286951Y525197D02*
X286660Y524988D01*
X286326Y524905D01*
X285993Y524988D01*
X285701Y525238D01*
X285493Y525613D01*
X285410Y525988D01*
Y526447D01*
X285493Y526822D01*
X285701Y527155D01*
X285951Y527322D01*
X286243Y527405D01*
X286576Y527322D01*
X286826Y527155D01*
X286993Y526905D01*
X287076Y526572D01*
X286993Y526280D01*
X286785Y525988D01*
X286535Y525822D01*
X286243Y525780D01*
X285910Y525863D01*
X285660Y526072D01*
X285410Y526447D01*
G01X283851Y525197D02*
X283560Y524988D01*
X283226Y524905D01*
X282893Y524988D01*
X282601Y525238D01*
X282393Y525613D01*
X282310Y525988D01*
Y526447D01*
X282393Y526822D01*
X282601Y527155D01*
X282851Y527322D01*
X283143Y527405D01*
X283476Y527322D01*
X283726Y527155D01*
X283893Y526905D01*
X283976Y526572D01*
X283893Y526280D01*
X283685Y525988D01*
X283435Y525822D01*
X283143Y525780D01*
X282810Y525863D01*
X282560Y526072D01*
X282310Y526447D01*
G01X279857Y528824D02*
Y531324D01*
X278816D01*
X278482Y531199D01*
X278274Y531032D01*
X278191Y530699D01*
X278274Y530366D01*
X278524Y530157D01*
X278816Y530032D01*
X279857D01*
G01X278816D02*
X278191Y528824D01*
G01X276841Y529324D02*
X276591Y529032D01*
X276257Y528866D01*
X275882Y528824D01*
X275549Y528866D01*
X275216Y529074D01*
X275007Y529324D01*
X274966Y529574D01*
X275049Y529866D01*
X275341Y530074D01*
X275632Y530157D01*
X276007D01*
G01X275632D02*
X275382Y530282D01*
X275174Y530491D01*
X275091Y530741D01*
X275174Y530991D01*
X275382Y531199D01*
X275757Y531324D01*
X276132Y531282D01*
X276507Y531116D01*
G01X273616Y530907D02*
X273366Y531157D01*
X273074Y531282D01*
X272741Y531324D01*
X272324Y531241D01*
X272032Y531032D01*
X271949Y530782D01*
X271991Y530532D01*
X272157Y530324D01*
X272991Y529907D01*
X273366Y529616D01*
X273616Y529199D01*
X273699Y528824D01*
X271949D01*
G01X270641Y529324D02*
X270391Y529032D01*
X270057Y528866D01*
X269682Y528824D01*
X269349Y528866D01*
X269016Y529074D01*
X268807Y529324D01*
X268766Y529574D01*
X268849Y529866D01*
X269141Y530074D01*
X269432Y530157D01*
X269807D01*
G01X269432D02*
X269182Y530282D01*
X268974Y530491D01*
X268891Y530741D01*
X268974Y530991D01*
X269182Y531199D01*
X269557Y531324D01*
X269932Y531282D01*
X270307Y531116D01*
G01X279857Y532824D02*
Y535324D01*
X278816D01*
X278482Y535199D01*
X278274Y535032D01*
X278191Y534699D01*
X278274Y534366D01*
X278524Y534157D01*
X278816Y534032D01*
X279857D01*
G01X278816D02*
X278191Y532824D01*
G01X275424D02*
Y535324D01*
X276966Y533532D01*
X274882D01*
G01X273616Y534907D02*
X273366Y535157D01*
X273074Y535282D01*
X272741Y535324D01*
X272324Y535241D01*
X272032Y535032D01*
X271949Y534782D01*
X271991Y534532D01*
X272157Y534324D01*
X272991Y533907D01*
X273366Y533616D01*
X273616Y533199D01*
X273699Y532824D01*
X271949D01*
G01X269724D02*
Y535324D01*
X270224Y534824D01*
G01Y532824D02*
X269224D01*
G01X279857Y524821D02*
Y527321D01*
X278816D01*
X278482Y527196D01*
X278274Y527029D01*
X278191Y526696D01*
X278274Y526363D01*
X278524Y526154D01*
X278816Y526029D01*
X279857D01*
G01X278816D02*
X278191Y524821D01*
G01X275424D02*
Y527321D01*
X276966Y525529D01*
X274882D01*
G01X273532Y525113D02*
X273241Y524904D01*
X272907Y524821D01*
X272574Y524904D01*
X272282Y525154D01*
X272074Y525529D01*
X271991Y525904D01*
Y526363D01*
X272074Y526738D01*
X272282Y527071D01*
X272532Y527238D01*
X272824Y527321D01*
X273157Y527238D01*
X273407Y527071D01*
X273574Y526821D01*
X273657Y526488D01*
X273574Y526196D01*
X273366Y525904D01*
X273116Y525738D01*
X272824Y525696D01*
X272491Y525779D01*
X272241Y525988D01*
X271991Y526363D01*
G01X270516Y526904D02*
X270266Y527154D01*
X269974Y527279D01*
X269641Y527321D01*
X269224Y527238D01*
X268932Y527029D01*
X268849Y526779D01*
X268891Y526529D01*
X269057Y526321D01*
X269891Y525904D01*
X270266Y525613D01*
X270516Y525196D01*
X270599Y524821D01*
X268849D01*
G01X279857Y520821D02*
Y523321D01*
X278816D01*
X278482Y523196D01*
X278274Y523029D01*
X278191Y522696D01*
X278274Y522363D01*
X278524Y522154D01*
X278816Y522029D01*
X279857D01*
G01X278816D02*
X278191Y520821D01*
G01X275424D02*
Y523321D01*
X276966Y521529D01*
X274882D01*
G01X272907Y520821D02*
X272824Y521363D01*
X272699Y521821D01*
X272532Y522238D01*
X272324Y522696D01*
X271991Y523321D01*
X273657D01*
G01X270516Y522904D02*
X270266Y523154D01*
X269974Y523279D01*
X269641Y523321D01*
X269224Y523238D01*
X268932Y523029D01*
X268849Y522779D01*
X268891Y522529D01*
X269057Y522321D01*
X269891Y521904D01*
X270266Y521613D01*
X270516Y521196D01*
X270599Y520821D01*
X268849D01*
G01X299700Y580500D02*
Y576500D01*
X292300D01*
G01X299700Y585000D02*
Y581000D01*
X292300D01*
G01X299700Y590500D02*
Y586500D01*
X292300D01*
G01X273067Y702915D02*
X275567D01*
Y703956D01*
X275442Y704290D01*
X275275Y704498D01*
X274942Y704581D01*
X274609Y704498D01*
X274400Y704248D01*
X274275Y703956D01*
Y702915D01*
G01Y703956D02*
X273067Y704581D01*
G01X273442Y705931D02*
X273234Y706181D01*
X273109Y706473D01*
X273067Y706848D01*
X273150Y707223D01*
X273317Y707515D01*
X273609Y707723D01*
X273942Y707765D01*
X274275Y707681D01*
X274484Y707473D01*
X274650Y707181D01*
X274692Y706890D01*
X274650Y706598D01*
X274484Y706223D01*
X275567Y706348D01*
Y707473D01*
G01X275150Y709156D02*
X275400Y709406D01*
X275525Y709698D01*
X275567Y710031D01*
X275484Y710448D01*
X275275Y710740D01*
X275025Y710823D01*
X274775Y710781D01*
X274567Y710615D01*
X274150Y709781D01*
X273859Y709406D01*
X273442Y709156D01*
X273067Y709073D01*
Y710823D01*
G01Y713048D02*
X275567D01*
X275067Y712548D01*
G01X273067D02*
Y713548D01*
G01X277067Y702915D02*
X279567D01*
Y703956D01*
X279442Y704290D01*
X279275Y704498D01*
X278942Y704581D01*
X278609Y704498D01*
X278400Y704248D01*
X278275Y703956D01*
Y702915D01*
G01Y703956D02*
X277067Y704581D01*
G01X277442Y705931D02*
X277234Y706181D01*
X277109Y706473D01*
X277067Y706848D01*
X277150Y707223D01*
X277317Y707515D01*
X277609Y707723D01*
X277942Y707765D01*
X278275Y707681D01*
X278484Y707473D01*
X278650Y707181D01*
X278692Y706890D01*
X278650Y706598D01*
X278484Y706223D01*
X279567Y706348D01*
Y707473D01*
G01X277067Y709948D02*
X279567D01*
X279067Y709448D01*
G01X277067D02*
Y710448D01*
G01Y713048D02*
X277109Y713340D01*
X277234Y713673D01*
X277442Y713881D01*
X277734Y713965D01*
X278025Y713881D01*
X278275Y713631D01*
X278400Y713256D01*
Y712840D01*
X278484Y712590D01*
X278692Y712381D01*
X278984Y712298D01*
X279275Y712423D01*
X279484Y712715D01*
X279567Y713048D01*
X279484Y713381D01*
X279275Y713673D01*
X278984Y713798D01*
X278692Y713715D01*
X278484Y713506D01*
X278400Y713256D01*
Y712840D01*
X278275Y712465D01*
X278025Y712215D01*
X277734Y712131D01*
X277442Y712215D01*
X277234Y712423D01*
X277109Y712756D01*
X277067Y713048D01*
G01X297315Y700180D02*
X299815D01*
Y701221D01*
X299690Y701555D01*
X299523Y701763D01*
X299190Y701846D01*
X298857Y701763D01*
X298648Y701513D01*
X298523Y701221D01*
Y700180D01*
G01Y701221D02*
X297315Y701846D01*
G01Y704613D02*
X299815D01*
X298023Y703071D01*
Y705155D01*
G01X297315Y707213D02*
X299815D01*
X299315Y706713D01*
G01X297315D02*
Y707713D01*
G01X299815Y710313D02*
X299732Y709980D01*
X299523Y709730D01*
X299273Y709563D01*
X298940Y709438D01*
X298565Y709396D01*
X298190Y709438D01*
X297857Y709563D01*
X297607Y709730D01*
X297398Y709980D01*
X297315Y710313D01*
X297398Y710646D01*
X297607Y710896D01*
X297857Y711063D01*
X298190Y711188D01*
X298565Y711230D01*
X298940Y711188D01*
X299273Y711063D01*
X299523Y710896D01*
X299732Y710646D01*
X299815Y710313D01*
G01X297315Y713330D02*
X297857Y713413D01*
X298315Y713538D01*
X298732Y713705D01*
X299190Y713913D01*
X299815Y714246D01*
Y712580D01*
G01X284967Y699065D02*
X287467D01*
Y700106D01*
X287342Y700440D01*
X287175Y700648D01*
X286842Y700731D01*
X286509Y700648D01*
X286300Y700398D01*
X286175Y700106D01*
Y699065D01*
G01Y700106D02*
X284967Y700731D01*
G01Y703498D02*
X287467D01*
X285675Y701956D01*
Y704040D01*
G01X284967Y706098D02*
X287467D01*
X286967Y705598D01*
G01X284967D02*
Y706598D01*
G01X287467Y709198D02*
X287384Y708865D01*
X287175Y708615D01*
X286925Y708448D01*
X286592Y708323D01*
X286217Y708281D01*
X285842Y708323D01*
X285509Y708448D01*
X285259Y708615D01*
X285050Y708865D01*
X284967Y709198D01*
X285050Y709531D01*
X285259Y709781D01*
X285509Y709948D01*
X285842Y710073D01*
X286217Y710115D01*
X286592Y710073D01*
X286925Y709948D01*
X287175Y709781D01*
X287384Y709531D01*
X287467Y709198D01*
G01X285467Y711381D02*
X285175Y711631D01*
X285009Y711965D01*
X284967Y712340D01*
X285009Y712673D01*
X285217Y713006D01*
X285467Y713215D01*
X285717Y713256D01*
X286009Y713173D01*
X286217Y712881D01*
X286300Y712590D01*
Y712215D01*
G01Y712590D02*
X286425Y712840D01*
X286634Y713048D01*
X286884Y713131D01*
X287134Y713048D01*
X287342Y712840D01*
X287467Y712465D01*
X287425Y712090D01*
X287259Y711715D01*
G01X281067Y701365D02*
X283567D01*
Y702406D01*
X283442Y702740D01*
X283275Y702948D01*
X282942Y703031D01*
X282609Y702948D01*
X282400Y702698D01*
X282275Y702406D01*
Y701365D01*
G01Y702406D02*
X281067Y703031D01*
G01Y705798D02*
X283567D01*
X281775Y704256D01*
Y706340D01*
G01X281067Y708398D02*
X283567D01*
X283067Y707898D01*
G01X281067D02*
Y708898D01*
G01X283567Y711498D02*
X283484Y711165D01*
X283275Y710915D01*
X283025Y710748D01*
X282692Y710623D01*
X282317Y710581D01*
X281942Y710623D01*
X281609Y710748D01*
X281359Y710915D01*
X281150Y711165D01*
X281067Y711498D01*
X281150Y711831D01*
X281359Y712081D01*
X281609Y712248D01*
X281942Y712373D01*
X282317Y712415D01*
X282692Y712373D01*
X283025Y712248D01*
X283275Y712081D01*
X283484Y711831D01*
X283567Y711498D01*
G01X283150Y713806D02*
X283400Y714056D01*
X283525Y714348D01*
X283567Y714681D01*
X283484Y715098D01*
X283275Y715390D01*
X283025Y715473D01*
X282775Y715431D01*
X282567Y715265D01*
X282150Y714431D01*
X281859Y714056D01*
X281442Y713806D01*
X281067Y713723D01*
Y715473D01*
G01X289116Y699593D02*
X291616D01*
Y700634D01*
X291491Y700968D01*
X291324Y701176D01*
X290991Y701259D01*
X290658Y701176D01*
X290449Y700926D01*
X290324Y700634D01*
Y699593D01*
G01Y700634D02*
X289116Y701259D01*
G01X289408Y702818D02*
X289199Y703109D01*
X289116Y703443D01*
X289199Y703776D01*
X289449Y704068D01*
X289824Y704276D01*
X290199Y704359D01*
X290658D01*
X291033Y704276D01*
X291366Y704068D01*
X291533Y703818D01*
X291616Y703526D01*
X291533Y703193D01*
X291366Y702943D01*
X291116Y702776D01*
X290783Y702693D01*
X290491Y702776D01*
X290199Y702984D01*
X290033Y703234D01*
X289991Y703526D01*
X290074Y703859D01*
X290283Y704109D01*
X290658Y704359D01*
G01X291616Y706626D02*
X291533Y706293D01*
X291324Y706043D01*
X291074Y705876D01*
X290741Y705751D01*
X290366Y705709D01*
X289991Y705751D01*
X289658Y705876D01*
X289408Y706043D01*
X289199Y706293D01*
X289116Y706626D01*
X289199Y706959D01*
X289408Y707209D01*
X289658Y707376D01*
X289991Y707501D01*
X290366Y707543D01*
X290741Y707501D01*
X291074Y707376D01*
X291324Y707209D01*
X291533Y706959D01*
X291616Y706626D01*
G01X291199Y708934D02*
X291449Y709184D01*
X291574Y709476D01*
X291616Y709809D01*
X291533Y710226D01*
X291324Y710518D01*
X291074Y710601D01*
X290824Y710559D01*
X290616Y710393D01*
X290199Y709559D01*
X289908Y709184D01*
X289491Y708934D01*
X289116Y708851D01*
Y710601D01*
G01X289408Y712118D02*
X289199Y712409D01*
X289116Y712743D01*
X289199Y713076D01*
X289449Y713368D01*
X289824Y713576D01*
X290199Y713659D01*
X290658D01*
X291033Y713576D01*
X291366Y713368D01*
X291533Y713118D01*
X291616Y712826D01*
X291533Y712493D01*
X291366Y712243D01*
X291116Y712076D01*
X290783Y711993D01*
X290491Y712076D01*
X290199Y712284D01*
X290033Y712534D01*
X289991Y712826D01*
X290074Y713159D01*
X290283Y713409D01*
X290658Y713659D01*
G01X293167Y701365D02*
X295667D01*
Y702406D01*
X295542Y702740D01*
X295375Y702948D01*
X295042Y703031D01*
X294709Y702948D01*
X294500Y702698D01*
X294375Y702406D01*
Y701365D01*
G01Y702406D02*
X293167Y703031D01*
G01Y705798D02*
X295667D01*
X293875Y704256D01*
Y706340D01*
G01X293167Y708398D02*
X295667D01*
X295167Y707898D01*
G01X293167D02*
Y708898D01*
G01X295667Y711498D02*
X295584Y711165D01*
X295375Y710915D01*
X295125Y710748D01*
X294792Y710623D01*
X294417Y710581D01*
X294042Y710623D01*
X293709Y710748D01*
X293459Y710915D01*
X293250Y711165D01*
X293167Y711498D01*
X293250Y711831D01*
X293459Y712081D01*
X293709Y712248D01*
X294042Y712373D01*
X294417Y712415D01*
X294792Y712373D01*
X295125Y712248D01*
X295375Y712081D01*
X295584Y711831D01*
X295667Y711498D01*
G01X293167Y715098D02*
X295667D01*
X293875Y713556D01*
Y715640D01*
G01X280722Y739769D02*
Y753169D01*
G01X270722Y739769D02*
X280722D01*
G01X270722Y753169D02*
Y739769D01*
G01X298000Y739800D02*
Y753200D01*
G01X288000Y739800D02*
X298000D01*
G01X288000Y753200D02*
Y739800D01*
G01X283000Y754200D02*
X287000D01*
Y746800D01*
G01X293678Y738131D02*
X297678D01*
Y730731D01*
G01X276050Y738717D02*
X280050D01*
Y731317D01*
G01X276406Y717698D02*
X272406D01*
Y725098D01*
G01X280406Y717698D02*
X276406D01*
Y725098D01*
G01X296554Y725113D02*
X300554D01*
Y717713D01*
G01X284406Y725098D02*
X288406D01*
Y717698D01*
G01X280406Y725098D02*
X284406D01*
Y717698D01*
G01X288500Y725200D02*
X292500D01*
Y717800D01*
G01X292506Y725098D02*
X296506D01*
Y717698D01*
G01X280722Y753169D02*
X270722D01*
G01X298000Y753200D02*
X288000D01*
G01X299000Y749700D02*
X303000D01*
Y742300D01*
G01X291678Y762131D02*
X295678D01*
Y754731D01*
G01X287678Y762131D02*
X291678D01*
Y754731D01*
G01X272661Y762403D02*
X275161D01*
Y763444D01*
X275036Y763778D01*
X274869Y763986D01*
X274536Y764069D01*
X274203Y763986D01*
X273994Y763736D01*
X273869Y763444D01*
Y762403D01*
G01Y763444D02*
X272661Y764069D01*
G01X273161Y765419D02*
X272869Y765669D01*
X272703Y766003D01*
X272661Y766378D01*
X272703Y766711D01*
X272911Y767044D01*
X273161Y767253D01*
X273411Y767294D01*
X273703Y767211D01*
X273911Y766919D01*
X273994Y766628D01*
Y766253D01*
G01Y766628D02*
X274119Y766878D01*
X274328Y767086D01*
X274578Y767169D01*
X274828Y767086D01*
X275036Y766878D01*
X275161Y766503D01*
X275119Y766128D01*
X274953Y765753D01*
G01X274744Y768644D02*
X274994Y768894D01*
X275119Y769186D01*
X275161Y769519D01*
X275078Y769936D01*
X274869Y770228D01*
X274619Y770311D01*
X274369Y770269D01*
X274161Y770103D01*
X273744Y769269D01*
X273453Y768894D01*
X273036Y768644D01*
X272661Y768561D01*
Y770311D01*
G01X273161Y771619D02*
X272869Y771869D01*
X272703Y772203D01*
X272661Y772578D01*
X272703Y772911D01*
X272911Y773244D01*
X273161Y773453D01*
X273411Y773494D01*
X273703Y773411D01*
X273911Y773119D01*
X273994Y772828D01*
Y772453D01*
G01Y772828D02*
X274119Y773078D01*
X274328Y773286D01*
X274578Y773369D01*
X274828Y773286D01*
X275036Y773078D01*
X275161Y772703D01*
X275119Y772328D01*
X274953Y771953D01*
G01X272661Y776136D02*
X275161D01*
X273369Y774594D01*
Y776678D01*
G01X277500Y761700D02*
X281500D01*
Y754300D01*
G01X281039Y777448D02*
X283539D01*
Y778489D01*
X283414Y778823D01*
X283247Y779031D01*
X282914Y779114D01*
X282581Y779031D01*
X282372Y778781D01*
X282247Y778489D01*
Y777448D01*
G01Y778489D02*
X281039Y779114D01*
G01X281414Y780464D02*
X281206Y780714D01*
X281081Y781006D01*
X281039Y781381D01*
X281122Y781756D01*
X281289Y782048D01*
X281581Y782256D01*
X281914Y782298D01*
X282247Y782214D01*
X282456Y782006D01*
X282622Y781714D01*
X282664Y781423D01*
X282622Y781131D01*
X282456Y780756D01*
X283539Y780881D01*
Y782006D01*
G01X281039Y784481D02*
X283539D01*
X283039Y783981D01*
G01X281039D02*
Y784981D01*
G01X281331Y786873D02*
X281122Y787164D01*
X281039Y787498D01*
X281122Y787831D01*
X281372Y788123D01*
X281747Y788331D01*
X282122Y788414D01*
X282581D01*
X282956Y788331D01*
X283289Y788123D01*
X283456Y787873D01*
X283539Y787581D01*
X283456Y787248D01*
X283289Y786998D01*
X283039Y786831D01*
X282706Y786748D01*
X282414Y786831D01*
X282122Y787039D01*
X281956Y787289D01*
X281914Y787581D01*
X281997Y787914D01*
X282206Y788164D01*
X282581Y788414D01*
G01X280378Y774131D02*
X284378D01*
Y766731D01*
G01X285567Y775865D02*
X288067D01*
Y776906D01*
X287942Y777240D01*
X287775Y777448D01*
X287442Y777531D01*
X287109Y777448D01*
X286900Y777198D01*
X286775Y776906D01*
Y775865D01*
G01Y776906D02*
X285567Y777531D01*
G01Y780298D02*
X288067D01*
X286275Y778756D01*
Y780840D01*
G01X285567Y782898D02*
X288067D01*
X287567Y782398D01*
G01X285567D02*
Y783398D01*
G01Y785998D02*
X288067D01*
X287567Y785498D01*
G01X285567D02*
Y786498D01*
G01X286609Y788306D02*
X286900Y788598D01*
X287067Y788848D01*
X287150Y789181D01*
X287067Y789473D01*
X286900Y789681D01*
X286650Y789848D01*
X286359Y789890D01*
X286109Y789848D01*
X285859Y789681D01*
X285650Y789431D01*
X285567Y789140D01*
X285650Y788806D01*
X285900Y788515D01*
X286275Y788348D01*
X286692Y788306D01*
X287234Y788390D01*
X287525Y788515D01*
X287817Y788723D01*
X288025Y789015D01*
X288067Y789306D01*
X287984Y789598D01*
X287775Y789806D01*
G01X288906Y766698D02*
X284906D01*
Y774098D01*
G01X301164Y766891D02*
X297164D01*
Y774291D01*
G01X297079Y766650D02*
X293079D01*
Y774050D01*
G01X297340Y783540D02*
X299840D01*
Y784581D01*
X299715Y784915D01*
X299548Y785123D01*
X299215Y785206D01*
X298882Y785123D01*
X298673Y784873D01*
X298548Y784581D01*
Y783540D01*
G01Y784581D02*
X297340Y785206D01*
G01Y787973D02*
X299840D01*
X298048Y786431D01*
Y788515D01*
G01X297340Y790573D02*
X299840D01*
X299340Y790073D01*
G01X297340D02*
Y791073D01*
G01Y793673D02*
X299840D01*
X299340Y793173D01*
G01X297340D02*
Y794173D01*
G01X297715Y795856D02*
X297507Y796106D01*
X297382Y796398D01*
X297340Y796773D01*
X297423Y797148D01*
X297590Y797440D01*
X297882Y797648D01*
X298215Y797690D01*
X298548Y797606D01*
X298757Y797398D01*
X298923Y797106D01*
X298965Y796815D01*
X298923Y796523D01*
X298757Y796148D01*
X299840Y796273D01*
Y797398D01*
G01X293240Y783540D02*
X295740D01*
Y784581D01*
X295615Y784915D01*
X295448Y785123D01*
X295115Y785206D01*
X294782Y785123D01*
X294573Y784873D01*
X294448Y784581D01*
Y783540D01*
G01Y784581D02*
X293240Y785206D01*
G01Y787973D02*
X295740D01*
X293948Y786431D01*
Y788515D01*
G01X293240Y790573D02*
X295740D01*
X295240Y790073D01*
G01X293240D02*
Y791073D01*
G01Y793673D02*
X295740D01*
X295240Y793173D01*
G01X293240D02*
Y794173D01*
G01Y797273D02*
X295740D01*
X293948Y795731D01*
Y797815D01*
G01X302500Y142017D02*
X305000D01*
Y143017D01*
X304875Y143350D01*
X304583Y143600D01*
X304250Y143683D01*
X303917Y143600D01*
X303667Y143392D01*
X303542Y143017D01*
Y142017D01*
G01X304792Y146867D02*
X304917Y146617D01*
X305000Y146325D01*
Y145992D01*
X304875Y145617D01*
X304667Y145325D01*
X304417Y145117D01*
X304000Y144950D01*
X303625Y144908D01*
X303250Y144992D01*
X303000Y145117D01*
X302750Y145367D01*
X302583Y145658D01*
X302500Y145950D01*
Y146242D01*
X302583Y146533D01*
X302708Y146783D01*
X302875Y146992D01*
G01X303000Y148133D02*
X302708Y148383D01*
X302542Y148717D01*
X302500Y149092D01*
X302542Y149425D01*
X302750Y149758D01*
X303000Y149967D01*
X303250Y150008D01*
X303542Y149925D01*
X303750Y149633D01*
X303833Y149342D01*
Y148967D01*
G01Y149342D02*
X303958Y149592D01*
X304167Y149800D01*
X304417Y149883D01*
X304667Y149800D01*
X304875Y149592D01*
X305000Y149217D01*
X304958Y148842D01*
X304792Y148467D01*
G01X305000Y152150D02*
X304917Y151817D01*
X304708Y151567D01*
X304458Y151400D01*
X304125Y151275D01*
X303750Y151233D01*
X303375Y151275D01*
X303042Y151400D01*
X302792Y151567D01*
X302583Y151817D01*
X302500Y152150D01*
X302583Y152483D01*
X302792Y152733D01*
X303042Y152900D01*
X303375Y153025D01*
X303750Y153067D01*
X304125Y153025D01*
X304458Y152900D01*
X304708Y152733D01*
X304917Y152483D01*
X305000Y152150D01*
G01X314488Y577813D02*
Y580313D01*
X313447D01*
X313113Y580188D01*
X312905Y580021D01*
X312822Y579688D01*
X312905Y579355D01*
X313155Y579146D01*
X313447Y579021D01*
X314488D01*
G01X313447D02*
X312822Y577813D01*
G01X310555D02*
Y580313D01*
X311055Y579813D01*
G01Y577813D02*
X310055D01*
G01X308163Y578105D02*
X307872Y577896D01*
X307538Y577813D01*
X307205Y577896D01*
X306913Y578146D01*
X306705Y578521D01*
X306622Y578896D01*
Y579355D01*
X306705Y579730D01*
X306913Y580063D01*
X307163Y580230D01*
X307455Y580313D01*
X307788Y580230D01*
X308038Y580063D01*
X308205Y579813D01*
X308288Y579480D01*
X308205Y579188D01*
X307997Y578896D01*
X307747Y578730D01*
X307455Y578688D01*
X307122Y578771D01*
X306872Y578980D01*
X306622Y579355D01*
G01X305147Y579896D02*
X304897Y580146D01*
X304605Y580271D01*
X304272Y580313D01*
X303855Y580230D01*
X303563Y580021D01*
X303480Y579771D01*
X303522Y579521D01*
X303688Y579313D01*
X304522Y578896D01*
X304897Y578605D01*
X305147Y578188D01*
X305230Y577813D01*
X303480D01*
G01X314488Y582313D02*
Y584813D01*
X313447D01*
X313113Y584688D01*
X312905Y584521D01*
X312822Y584188D01*
X312905Y583855D01*
X313155Y583646D01*
X313447Y583521D01*
X314488D01*
G01X313447D02*
X312822Y582313D01*
G01X310555D02*
Y584813D01*
X311055Y584313D01*
G01Y582313D02*
X310055D01*
G01X308163Y582605D02*
X307872Y582396D01*
X307538Y582313D01*
X307205Y582396D01*
X306913Y582646D01*
X306705Y583021D01*
X306622Y583396D01*
Y583855D01*
X306705Y584230D01*
X306913Y584563D01*
X307163Y584730D01*
X307455Y584813D01*
X307788Y584730D01*
X308038Y584563D01*
X308205Y584313D01*
X308288Y583980D01*
X308205Y583688D01*
X307997Y583396D01*
X307747Y583230D01*
X307455Y583188D01*
X307122Y583271D01*
X306872Y583480D01*
X306622Y583855D01*
G01X305272Y582813D02*
X305022Y582521D01*
X304688Y582355D01*
X304313Y582313D01*
X303980Y582355D01*
X303647Y582563D01*
X303438Y582813D01*
X303397Y583063D01*
X303480Y583355D01*
X303772Y583563D01*
X304063Y583646D01*
X304438D01*
G01X304063D02*
X303813Y583771D01*
X303605Y583980D01*
X303522Y584230D01*
X303605Y584480D01*
X303813Y584688D01*
X304188Y584813D01*
X304563Y584771D01*
X304938Y584605D01*
G01X314488Y587813D02*
Y590313D01*
X313447D01*
X313113Y590188D01*
X312905Y590021D01*
X312822Y589688D01*
X312905Y589355D01*
X313155Y589146D01*
X313447Y589021D01*
X314488D01*
G01X313447D02*
X312822Y587813D01*
G01X310555D02*
Y590313D01*
X311055Y589813D01*
G01Y587813D02*
X310055D01*
G01X308163Y588105D02*
X307872Y587896D01*
X307538Y587813D01*
X307205Y587896D01*
X306913Y588146D01*
X306705Y588521D01*
X306622Y588896D01*
Y589355D01*
X306705Y589730D01*
X306913Y590063D01*
X307163Y590230D01*
X307455Y590313D01*
X307788Y590230D01*
X308038Y590063D01*
X308205Y589813D01*
X308288Y589480D01*
X308205Y589188D01*
X307997Y588896D01*
X307747Y588730D01*
X307455Y588688D01*
X307122Y588771D01*
X306872Y588980D01*
X306622Y589355D01*
G01X303855Y587813D02*
Y590313D01*
X305397Y588521D01*
X303313D01*
G01X309067Y701365D02*
X311567D01*
Y702406D01*
X311442Y702740D01*
X311275Y702948D01*
X310942Y703031D01*
X310609Y702948D01*
X310400Y702698D01*
X310275Y702406D01*
Y701365D01*
G01Y702406D02*
X309067Y703031D01*
G01Y705798D02*
X311567D01*
X309775Y704256D01*
Y706340D01*
G01X309067Y708398D02*
X311567D01*
X311067Y707898D01*
G01X309067D02*
Y708898D01*
G01X311567Y711498D02*
X311484Y711165D01*
X311275Y710915D01*
X311025Y710748D01*
X310692Y710623D01*
X310317Y710581D01*
X309942Y710623D01*
X309609Y710748D01*
X309359Y710915D01*
X309150Y711165D01*
X309067Y711498D01*
X309150Y711831D01*
X309359Y712081D01*
X309609Y712248D01*
X309942Y712373D01*
X310317Y712415D01*
X310692Y712373D01*
X311025Y712248D01*
X311275Y712081D01*
X311484Y711831D01*
X311567Y711498D01*
G01X309067Y714598D02*
X309109Y714890D01*
X309234Y715223D01*
X309442Y715431D01*
X309734Y715515D01*
X310025Y715431D01*
X310275Y715181D01*
X310400Y714806D01*
Y714390D01*
X310484Y714140D01*
X310692Y713931D01*
X310984Y713848D01*
X311275Y713973D01*
X311484Y714265D01*
X311567Y714598D01*
X311484Y714931D01*
X311275Y715223D01*
X310984Y715348D01*
X310692Y715265D01*
X310484Y715056D01*
X310400Y714806D01*
Y714390D01*
X310275Y714015D01*
X310025Y713765D01*
X309734Y713681D01*
X309442Y713765D01*
X309234Y713973D01*
X309109Y714306D01*
X309067Y714598D01*
G01X301315Y700180D02*
X303815D01*
Y701221D01*
X303690Y701555D01*
X303523Y701763D01*
X303190Y701846D01*
X302857Y701763D01*
X302648Y701513D01*
X302523Y701221D01*
Y700180D01*
G01Y701221D02*
X301315Y701846D01*
G01Y704613D02*
X303815D01*
X302023Y703071D01*
Y705155D01*
G01X301315Y707213D02*
X303815D01*
X303315Y706713D01*
G01X301315D02*
Y707713D01*
G01X303815Y710313D02*
X303732Y709980D01*
X303523Y709730D01*
X303273Y709563D01*
X302940Y709438D01*
X302565Y709396D01*
X302190Y709438D01*
X301857Y709563D01*
X301607Y709730D01*
X301398Y709980D01*
X301315Y710313D01*
X301398Y710646D01*
X301607Y710896D01*
X301857Y711063D01*
X302190Y711188D01*
X302565Y711230D01*
X302940Y711188D01*
X303273Y711063D01*
X303523Y710896D01*
X303732Y710646D01*
X303815Y710313D01*
G01X302357Y712621D02*
X302648Y712913D01*
X302815Y713163D01*
X302898Y713496D01*
X302815Y713788D01*
X302648Y713996D01*
X302398Y714163D01*
X302107Y714205D01*
X301857Y714163D01*
X301607Y713996D01*
X301398Y713746D01*
X301315Y713455D01*
X301398Y713121D01*
X301648Y712830D01*
X302023Y712663D01*
X302440Y712621D01*
X302982Y712705D01*
X303273Y712830D01*
X303565Y713038D01*
X303773Y713330D01*
X303815Y713621D01*
X303732Y713913D01*
X303523Y714121D01*
G01X314000Y739800D02*
Y753200D01*
G01X304000Y739800D02*
X314000D01*
G01X304000Y753200D02*
Y739800D01*
G01X330000D02*
Y753200D01*
G01X320000Y739800D02*
X330000D01*
G01X320000Y753200D02*
Y739800D01*
G01X315000Y750200D02*
X319000D01*
Y742800D01*
G01X309678Y738131D02*
X313678D01*
Y730731D01*
G01X325678Y738131D02*
X329678D01*
Y730731D01*
G01X308406Y725098D02*
X312406D01*
Y717698D01*
G01X300554Y725113D02*
X304554D01*
Y717713D01*
G01X314000Y753200D02*
X304000D01*
G01X330000D02*
X320000D01*
G01X309178Y762131D02*
X313178D01*
Y754731D01*
G01X305178Y762131D02*
X309178D01*
Y754731D01*
G01X323678Y762131D02*
X327678D01*
Y754731D01*
G01X319678Y762131D02*
X323678D01*
Y754731D01*
G01X305406Y766698D02*
X301406D01*
Y774098D01*
G01X322067Y774865D02*
X324567D01*
Y775906D01*
X324442Y776240D01*
X324275Y776448D01*
X323942Y776531D01*
X323609Y776448D01*
X323400Y776198D01*
X323275Y775906D01*
Y774865D01*
G01Y775906D02*
X322067Y776531D01*
G01Y779298D02*
X324567D01*
X322775Y777756D01*
Y779840D01*
G01X322067Y781898D02*
X324567D01*
X324067Y781398D01*
G01X322067D02*
Y782398D01*
G01Y784998D02*
X324567D01*
X324067Y784498D01*
G01X322067D02*
Y785498D01*
G01Y788098D02*
X324567D01*
X324067Y787598D01*
G01X322067D02*
Y788598D01*
G01X325406Y765698D02*
X321406D01*
Y773098D01*
G01X318067Y774865D02*
X320567D01*
Y775906D01*
X320442Y776240D01*
X320275Y776448D01*
X319942Y776531D01*
X319609Y776448D01*
X319400Y776198D01*
X319275Y775906D01*
Y774865D01*
G01Y775906D02*
X318067Y776531D01*
G01Y779298D02*
X320567D01*
X318775Y777756D01*
Y779840D01*
G01X318067Y781898D02*
X320567D01*
X320067Y781398D01*
G01X318067D02*
Y782398D01*
G01Y784998D02*
X320567D01*
X320067Y784498D01*
G01X318067D02*
Y785498D01*
G01X320567Y788098D02*
X320484Y787765D01*
X320275Y787515D01*
X320025Y787348D01*
X319692Y787223D01*
X319317Y787181D01*
X318942Y787223D01*
X318609Y787348D01*
X318359Y787515D01*
X318150Y787765D01*
X318067Y788098D01*
X318150Y788431D01*
X318359Y788681D01*
X318609Y788848D01*
X318942Y788973D01*
X319317Y789015D01*
X319692Y788973D01*
X320025Y788848D01*
X320275Y788681D01*
X320484Y788431D01*
X320567Y788098D01*
G01X321406Y765698D02*
X317406D01*
Y773098D01*
G01X309293Y785232D02*
X309418Y784982D01*
X309501Y784690D01*
Y784357D01*
X309376Y783982D01*
X309168Y783690D01*
X308918Y783482D01*
X308501Y783315D01*
X308126Y783273D01*
X307751Y783357D01*
X307501Y783482D01*
X307251Y783732D01*
X307084Y784023D01*
X307001Y784315D01*
Y784607D01*
X307084Y784898D01*
X307209Y785148D01*
X307376Y785357D01*
G01X307001Y787915D02*
X309501D01*
X307709Y786373D01*
Y788457D01*
G01X307001Y790515D02*
X309501D01*
X309001Y790015D01*
G01X307001D02*
Y791015D01*
G01Y793615D02*
X309501D01*
X309001Y793115D01*
G01X307001D02*
Y794115D01*
G01X309084Y795923D02*
X309334Y796173D01*
X309459Y796465D01*
X309501Y796798D01*
X309418Y797215D01*
X309209Y797507D01*
X308959Y797590D01*
X308709Y797548D01*
X308501Y797382D01*
X308084Y796548D01*
X307793Y796173D01*
X307376Y795923D01*
X307001Y795840D01*
Y797590D01*
G01X301567Y783588D02*
X304067D01*
Y784629D01*
X303942Y784963D01*
X303775Y785171D01*
X303442Y785254D01*
X303109Y785171D01*
X302900Y784921D01*
X302775Y784629D01*
Y783588D01*
G01Y784629D02*
X301567Y785254D01*
G01Y788021D02*
X304067D01*
X302275Y786479D01*
Y788563D01*
G01X301567Y790621D02*
X304067D01*
X303567Y790121D01*
G01X301567D02*
Y791121D01*
G01Y793721D02*
X304067D01*
X303567Y793221D01*
G01X301567D02*
Y794221D01*
G01X303650Y796029D02*
X303900Y796279D01*
X304025Y796571D01*
X304067Y796904D01*
X303984Y797321D01*
X303775Y797613D01*
X303525Y797696D01*
X303275Y797654D01*
X303067Y797488D01*
X302650Y796654D01*
X302359Y796279D01*
X301942Y796029D01*
X301567Y795946D01*
Y797696D01*
G01X334852Y749179D02*
X337352D01*
Y750220D01*
X337227Y750554D01*
X337060Y750762D01*
X336727Y750845D01*
X336394Y750762D01*
X336185Y750512D01*
X336060Y750220D01*
Y749179D01*
G01Y750220D02*
X334852Y750845D01*
G01Y753112D02*
X337352D01*
X336852Y752612D01*
G01X334852D02*
Y753612D01*
G01Y756712D02*
X337352D01*
X335560Y755170D01*
Y757254D01*
G01X335352Y758395D02*
X335060Y758645D01*
X334894Y758979D01*
X334852Y759354D01*
X334894Y759687D01*
X335102Y760020D01*
X335352Y760229D01*
X335602Y760270D01*
X335894Y760187D01*
X336102Y759895D01*
X336185Y759604D01*
Y759229D01*
G01Y759604D02*
X336310Y759854D01*
X336519Y760062D01*
X336769Y760145D01*
X337019Y760062D01*
X337227Y759854D01*
X337352Y759479D01*
X337310Y759104D01*
X337144Y758729D01*
G01X343257Y749091D02*
X345757D01*
Y750132D01*
X345632Y750466D01*
X345465Y750674D01*
X345132Y750757D01*
X344799Y750674D01*
X344590Y750424D01*
X344465Y750132D01*
Y749091D01*
G01Y750132D02*
X343257Y750757D01*
G01Y753024D02*
X345757D01*
X345257Y752524D01*
G01X343257D02*
Y753524D01*
G01Y756624D02*
X345757D01*
X343965Y755082D01*
Y757166D01*
G01X344299Y758432D02*
X344590Y758724D01*
X344757Y758974D01*
X344840Y759307D01*
X344757Y759599D01*
X344590Y759807D01*
X344340Y759974D01*
X344049Y760016D01*
X343799Y759974D01*
X343549Y759807D01*
X343340Y759557D01*
X343257Y759266D01*
X343340Y758932D01*
X343590Y758641D01*
X343965Y758474D01*
X344382Y758432D01*
X344924Y758516D01*
X345215Y758641D01*
X345507Y758849D01*
X345715Y759141D01*
X345757Y759432D01*
X345674Y759724D01*
X345465Y759932D01*
G01X351661Y748737D02*
X354161D01*
Y749778D01*
X354036Y750112D01*
X353869Y750320D01*
X353536Y750403D01*
X353203Y750320D01*
X352994Y750070D01*
X352869Y749778D01*
Y748737D01*
G01Y749778D02*
X351661Y750403D01*
G01Y752670D02*
X354161D01*
X353661Y752170D01*
G01X351661D02*
Y753170D01*
G01X352036Y754853D02*
X351828Y755103D01*
X351703Y755395D01*
X351661Y755770D01*
X351744Y756145D01*
X351911Y756437D01*
X352203Y756645D01*
X352536Y756687D01*
X352869Y756603D01*
X353078Y756395D01*
X353244Y756103D01*
X353286Y755812D01*
X353244Y755520D01*
X353078Y755145D01*
X354161Y755270D01*
Y756395D01*
G01X351661Y758870D02*
X351703Y759162D01*
X351828Y759495D01*
X352036Y759703D01*
X352328Y759787D01*
X352619Y759703D01*
X352869Y759453D01*
X352994Y759078D01*
Y758662D01*
X353078Y758412D01*
X353286Y758203D01*
X353578Y758120D01*
X353869Y758245D01*
X354078Y758537D01*
X354161Y758870D01*
X354078Y759203D01*
X353869Y759495D01*
X353578Y759620D01*
X353286Y759537D01*
X353078Y759328D01*
X352994Y759078D01*
Y758662D01*
X352869Y758287D01*
X352619Y758037D01*
X352328Y757953D01*
X352036Y758037D01*
X351828Y758245D01*
X351703Y758578D01*
X351661Y758870D01*
G01X348740Y731794D02*
X351240D01*
Y732835D01*
X351115Y733169D01*
X350948Y733377D01*
X350615Y733460D01*
X350282Y733377D01*
X350073Y733127D01*
X349948Y732835D01*
Y731794D01*
G01Y732835D02*
X348740Y733460D01*
G01X349240Y734810D02*
X348948Y735060D01*
X348782Y735394D01*
X348740Y735769D01*
X348782Y736102D01*
X348990Y736435D01*
X349240Y736644D01*
X349490Y736685D01*
X349782Y736602D01*
X349990Y736310D01*
X350073Y736019D01*
Y735644D01*
G01Y736019D02*
X350198Y736269D01*
X350407Y736477D01*
X350657Y736560D01*
X350907Y736477D01*
X351115Y736269D01*
X351240Y735894D01*
X351198Y735519D01*
X351032Y735144D01*
G01X350823Y738035D02*
X351073Y738285D01*
X351198Y738577D01*
X351240Y738910D01*
X351157Y739327D01*
X350948Y739619D01*
X350698Y739702D01*
X350448Y739660D01*
X350240Y739494D01*
X349823Y738660D01*
X349532Y738285D01*
X349115Y738035D01*
X348740Y737952D01*
Y739702D01*
G01X351240Y741927D02*
X351157Y741594D01*
X350948Y741344D01*
X350698Y741177D01*
X350365Y741052D01*
X349990Y741010D01*
X349615Y741052D01*
X349282Y741177D01*
X349032Y741344D01*
X348823Y741594D01*
X348740Y741927D01*
X348823Y742260D01*
X349032Y742510D01*
X349282Y742677D01*
X349615Y742802D01*
X349990Y742844D01*
X350365Y742802D01*
X350698Y742677D01*
X350948Y742510D01*
X351157Y742260D01*
X351240Y741927D01*
G01X349240Y744110D02*
X348948Y744360D01*
X348782Y744694D01*
X348740Y745069D01*
X348782Y745402D01*
X348990Y745735D01*
X349240Y745944D01*
X349490Y745985D01*
X349782Y745902D01*
X349990Y745610D01*
X350073Y745319D01*
Y744944D01*
G01Y745319D02*
X350198Y745569D01*
X350407Y745777D01*
X350657Y745860D01*
X350907Y745777D01*
X351115Y745569D01*
X351240Y745194D01*
X351198Y744819D01*
X351032Y744444D01*
G01X357586Y733651D02*
X360086D01*
Y734692D01*
X359961Y735026D01*
X359794Y735234D01*
X359461Y735317D01*
X359128Y735234D01*
X358919Y734984D01*
X358794Y734692D01*
Y733651D01*
G01Y734692D02*
X357586Y735317D01*
G01X358086Y736667D02*
X357794Y736917D01*
X357628Y737251D01*
X357586Y737626D01*
X357628Y737959D01*
X357836Y738292D01*
X358086Y738501D01*
X358336Y738542D01*
X358628Y738459D01*
X358836Y738167D01*
X358919Y737876D01*
Y737501D01*
G01Y737876D02*
X359044Y738126D01*
X359253Y738334D01*
X359503Y738417D01*
X359753Y738334D01*
X359961Y738126D01*
X360086Y737751D01*
X360044Y737376D01*
X359878Y737001D01*
G01X359669Y739892D02*
X359919Y740142D01*
X360044Y740434D01*
X360086Y740767D01*
X360003Y741184D01*
X359794Y741476D01*
X359544Y741559D01*
X359294Y741517D01*
X359086Y741351D01*
X358669Y740517D01*
X358378Y740142D01*
X357961Y739892D01*
X357586Y739809D01*
Y741559D01*
G01Y743784D02*
X360086D01*
X359586Y743284D01*
G01X357586D02*
Y744284D01*
G01Y746884D02*
X357628Y747176D01*
X357753Y747509D01*
X357961Y747717D01*
X358253Y747801D01*
X358544Y747717D01*
X358794Y747467D01*
X358919Y747092D01*
Y746676D01*
X359003Y746426D01*
X359211Y746217D01*
X359503Y746134D01*
X359794Y746259D01*
X360003Y746551D01*
X360086Y746884D01*
X360003Y747217D01*
X359794Y747509D01*
X359503Y747634D01*
X359211Y747551D01*
X359003Y747342D01*
X358919Y747092D01*
Y746676D01*
X358794Y746301D01*
X358544Y746051D01*
X358253Y745967D01*
X357961Y746051D01*
X357753Y746259D01*
X357628Y746592D01*
X357586Y746884D01*
G01X365460Y734271D02*
X367960D01*
Y735312D01*
X367835Y735646D01*
X367668Y735854D01*
X367335Y735937D01*
X367002Y735854D01*
X366793Y735604D01*
X366668Y735312D01*
Y734271D01*
G01Y735312D02*
X365460Y735937D01*
G01X365960Y737287D02*
X365668Y737537D01*
X365502Y737871D01*
X365460Y738246D01*
X365502Y738579D01*
X365710Y738912D01*
X365960Y739121D01*
X366210Y739162D01*
X366502Y739079D01*
X366710Y738787D01*
X366793Y738496D01*
Y738121D01*
G01Y738496D02*
X366918Y738746D01*
X367127Y738954D01*
X367377Y739037D01*
X367627Y738954D01*
X367835Y738746D01*
X367960Y738371D01*
X367918Y737996D01*
X367752Y737621D01*
G01X367543Y740512D02*
X367793Y740762D01*
X367918Y741054D01*
X367960Y741387D01*
X367877Y741804D01*
X367668Y742096D01*
X367418Y742179D01*
X367168Y742137D01*
X366960Y741971D01*
X366543Y741137D01*
X366252Y740762D01*
X365835Y740512D01*
X365460Y740429D01*
Y742179D01*
G01X365960Y743487D02*
X365668Y743737D01*
X365502Y744071D01*
X365460Y744446D01*
X365502Y744779D01*
X365710Y745112D01*
X365960Y745321D01*
X366210Y745362D01*
X366502Y745279D01*
X366710Y744987D01*
X366793Y744696D01*
Y744321D01*
G01Y744696D02*
X366918Y744946D01*
X367127Y745154D01*
X367377Y745237D01*
X367627Y745154D01*
X367835Y744946D01*
X367960Y744571D01*
X367918Y744196D01*
X367752Y743821D01*
G01X365960Y746587D02*
X365668Y746837D01*
X365502Y747171D01*
X365460Y747546D01*
X365502Y747879D01*
X365710Y748212D01*
X365960Y748421D01*
X366210Y748462D01*
X366502Y748379D01*
X366710Y748087D01*
X366793Y747796D01*
Y747421D01*
G01Y747796D02*
X366918Y748046D01*
X367127Y748254D01*
X367377Y748337D01*
X367627Y748254D01*
X367835Y748046D01*
X367960Y747671D01*
X367918Y747296D01*
X367752Y746921D01*
G01X338833Y732501D02*
X341333D01*
Y733542D01*
X341208Y733876D01*
X341041Y734084D01*
X340708Y734167D01*
X340375Y734084D01*
X340166Y733834D01*
X340041Y733542D01*
Y732501D01*
G01Y733542D02*
X338833Y734167D01*
G01X339333Y735517D02*
X339041Y735767D01*
X338875Y736101D01*
X338833Y736476D01*
X338875Y736809D01*
X339083Y737142D01*
X339333Y737351D01*
X339583Y737392D01*
X339875Y737309D01*
X340083Y737017D01*
X340166Y736726D01*
Y736351D01*
G01Y736726D02*
X340291Y736976D01*
X340500Y737184D01*
X340750Y737267D01*
X341000Y737184D01*
X341208Y736976D01*
X341333Y736601D01*
X341291Y736226D01*
X341125Y735851D01*
G01X340916Y738742D02*
X341166Y738992D01*
X341291Y739284D01*
X341333Y739617D01*
X341250Y740034D01*
X341041Y740326D01*
X340791Y740409D01*
X340541Y740367D01*
X340333Y740201D01*
X339916Y739367D01*
X339625Y738992D01*
X339208Y738742D01*
X338833Y738659D01*
Y740409D01*
G01X339333Y741717D02*
X339041Y741967D01*
X338875Y742301D01*
X338833Y742676D01*
X338875Y743009D01*
X339083Y743342D01*
X339333Y743551D01*
X339583Y743592D01*
X339875Y743509D01*
X340083Y743217D01*
X340166Y742926D01*
Y742551D01*
G01Y742926D02*
X340291Y743176D01*
X340500Y743384D01*
X340750Y743467D01*
X341000Y743384D01*
X341208Y743176D01*
X341333Y742801D01*
X341291Y742426D01*
X341125Y742051D01*
G01X339875Y744942D02*
X340166Y745234D01*
X340333Y745484D01*
X340416Y745817D01*
X340333Y746109D01*
X340166Y746317D01*
X339916Y746484D01*
X339625Y746526D01*
X339375Y746484D01*
X339125Y746317D01*
X338916Y746067D01*
X338833Y745776D01*
X338916Y745442D01*
X339166Y745151D01*
X339541Y744984D01*
X339958Y744942D01*
X340500Y745026D01*
X340791Y745151D01*
X341083Y745359D01*
X341291Y745651D01*
X341333Y745942D01*
X341250Y746234D01*
X341041Y746442D01*
G01X346078Y734340D02*
X346203Y734090D01*
X346286Y733798D01*
Y733465D01*
X346161Y733090D01*
X345953Y732798D01*
X345703Y732590D01*
X345286Y732423D01*
X344911Y732381D01*
X344536Y732465D01*
X344286Y732590D01*
X344036Y732840D01*
X343869Y733131D01*
X343786Y733423D01*
Y733715D01*
X343869Y734006D01*
X343994Y734256D01*
X344161Y734465D01*
G01X344286Y735606D02*
X343994Y735856D01*
X343828Y736190D01*
X343786Y736565D01*
X343828Y736898D01*
X344036Y737231D01*
X344286Y737440D01*
X344536Y737481D01*
X344828Y737398D01*
X345036Y737106D01*
X345119Y736815D01*
Y736440D01*
G01Y736815D02*
X345244Y737065D01*
X345453Y737273D01*
X345703Y737356D01*
X345953Y737273D01*
X346161Y737065D01*
X346286Y736690D01*
X346244Y736315D01*
X346078Y735940D01*
G01X345869Y738831D02*
X346119Y739081D01*
X346244Y739373D01*
X346286Y739706D01*
X346203Y740123D01*
X345994Y740415D01*
X345744Y740498D01*
X345494Y740456D01*
X345286Y740290D01*
X344869Y739456D01*
X344578Y739081D01*
X344161Y738831D01*
X343786Y738748D01*
Y740498D01*
G01X346286Y742723D02*
X346203Y742390D01*
X345994Y742140D01*
X345744Y741973D01*
X345411Y741848D01*
X345036Y741806D01*
X344661Y741848D01*
X344328Y741973D01*
X344078Y742140D01*
X343869Y742390D01*
X343786Y742723D01*
X343869Y743056D01*
X344078Y743306D01*
X344328Y743473D01*
X344661Y743598D01*
X345036Y743640D01*
X345411Y743598D01*
X345744Y743473D01*
X345994Y743306D01*
X346203Y743056D01*
X346286Y742723D01*
G01X343786Y745823D02*
X346286D01*
X345786Y745323D01*
G01X343786D02*
Y746323D01*
G01X364036Y735401D02*
X364161Y735151D01*
X364244Y734859D01*
Y734526D01*
X364119Y734151D01*
X363911Y733859D01*
X363661Y733651D01*
X363244Y733484D01*
X362869Y733442D01*
X362494Y733526D01*
X362244Y733651D01*
X361994Y733901D01*
X361827Y734192D01*
X361744Y734484D01*
Y734776D01*
X361827Y735067D01*
X361952Y735317D01*
X362119Y735526D01*
G01X362244Y736667D02*
X361952Y736917D01*
X361786Y737251D01*
X361744Y737626D01*
X361786Y737959D01*
X361994Y738292D01*
X362244Y738501D01*
X362494Y738542D01*
X362786Y738459D01*
X362994Y738167D01*
X363077Y737876D01*
Y737501D01*
G01Y737876D02*
X363202Y738126D01*
X363411Y738334D01*
X363661Y738417D01*
X363911Y738334D01*
X364119Y738126D01*
X364244Y737751D01*
X364202Y737376D01*
X364036Y737001D01*
G01X363827Y739892D02*
X364077Y740142D01*
X364202Y740434D01*
X364244Y740767D01*
X364161Y741184D01*
X363952Y741476D01*
X363702Y741559D01*
X363452Y741517D01*
X363244Y741351D01*
X362827Y740517D01*
X362536Y740142D01*
X362119Y739892D01*
X361744Y739809D01*
Y741559D01*
G01Y743784D02*
X364244D01*
X363744Y743284D01*
G01X361744D02*
Y744284D01*
G01Y746884D02*
X364244D01*
X363744Y746384D01*
G01X361744D02*
Y747384D01*
G01X337321Y734428D02*
X337446Y734178D01*
X337529Y733886D01*
Y733553D01*
X337404Y733178D01*
X337196Y732886D01*
X336946Y732678D01*
X336529Y732511D01*
X336154Y732469D01*
X335779Y732553D01*
X335529Y732678D01*
X335279Y732928D01*
X335112Y733219D01*
X335029Y733511D01*
Y733803D01*
X335112Y734094D01*
X335237Y734344D01*
X335404Y734553D01*
G01X335529Y735694D02*
X335237Y735944D01*
X335071Y736278D01*
X335029Y736653D01*
X335071Y736986D01*
X335279Y737319D01*
X335529Y737528D01*
X335779Y737569D01*
X336071Y737486D01*
X336279Y737194D01*
X336362Y736903D01*
Y736528D01*
G01Y736903D02*
X336487Y737153D01*
X336696Y737361D01*
X336946Y737444D01*
X337196Y737361D01*
X337404Y737153D01*
X337529Y736778D01*
X337487Y736403D01*
X337321Y736028D01*
G01X337112Y738919D02*
X337362Y739169D01*
X337487Y739461D01*
X337529Y739794D01*
X337446Y740211D01*
X337237Y740503D01*
X336987Y740586D01*
X336737Y740544D01*
X336529Y740378D01*
X336112Y739544D01*
X335821Y739169D01*
X335404Y738919D01*
X335029Y738836D01*
Y740586D01*
G01Y742811D02*
X337529D01*
X337029Y742311D01*
G01X335029D02*
Y743311D01*
G01X335529Y744994D02*
X335237Y745244D01*
X335071Y745578D01*
X335029Y745953D01*
X335071Y746286D01*
X335279Y746619D01*
X335529Y746828D01*
X335779Y746869D01*
X336071Y746786D01*
X336279Y746494D01*
X336362Y746203D01*
Y745828D01*
G01Y746203D02*
X336487Y746453D01*
X336696Y746661D01*
X336946Y746744D01*
X337196Y746661D01*
X337404Y746453D01*
X337529Y746078D01*
X337487Y745703D01*
X337321Y745328D01*
G01X355455Y736686D02*
X355580Y736436D01*
X355663Y736144D01*
Y735811D01*
X355538Y735436D01*
X355330Y735144D01*
X355080Y734936D01*
X354663Y734769D01*
X354288Y734727D01*
X353913Y734811D01*
X353663Y734936D01*
X353413Y735186D01*
X353246Y735477D01*
X353163Y735769D01*
Y736061D01*
X353246Y736352D01*
X353371Y736602D01*
X353538Y736811D01*
G01X353163Y739369D02*
X355663D01*
X353871Y737827D01*
Y739911D01*
G01X353163Y741969D02*
X355663D01*
X355163Y741469D01*
G01X353163D02*
Y742469D01*
G01X353538Y744152D02*
X353330Y744402D01*
X353205Y744694D01*
X353163Y745069D01*
X353246Y745444D01*
X353413Y745736D01*
X353705Y745944D01*
X354038Y745986D01*
X354371Y745902D01*
X354580Y745694D01*
X354746Y745402D01*
X354788Y745111D01*
X354746Y744819D01*
X354580Y744444D01*
X355663Y744569D01*
Y745694D01*
G01X349826Y751972D02*
X348034D01*
X347659Y752139D01*
X347409Y752472D01*
X347326Y752889D01*
X347409Y753306D01*
X347659Y753639D01*
X348034Y753806D01*
X349826D01*
G01X348368Y755197D02*
X348659Y755489D01*
X348826Y755739D01*
X348909Y756072D01*
X348826Y756364D01*
X348659Y756572D01*
X348409Y756739D01*
X348118Y756781D01*
X347868Y756739D01*
X347618Y756572D01*
X347409Y756322D01*
X347326Y756031D01*
X347409Y755697D01*
X347659Y755406D01*
X348034Y755239D01*
X348451Y755197D01*
X348993Y755281D01*
X349284Y755406D01*
X349576Y755614D01*
X349784Y755906D01*
X349826Y756197D01*
X349743Y756489D01*
X349534Y756697D01*
G01X347618Y758381D02*
X347409Y758672D01*
X347326Y759006D01*
X347409Y759339D01*
X347659Y759631D01*
X348034Y759839D01*
X348409Y759922D01*
X348868D01*
X349243Y759839D01*
X349576Y759631D01*
X349743Y759381D01*
X349826Y759089D01*
X349743Y758756D01*
X349576Y758506D01*
X349326Y758339D01*
X348993Y758256D01*
X348701Y758339D01*
X348409Y758547D01*
X348243Y758797D01*
X348201Y759089D01*
X348284Y759422D01*
X348493Y759672D01*
X348868Y759922D01*
G01X341599Y751795D02*
X339807D01*
X339432Y751962D01*
X339182Y752295D01*
X339099Y752712D01*
X339182Y753129D01*
X339432Y753462D01*
X339807Y753629D01*
X341599D01*
G01X340141Y755020D02*
X340432Y755312D01*
X340599Y755562D01*
X340682Y755895D01*
X340599Y756187D01*
X340432Y756395D01*
X340182Y756562D01*
X339891Y756604D01*
X339641Y756562D01*
X339391Y756395D01*
X339182Y756145D01*
X339099Y755854D01*
X339182Y755520D01*
X339432Y755229D01*
X339807Y755062D01*
X340224Y755020D01*
X340766Y755104D01*
X341057Y755229D01*
X341349Y755437D01*
X341557Y755729D01*
X341599Y756020D01*
X341516Y756312D01*
X341307Y756520D01*
G01X339099Y759412D02*
X341599D01*
X339807Y757870D01*
Y759954D01*
G01X358142Y751441D02*
X356350D01*
X355975Y751608D01*
X355725Y751941D01*
X355642Y752358D01*
X355725Y752775D01*
X355975Y753108D01*
X356350Y753275D01*
X358142D01*
G01X355642Y755375D02*
X356184Y755458D01*
X356642Y755583D01*
X357059Y755750D01*
X357517Y755958D01*
X358142Y756291D01*
Y754625D01*
G01X355642Y759058D02*
X358142D01*
X356350Y757516D01*
Y759600D01*
G01X339098Y762580D02*
X341598D01*
Y763621D01*
X341473Y763955D01*
X341306Y764163D01*
X340973Y764246D01*
X340640Y764163D01*
X340431Y763913D01*
X340306Y763621D01*
Y762580D01*
G01Y763621D02*
X339098Y764246D01*
G01X339598Y765596D02*
X339306Y765846D01*
X339140Y766180D01*
X339098Y766555D01*
X339140Y766888D01*
X339348Y767221D01*
X339598Y767430D01*
X339848Y767471D01*
X340140Y767388D01*
X340348Y767096D01*
X340431Y766805D01*
Y766430D01*
G01Y766805D02*
X340556Y767055D01*
X340765Y767263D01*
X341015Y767346D01*
X341265Y767263D01*
X341473Y767055D01*
X341598Y766680D01*
X341556Y766305D01*
X341390Y765930D01*
G01X341181Y768821D02*
X341431Y769071D01*
X341556Y769363D01*
X341598Y769696D01*
X341515Y770113D01*
X341306Y770405D01*
X341056Y770488D01*
X340806Y770446D01*
X340598Y770280D01*
X340181Y769446D01*
X339890Y769071D01*
X339473Y768821D01*
X339098Y768738D01*
Y770488D01*
G01X341598Y772713D02*
X341515Y772380D01*
X341306Y772130D01*
X341056Y771963D01*
X340723Y771838D01*
X340348Y771796D01*
X339973Y771838D01*
X339640Y771963D01*
X339390Y772130D01*
X339181Y772380D01*
X339098Y772713D01*
X339181Y773046D01*
X339390Y773296D01*
X339640Y773463D01*
X339973Y773588D01*
X340348Y773630D01*
X340723Y773588D01*
X341056Y773463D01*
X341306Y773296D01*
X341515Y773046D01*
X341598Y772713D01*
G01X339098Y775813D02*
X341598D01*
X341098Y775313D01*
G01X339098D02*
Y776313D01*
G01X334675Y762491D02*
X337175D01*
Y763532D01*
X337050Y763866D01*
X336883Y764074D01*
X336550Y764157D01*
X336217Y764074D01*
X336008Y763824D01*
X335883Y763532D01*
Y762491D01*
G01Y763532D02*
X334675Y764157D01*
G01X335175Y765507D02*
X334883Y765757D01*
X334717Y766091D01*
X334675Y766466D01*
X334717Y766799D01*
X334925Y767132D01*
X335175Y767341D01*
X335425Y767382D01*
X335717Y767299D01*
X335925Y767007D01*
X336008Y766716D01*
Y766341D01*
G01Y766716D02*
X336133Y766966D01*
X336342Y767174D01*
X336592Y767257D01*
X336842Y767174D01*
X337050Y766966D01*
X337175Y766591D01*
X337133Y766216D01*
X336967Y765841D01*
G01X336758Y768732D02*
X337008Y768982D01*
X337133Y769274D01*
X337175Y769607D01*
X337092Y770024D01*
X336883Y770316D01*
X336633Y770399D01*
X336383Y770357D01*
X336175Y770191D01*
X335758Y769357D01*
X335467Y768982D01*
X335050Y768732D01*
X334675Y768649D01*
Y770399D01*
G01X337175Y772624D02*
X337092Y772291D01*
X336883Y772041D01*
X336633Y771874D01*
X336300Y771749D01*
X335925Y771707D01*
X335550Y771749D01*
X335217Y771874D01*
X334967Y772041D01*
X334758Y772291D01*
X334675Y772624D01*
X334758Y772957D01*
X334967Y773207D01*
X335217Y773374D01*
X335550Y773499D01*
X335925Y773541D01*
X336300Y773499D01*
X336633Y773374D01*
X336883Y773207D01*
X337092Y772957D01*
X337175Y772624D01*
G01X336758Y774932D02*
X337008Y775182D01*
X337133Y775474D01*
X337175Y775807D01*
X337092Y776224D01*
X336883Y776516D01*
X336633Y776599D01*
X336383Y776557D01*
X336175Y776391D01*
X335758Y775557D01*
X335467Y775182D01*
X335050Y774932D01*
X334675Y774849D01*
Y776599D01*
G01X350069Y762402D02*
X352569D01*
Y763443D01*
X352444Y763777D01*
X352277Y763985D01*
X351944Y764068D01*
X351611Y763985D01*
X351402Y763735D01*
X351277Y763443D01*
Y762402D01*
G01Y763443D02*
X350069Y764068D01*
G01X350569Y765418D02*
X350277Y765668D01*
X350111Y766002D01*
X350069Y766377D01*
X350111Y766710D01*
X350319Y767043D01*
X350569Y767252D01*
X350819Y767293D01*
X351111Y767210D01*
X351319Y766918D01*
X351402Y766627D01*
Y766252D01*
G01Y766627D02*
X351527Y766877D01*
X351736Y767085D01*
X351986Y767168D01*
X352236Y767085D01*
X352444Y766877D01*
X352569Y766502D01*
X352527Y766127D01*
X352361Y765752D01*
G01X352152Y768643D02*
X352402Y768893D01*
X352527Y769185D01*
X352569Y769518D01*
X352486Y769935D01*
X352277Y770227D01*
X352027Y770310D01*
X351777Y770268D01*
X351569Y770102D01*
X351152Y769268D01*
X350861Y768893D01*
X350444Y768643D01*
X350069Y768560D01*
Y770310D01*
G01Y772535D02*
X352569D01*
X352069Y772035D01*
G01X350069D02*
Y773035D01*
G01X351111Y774843D02*
X351402Y775135D01*
X351569Y775385D01*
X351652Y775718D01*
X351569Y776010D01*
X351402Y776218D01*
X351152Y776385D01*
X350861Y776427D01*
X350611Y776385D01*
X350361Y776218D01*
X350152Y775968D01*
X350069Y775677D01*
X350152Y775343D01*
X350402Y775052D01*
X350777Y774885D01*
X351194Y774843D01*
X351736Y774927D01*
X352027Y775052D01*
X352319Y775260D01*
X352527Y775552D01*
X352569Y775843D01*
X352486Y776135D01*
X352277Y776343D01*
G01X345822Y762491D02*
X348322D01*
Y763532D01*
X348197Y763866D01*
X348030Y764074D01*
X347697Y764157D01*
X347364Y764074D01*
X347155Y763824D01*
X347030Y763532D01*
Y762491D01*
G01Y763532D02*
X345822Y764157D01*
G01X346322Y765507D02*
X346030Y765757D01*
X345864Y766091D01*
X345822Y766466D01*
X345864Y766799D01*
X346072Y767132D01*
X346322Y767341D01*
X346572Y767382D01*
X346864Y767299D01*
X347072Y767007D01*
X347155Y766716D01*
Y766341D01*
G01Y766716D02*
X347280Y766966D01*
X347489Y767174D01*
X347739Y767257D01*
X347989Y767174D01*
X348197Y766966D01*
X348322Y766591D01*
X348280Y766216D01*
X348114Y765841D01*
G01X347905Y768732D02*
X348155Y768982D01*
X348280Y769274D01*
X348322Y769607D01*
X348239Y770024D01*
X348030Y770316D01*
X347780Y770399D01*
X347530Y770357D01*
X347322Y770191D01*
X346905Y769357D01*
X346614Y768982D01*
X346197Y768732D01*
X345822Y768649D01*
Y770399D01*
G01Y772624D02*
X348322D01*
X347822Y772124D01*
G01X345822D02*
Y773124D01*
G01Y775641D02*
X346364Y775724D01*
X346822Y775849D01*
X347239Y776016D01*
X347697Y776224D01*
X348322Y776557D01*
Y774891D01*
G01X359181Y761961D02*
X361681D01*
Y763002D01*
X361556Y763336D01*
X361389Y763544D01*
X361056Y763627D01*
X360723Y763544D01*
X360514Y763294D01*
X360389Y763002D01*
Y761961D01*
G01Y763002D02*
X359181Y763627D01*
G01X359681Y764977D02*
X359389Y765227D01*
X359223Y765561D01*
X359181Y765936D01*
X359223Y766269D01*
X359431Y766602D01*
X359681Y766811D01*
X359931Y766852D01*
X360223Y766769D01*
X360431Y766477D01*
X360514Y766186D01*
Y765811D01*
G01Y766186D02*
X360639Y766436D01*
X360848Y766644D01*
X361098Y766727D01*
X361348Y766644D01*
X361556Y766436D01*
X361681Y766061D01*
X361639Y765686D01*
X361473Y765311D01*
G01X361264Y768202D02*
X361514Y768452D01*
X361639Y768744D01*
X361681Y769077D01*
X361598Y769494D01*
X361389Y769786D01*
X361139Y769869D01*
X360889Y769827D01*
X360681Y769661D01*
X360264Y768827D01*
X359973Y768452D01*
X359556Y768202D01*
X359181Y768119D01*
Y769869D01*
G01X359681Y771177D02*
X359389Y771427D01*
X359223Y771761D01*
X359181Y772136D01*
X359223Y772469D01*
X359431Y772802D01*
X359681Y773011D01*
X359931Y773052D01*
X360223Y772969D01*
X360431Y772677D01*
X360514Y772386D01*
Y772011D01*
G01Y772386D02*
X360639Y772636D01*
X360848Y772844D01*
X361098Y772927D01*
X361348Y772844D01*
X361556Y772636D01*
X361681Y772261D01*
X361639Y771886D01*
X361473Y771511D01*
G01X359181Y775194D02*
X361681D01*
X361181Y774694D01*
G01X359181D02*
Y775694D01*
G01X355111Y762137D02*
X357611D01*
Y763178D01*
X357486Y763512D01*
X357319Y763720D01*
X356986Y763803D01*
X356653Y763720D01*
X356444Y763470D01*
X356319Y763178D01*
Y762137D01*
G01Y763178D02*
X355111Y763803D01*
G01X355611Y765153D02*
X355319Y765403D01*
X355153Y765737D01*
X355111Y766112D01*
X355153Y766445D01*
X355361Y766778D01*
X355611Y766987D01*
X355861Y767028D01*
X356153Y766945D01*
X356361Y766653D01*
X356444Y766362D01*
Y765987D01*
G01Y766362D02*
X356569Y766612D01*
X356778Y766820D01*
X357028Y766903D01*
X357278Y766820D01*
X357486Y766612D01*
X357611Y766237D01*
X357569Y765862D01*
X357403Y765487D01*
G01X357194Y768378D02*
X357444Y768628D01*
X357569Y768920D01*
X357611Y769253D01*
X357528Y769670D01*
X357319Y769962D01*
X357069Y770045D01*
X356819Y770003D01*
X356611Y769837D01*
X356194Y769003D01*
X355903Y768628D01*
X355486Y768378D01*
X355111Y768295D01*
Y770045D01*
G01X355611Y771353D02*
X355319Y771603D01*
X355153Y771937D01*
X355111Y772312D01*
X355153Y772645D01*
X355361Y772978D01*
X355611Y773187D01*
X355861Y773228D01*
X356153Y773145D01*
X356361Y772853D01*
X356444Y772562D01*
Y772187D01*
G01Y772562D02*
X356569Y772812D01*
X356778Y773020D01*
X357028Y773103D01*
X357278Y773020D01*
X357486Y772812D01*
X357611Y772437D01*
X357569Y772062D01*
X357403Y771687D01*
G01X357194Y774578D02*
X357444Y774828D01*
X357569Y775120D01*
X357611Y775453D01*
X357528Y775870D01*
X357319Y776162D01*
X357069Y776245D01*
X356819Y776203D01*
X356611Y776037D01*
X356194Y775203D01*
X355903Y774828D01*
X355486Y774578D01*
X355111Y774495D01*
Y776245D01*
G01X459261Y786928D02*
X457469D01*
X457094Y787095D01*
X456844Y787428D01*
X456761Y787845D01*
X456844Y788262D01*
X457094Y788595D01*
X457469Y788762D01*
X459261D01*
G01X456761Y790862D02*
X457303Y790945D01*
X457761Y791070D01*
X458178Y791237D01*
X458636Y791445D01*
X459261Y791778D01*
Y790112D01*
G01X456761Y794045D02*
X459261D01*
X458761Y793545D01*
G01X456761D02*
Y794545D01*
G01X467665Y787105D02*
X465873D01*
X465498Y787272D01*
X465248Y787605D01*
X465165Y788022D01*
X465248Y788439D01*
X465498Y788772D01*
X465873Y788939D01*
X467665D01*
G01X466207Y790330D02*
X466498Y790622D01*
X466665Y790872D01*
X466748Y791205D01*
X466665Y791497D01*
X466498Y791705D01*
X466248Y791872D01*
X465957Y791914D01*
X465707Y791872D01*
X465457Y791705D01*
X465248Y791455D01*
X465165Y791164D01*
X465248Y790830D01*
X465498Y790539D01*
X465873Y790372D01*
X466290Y790330D01*
X466832Y790414D01*
X467123Y790539D01*
X467415Y790747D01*
X467623Y791039D01*
X467665Y791330D01*
X467582Y791622D01*
X467373Y791830D01*
G01X465540Y793305D02*
X465332Y793555D01*
X465207Y793847D01*
X465165Y794222D01*
X465248Y794597D01*
X465415Y794889D01*
X465707Y795097D01*
X466040Y795139D01*
X466373Y795055D01*
X466582Y794847D01*
X466748Y794555D01*
X466790Y794264D01*
X466748Y793972D01*
X466582Y793597D01*
X467665Y793722D01*
Y794847D01*
G01X469146Y787143D02*
X471646D01*
Y788184D01*
X471521Y788518D01*
X471354Y788726D01*
X471021Y788809D01*
X470688Y788726D01*
X470479Y788476D01*
X470354Y788184D01*
Y787143D01*
G01Y788184D02*
X469146Y788809D01*
G01Y791076D02*
X471646D01*
X471146Y790576D01*
G01X469146D02*
Y791576D01*
G01Y794676D02*
X471646D01*
X469854Y793134D01*
Y795218D01*
G01X471646Y797276D02*
X471563Y796943D01*
X471354Y796693D01*
X471104Y796526D01*
X470771Y796401D01*
X470396Y796359D01*
X470021Y796401D01*
X469688Y796526D01*
X469438Y796693D01*
X469229Y796943D01*
X469146Y797276D01*
X469229Y797609D01*
X469438Y797859D01*
X469688Y798026D01*
X470021Y798151D01*
X470396Y798193D01*
X470771Y798151D01*
X471104Y798026D01*
X471354Y797859D01*
X471563Y797609D01*
X471646Y797276D01*
G01X460830Y787054D02*
X463330D01*
Y788095D01*
X463205Y788429D01*
X463038Y788637D01*
X462705Y788720D01*
X462372Y788637D01*
X462163Y788387D01*
X462038Y788095D01*
Y787054D01*
G01Y788095D02*
X460830Y788720D01*
G01Y790987D02*
X463330D01*
X462830Y790487D01*
G01X460830D02*
Y791487D01*
G01Y794587D02*
X463330D01*
X461538Y793045D01*
Y795129D01*
G01X460830Y797687D02*
X463330D01*
X461538Y796145D01*
Y798229D01*
G01X452603Y787143D02*
X455103D01*
Y788184D01*
X454978Y788518D01*
X454811Y788726D01*
X454478Y788809D01*
X454145Y788726D01*
X453936Y788476D01*
X453811Y788184D01*
Y787143D01*
G01Y788184D02*
X452603Y788809D01*
G01Y791076D02*
X455103D01*
X454603Y790576D01*
G01X452603D02*
Y791576D01*
G01Y794676D02*
X455103D01*
X453311Y793134D01*
Y795218D01*
G01X452603Y797193D02*
X453145Y797276D01*
X453603Y797401D01*
X454020Y797568D01*
X454478Y797776D01*
X455103Y798109D01*
Y796443D01*
G01X462740Y800739D02*
X465240D01*
Y801780D01*
X465115Y802114D01*
X464948Y802322D01*
X464615Y802405D01*
X464282Y802322D01*
X464073Y802072D01*
X463948Y801780D01*
Y800739D01*
G01Y801780D02*
X462740Y802405D01*
G01X463240Y803755D02*
X462948Y804005D01*
X462782Y804339D01*
X462740Y804714D01*
X462782Y805047D01*
X462990Y805380D01*
X463240Y805589D01*
X463490Y805630D01*
X463782Y805547D01*
X463990Y805255D01*
X464073Y804964D01*
Y804589D01*
G01Y804964D02*
X464198Y805214D01*
X464407Y805422D01*
X464657Y805505D01*
X464907Y805422D01*
X465115Y805214D01*
X465240Y804839D01*
X465198Y804464D01*
X465032Y804089D01*
G01X464823Y806980D02*
X465073Y807230D01*
X465198Y807522D01*
X465240Y807855D01*
X465157Y808272D01*
X464948Y808564D01*
X464698Y808647D01*
X464448Y808605D01*
X464240Y808439D01*
X463823Y807605D01*
X463532Y807230D01*
X463115Y806980D01*
X462740Y806897D01*
Y808647D01*
G01X465240Y810872D02*
X465157Y810539D01*
X464948Y810289D01*
X464698Y810122D01*
X464365Y809997D01*
X463990Y809955D01*
X463615Y809997D01*
X463282Y810122D01*
X463032Y810289D01*
X462823Y810539D01*
X462740Y810872D01*
X462823Y811205D01*
X463032Y811455D01*
X463282Y811622D01*
X463615Y811747D01*
X463990Y811789D01*
X464365Y811747D01*
X464698Y811622D01*
X464948Y811455D01*
X465157Y811205D01*
X465240Y810872D01*
G01X462740Y814472D02*
X465240D01*
X463448Y812930D01*
Y815014D01*
G01X458406Y800828D02*
X460906D01*
Y801869D01*
X460781Y802203D01*
X460614Y802411D01*
X460281Y802494D01*
X459948Y802411D01*
X459739Y802161D01*
X459614Y801869D01*
Y800828D01*
G01Y801869D02*
X458406Y802494D01*
G01X458906Y803844D02*
X458614Y804094D01*
X458448Y804428D01*
X458406Y804803D01*
X458448Y805136D01*
X458656Y805469D01*
X458906Y805678D01*
X459156Y805719D01*
X459448Y805636D01*
X459656Y805344D01*
X459739Y805053D01*
Y804678D01*
G01Y805053D02*
X459864Y805303D01*
X460073Y805511D01*
X460323Y805594D01*
X460573Y805511D01*
X460781Y805303D01*
X460906Y804928D01*
X460864Y804553D01*
X460698Y804178D01*
G01X460489Y807069D02*
X460739Y807319D01*
X460864Y807611D01*
X460906Y807944D01*
X460823Y808361D01*
X460614Y808653D01*
X460364Y808736D01*
X460114Y808694D01*
X459906Y808528D01*
X459489Y807694D01*
X459198Y807319D01*
X458781Y807069D01*
X458406Y806986D01*
Y808736D01*
G01X460906Y810961D02*
X460823Y810628D01*
X460614Y810378D01*
X460364Y810211D01*
X460031Y810086D01*
X459656Y810044D01*
X459281Y810086D01*
X458948Y810211D01*
X458698Y810378D01*
X458489Y810628D01*
X458406Y810961D01*
X458489Y811294D01*
X458698Y811544D01*
X458948Y811711D01*
X459281Y811836D01*
X459656Y811878D01*
X460031Y811836D01*
X460364Y811711D01*
X460614Y811544D01*
X460823Y811294D01*
X460906Y810961D01*
G01X458781Y813144D02*
X458573Y813394D01*
X458448Y813686D01*
X458406Y814061D01*
X458489Y814436D01*
X458656Y814728D01*
X458948Y814936D01*
X459281Y814978D01*
X459614Y814894D01*
X459823Y814686D01*
X459989Y814394D01*
X460031Y814103D01*
X459989Y813811D01*
X459823Y813436D01*
X460906Y813561D01*
Y814686D01*
G01X467910Y800640D02*
X470410D01*
Y801681D01*
X470285Y802015D01*
X470118Y802223D01*
X469785Y802306D01*
X469452Y802223D01*
X469243Y801973D01*
X469118Y801681D01*
Y800640D01*
G01Y801681D02*
X467910Y802306D01*
G01X468410Y803656D02*
X468118Y803906D01*
X467952Y804240D01*
X467910Y804615D01*
X467952Y804948D01*
X468160Y805281D01*
X468410Y805490D01*
X468660Y805531D01*
X468952Y805448D01*
X469160Y805156D01*
X469243Y804865D01*
Y804490D01*
G01Y804865D02*
X469368Y805115D01*
X469577Y805323D01*
X469827Y805406D01*
X470077Y805323D01*
X470285Y805115D01*
X470410Y804740D01*
X470368Y804365D01*
X470202Y803990D01*
G01X469993Y806881D02*
X470243Y807131D01*
X470368Y807423D01*
X470410Y807756D01*
X470327Y808173D01*
X470118Y808465D01*
X469868Y808548D01*
X469618Y808506D01*
X469410Y808340D01*
X468993Y807506D01*
X468702Y807131D01*
X468285Y806881D01*
X467910Y806798D01*
Y808548D01*
G01X470410Y810773D02*
X470327Y810440D01*
X470118Y810190D01*
X469868Y810023D01*
X469535Y809898D01*
X469160Y809856D01*
X468785Y809898D01*
X468452Y810023D01*
X468202Y810190D01*
X467993Y810440D01*
X467910Y810773D01*
X467993Y811106D01*
X468202Y811356D01*
X468452Y811523D01*
X468785Y811648D01*
X469160Y811690D01*
X469535Y811648D01*
X469868Y811523D01*
X470118Y811356D01*
X470327Y811106D01*
X470410Y810773D01*
G01X467910Y813873D02*
X467952Y814165D01*
X468077Y814498D01*
X468285Y814706D01*
X468577Y814790D01*
X468868Y814706D01*
X469118Y814456D01*
X469243Y814081D01*
Y813665D01*
X469327Y813415D01*
X469535Y813206D01*
X469827Y813123D01*
X470118Y813248D01*
X470327Y813540D01*
X470410Y813873D01*
X470327Y814206D01*
X470118Y814498D01*
X469827Y814623D01*
X469535Y814540D01*
X469327Y814331D01*
X469243Y814081D01*
Y813665D01*
X469118Y813290D01*
X468868Y813040D01*
X468577Y812956D01*
X468285Y813040D01*
X468077Y813248D01*
X467952Y813581D01*
X467910Y813873D01*
G01X452071Y800928D02*
X454571D01*
Y801969D01*
X454446Y802303D01*
X454279Y802511D01*
X453946Y802594D01*
X453613Y802511D01*
X453404Y802261D01*
X453279Y801969D01*
Y800928D01*
G01Y801969D02*
X452071Y802594D01*
G01X452571Y803944D02*
X452279Y804194D01*
X452113Y804528D01*
X452071Y804903D01*
X452113Y805236D01*
X452321Y805569D01*
X452571Y805778D01*
X452821Y805819D01*
X453113Y805736D01*
X453321Y805444D01*
X453404Y805153D01*
Y804778D01*
G01Y805153D02*
X453529Y805403D01*
X453738Y805611D01*
X453988Y805694D01*
X454238Y805611D01*
X454446Y805403D01*
X454571Y805028D01*
X454529Y804653D01*
X454363Y804278D01*
G01X454154Y807169D02*
X454404Y807419D01*
X454529Y807711D01*
X454571Y808044D01*
X454488Y808461D01*
X454279Y808753D01*
X454029Y808836D01*
X453779Y808794D01*
X453571Y808628D01*
X453154Y807794D01*
X452863Y807419D01*
X452446Y807169D01*
X452071Y807086D01*
Y808836D01*
G01X454154Y810269D02*
X454404Y810519D01*
X454529Y810811D01*
X454571Y811144D01*
X454488Y811561D01*
X454279Y811853D01*
X454029Y811936D01*
X453779Y811894D01*
X453571Y811728D01*
X453154Y810894D01*
X452863Y810519D01*
X452446Y810269D01*
X452071Y810186D01*
Y811936D01*
G01X454154Y813369D02*
X454404Y813619D01*
X454529Y813911D01*
X454571Y814244D01*
X454488Y814661D01*
X454279Y814953D01*
X454029Y815036D01*
X453779Y814994D01*
X453571Y814828D01*
X453154Y813994D01*
X452863Y813619D01*
X452446Y813369D01*
X452071Y813286D01*
Y815036D01*
G01X442336Y800905D02*
X444836D01*
Y801946D01*
X444711Y802280D01*
X444544Y802488D01*
X444211Y802571D01*
X443878Y802488D01*
X443669Y802238D01*
X443544Y801946D01*
Y800905D01*
G01Y801946D02*
X442336Y802571D01*
G01X442836Y803921D02*
X442544Y804171D01*
X442378Y804505D01*
X442336Y804880D01*
X442378Y805213D01*
X442586Y805546D01*
X442836Y805755D01*
X443086Y805796D01*
X443378Y805713D01*
X443586Y805421D01*
X443669Y805130D01*
Y804755D01*
G01Y805130D02*
X443794Y805380D01*
X444003Y805588D01*
X444253Y805671D01*
X444503Y805588D01*
X444711Y805380D01*
X444836Y805005D01*
X444794Y804630D01*
X444628Y804255D01*
G01X444419Y807146D02*
X444669Y807396D01*
X444794Y807688D01*
X444836Y808021D01*
X444753Y808438D01*
X444544Y808730D01*
X444294Y808813D01*
X444044Y808771D01*
X443836Y808605D01*
X443419Y807771D01*
X443128Y807396D01*
X442711Y807146D01*
X442336Y807063D01*
Y808813D01*
G01X444419Y810246D02*
X444669Y810496D01*
X444794Y810788D01*
X444836Y811121D01*
X444753Y811538D01*
X444544Y811830D01*
X444294Y811913D01*
X444044Y811871D01*
X443836Y811705D01*
X443419Y810871D01*
X443128Y810496D01*
X442711Y810246D01*
X442336Y810163D01*
Y811913D01*
G01X442836Y813221D02*
X442544Y813471D01*
X442378Y813805D01*
X442336Y814180D01*
X442378Y814513D01*
X442586Y814846D01*
X442836Y815055D01*
X443086Y815096D01*
X443378Y815013D01*
X443586Y814721D01*
X443669Y814430D01*
Y814055D01*
G01Y814430D02*
X443794Y814680D01*
X444003Y814888D01*
X444253Y814971D01*
X444503Y814888D01*
X444711Y814680D01*
X444836Y814305D01*
X444794Y813930D01*
X444628Y813555D01*
G01X450340Y802855D02*
X450465Y802605D01*
X450548Y802313D01*
Y801980D01*
X450423Y801605D01*
X450215Y801313D01*
X449965Y801105D01*
X449548Y800938D01*
X449173Y800896D01*
X448798Y800980D01*
X448548Y801105D01*
X448298Y801355D01*
X448131Y801646D01*
X448048Y801938D01*
Y802230D01*
X448131Y802521D01*
X448256Y802771D01*
X448423Y802980D01*
G01X448048Y805038D02*
X448090Y805330D01*
X448215Y805663D01*
X448423Y805871D01*
X448715Y805955D01*
X449006Y805871D01*
X449256Y805621D01*
X449381Y805246D01*
Y804830D01*
X449465Y804580D01*
X449673Y804371D01*
X449965Y804288D01*
X450256Y804413D01*
X450465Y804705D01*
X450548Y805038D01*
X450465Y805371D01*
X450256Y805663D01*
X449965Y805788D01*
X449673Y805705D01*
X449465Y805496D01*
X449381Y805246D01*
Y804830D01*
X449256Y804455D01*
X449006Y804205D01*
X448715Y804121D01*
X448423Y804205D01*
X448215Y804413D01*
X448090Y804746D01*
X448048Y805038D01*
G01X450548Y808138D02*
X450465Y807805D01*
X450256Y807555D01*
X450006Y807388D01*
X449673Y807263D01*
X449298Y807221D01*
X448923Y807263D01*
X448590Y807388D01*
X448340Y807555D01*
X448131Y807805D01*
X448048Y808138D01*
X448131Y808471D01*
X448340Y808721D01*
X448590Y808888D01*
X448923Y809013D01*
X449298Y809055D01*
X449673Y809013D01*
X450006Y808888D01*
X450256Y808721D01*
X450465Y808471D01*
X450548Y808138D01*
G01X448340Y810530D02*
X448131Y810821D01*
X448048Y811155D01*
X448131Y811488D01*
X448381Y811780D01*
X448756Y811988D01*
X449131Y812071D01*
X449590D01*
X449965Y811988D01*
X450298Y811780D01*
X450465Y811530D01*
X450548Y811238D01*
X450465Y810905D01*
X450298Y810655D01*
X450048Y810488D01*
X449715Y810405D01*
X449423Y810488D01*
X449131Y810696D01*
X448965Y810946D01*
X448923Y811238D01*
X449006Y811571D01*
X449215Y811821D01*
X449590Y812071D01*
G01X448048Y814838D02*
X450548D01*
X448756Y813296D01*
Y815380D01*
G01X450539Y818648D02*
X453039D01*
Y819689D01*
X452914Y820023D01*
X452747Y820231D01*
X452414Y820314D01*
X452081Y820231D01*
X451872Y819981D01*
X451747Y819689D01*
Y818648D01*
G01Y819689D02*
X450539Y820314D01*
G01X450914Y821664D02*
X450706Y821914D01*
X450581Y822206D01*
X450539Y822581D01*
X450622Y822956D01*
X450789Y823248D01*
X451081Y823456D01*
X451414Y823498D01*
X451747Y823414D01*
X451956Y823206D01*
X452122Y822914D01*
X452164Y822623D01*
X452122Y822331D01*
X451956Y821956D01*
X453039Y822081D01*
Y823206D01*
G01X451039Y824764D02*
X450747Y825014D01*
X450581Y825348D01*
X450539Y825723D01*
X450581Y826056D01*
X450789Y826389D01*
X451039Y826598D01*
X451289Y826639D01*
X451581Y826556D01*
X451789Y826264D01*
X451872Y825973D01*
Y825598D01*
G01Y825973D02*
X451997Y826223D01*
X452206Y826431D01*
X452456Y826514D01*
X452706Y826431D01*
X452914Y826223D01*
X453039Y825848D01*
X452997Y825473D01*
X452831Y825098D01*
G01X450914Y827864D02*
X450706Y828114D01*
X450581Y828406D01*
X450539Y828781D01*
X450622Y829156D01*
X450789Y829448D01*
X451081Y829656D01*
X451414Y829698D01*
X451747Y829614D01*
X451956Y829406D01*
X452122Y829114D01*
X452164Y828823D01*
X452122Y828531D01*
X451956Y828156D01*
X453039Y828281D01*
Y829406D01*
G01X454567Y818665D02*
X457067D01*
Y819706D01*
X456942Y820040D01*
X456775Y820248D01*
X456442Y820331D01*
X456109Y820248D01*
X455900Y819998D01*
X455775Y819706D01*
Y818665D01*
G01Y819706D02*
X454567Y820331D01*
G01Y823098D02*
X457067D01*
X455275Y821556D01*
Y823640D01*
G01X454567Y825698D02*
X457067D01*
X456567Y825198D01*
G01X454567D02*
Y826198D01*
G01X455067Y827881D02*
X454775Y828131D01*
X454609Y828465D01*
X454567Y828840D01*
X454609Y829173D01*
X454817Y829506D01*
X455067Y829715D01*
X455317Y829756D01*
X455609Y829673D01*
X455817Y829381D01*
X455900Y829090D01*
Y828715D01*
G01Y829090D02*
X456025Y829340D01*
X456234Y829548D01*
X456484Y829631D01*
X456734Y829548D01*
X456942Y829340D01*
X457067Y828965D01*
X457025Y828590D01*
X456859Y828215D01*
G01X455067Y830981D02*
X454775Y831231D01*
X454609Y831565D01*
X454567Y831940D01*
X454609Y832273D01*
X454817Y832606D01*
X455067Y832815D01*
X455317Y832856D01*
X455609Y832773D01*
X455817Y832481D01*
X455900Y832190D01*
Y831815D01*
G01Y832190D02*
X456025Y832440D01*
X456234Y832648D01*
X456484Y832731D01*
X456734Y832648D01*
X456942Y832440D01*
X457067Y832065D01*
X457025Y831690D01*
X456859Y831315D01*
G01X467240Y818017D02*
X469740D01*
Y819058D01*
X469615Y819392D01*
X469448Y819600D01*
X469115Y819683D01*
X468782Y819600D01*
X468573Y819350D01*
X468448Y819058D01*
Y818017D01*
G01Y819058D02*
X467240Y819683D01*
G01Y822450D02*
X469740D01*
X467948Y820908D01*
Y822992D01*
G01X467240Y825050D02*
X469740D01*
X469240Y824550D01*
G01X467240D02*
Y825550D01*
G01X469323Y827358D02*
X469573Y827608D01*
X469698Y827900D01*
X469740Y828233D01*
X469657Y828650D01*
X469448Y828942D01*
X469198Y829025D01*
X468948Y828983D01*
X468740Y828817D01*
X468323Y827983D01*
X468032Y827608D01*
X467615Y827358D01*
X467240Y827275D01*
Y829025D01*
G01Y831250D02*
X467282Y831542D01*
X467407Y831875D01*
X467615Y832083D01*
X467907Y832167D01*
X468198Y832083D01*
X468448Y831833D01*
X468573Y831458D01*
Y831042D01*
X468657Y830792D01*
X468865Y830583D01*
X469157Y830500D01*
X469448Y830625D01*
X469657Y830917D01*
X469740Y831250D01*
X469657Y831583D01*
X469448Y831875D01*
X469157Y832000D01*
X468865Y831917D01*
X468657Y831708D01*
X468573Y831458D01*
Y831042D01*
X468448Y830667D01*
X468198Y830417D01*
X467907Y830333D01*
X467615Y830417D01*
X467407Y830625D01*
X467282Y830958D01*
X467240Y831250D01*
G01X463140Y818017D02*
X465640D01*
Y819058D01*
X465515Y819392D01*
X465348Y819600D01*
X465015Y819683D01*
X464682Y819600D01*
X464473Y819350D01*
X464348Y819058D01*
Y818017D01*
G01Y819058D02*
X463140Y819683D01*
G01Y822450D02*
X465640D01*
X463848Y820908D01*
Y822992D01*
G01X463140Y825050D02*
X465640D01*
X465140Y824550D01*
G01X463140D02*
Y825550D01*
G01X465223Y827358D02*
X465473Y827608D01*
X465598Y827900D01*
X465640Y828233D01*
X465557Y828650D01*
X465348Y828942D01*
X465098Y829025D01*
X464848Y828983D01*
X464640Y828817D01*
X464223Y827983D01*
X463932Y827608D01*
X463515Y827358D01*
X463140Y827275D01*
Y829025D01*
G01Y831167D02*
X463682Y831250D01*
X464140Y831375D01*
X464557Y831542D01*
X465015Y831750D01*
X465640Y832083D01*
Y830417D01*
G01X501589Y114738D02*
X501714Y114488D01*
X501797Y114196D01*
Y113863D01*
X501672Y113488D01*
X501464Y113196D01*
X501214Y112988D01*
X500797Y112821D01*
X500422Y112779D01*
X500047Y112863D01*
X499797Y112988D01*
X499547Y113238D01*
X499380Y113529D01*
X499297Y113821D01*
Y114113D01*
X499380Y114404D01*
X499505Y114654D01*
X499672Y114863D01*
G01X501380Y116129D02*
X501630Y116379D01*
X501755Y116671D01*
X501797Y117004D01*
X501714Y117421D01*
X501505Y117713D01*
X501255Y117796D01*
X501005Y117754D01*
X500797Y117588D01*
X500380Y116754D01*
X500089Y116379D01*
X499672Y116129D01*
X499297Y116046D01*
Y117796D01*
G01X501380Y119229D02*
X501630Y119479D01*
X501755Y119771D01*
X501797Y120104D01*
X501714Y120521D01*
X501505Y120813D01*
X501255Y120896D01*
X501005Y120854D01*
X500797Y120688D01*
X500380Y119854D01*
X500089Y119479D01*
X499672Y119229D01*
X499297Y119146D01*
Y120896D01*
G01Y123121D02*
X501797D01*
X501297Y122621D01*
G01X499297D02*
Y123621D01*
G01X505084Y114678D02*
X505209Y114428D01*
X505292Y114136D01*
Y113803D01*
X505167Y113428D01*
X504959Y113136D01*
X504709Y112928D01*
X504292Y112761D01*
X503917Y112719D01*
X503542Y112803D01*
X503292Y112928D01*
X503042Y113178D01*
X502875Y113469D01*
X502792Y113761D01*
Y114053D01*
X502875Y114344D01*
X503000Y114594D01*
X503167Y114803D01*
G01X504875Y116069D02*
X505125Y116319D01*
X505250Y116611D01*
X505292Y116944D01*
X505209Y117361D01*
X505000Y117653D01*
X504750Y117736D01*
X504500Y117694D01*
X504292Y117528D01*
X503875Y116694D01*
X503584Y116319D01*
X503167Y116069D01*
X502792Y115986D01*
Y117736D01*
G01X504875Y119169D02*
X505125Y119419D01*
X505250Y119711D01*
X505292Y120044D01*
X505209Y120461D01*
X505000Y120753D01*
X504750Y120836D01*
X504500Y120794D01*
X504292Y120628D01*
X503875Y119794D01*
X503584Y119419D01*
X503167Y119169D01*
X502792Y119086D01*
Y120836D01*
G01X505292Y123061D02*
X505209Y122728D01*
X505000Y122478D01*
X504750Y122311D01*
X504417Y122186D01*
X504042Y122144D01*
X503667Y122186D01*
X503334Y122311D01*
X503084Y122478D01*
X502875Y122728D01*
X502792Y123061D01*
X502875Y123394D01*
X503084Y123644D01*
X503334Y123811D01*
X503667Y123936D01*
X504042Y123978D01*
X504417Y123936D01*
X504750Y123811D01*
X505000Y123644D01*
X505209Y123394D01*
X505292Y123061D01*
G01X493737Y115070D02*
X493862Y114820D01*
X493945Y114528D01*
Y114195D01*
X493820Y113820D01*
X493612Y113528D01*
X493362Y113320D01*
X492945Y113153D01*
X492570Y113111D01*
X492195Y113195D01*
X491945Y113320D01*
X491695Y113570D01*
X491528Y113861D01*
X491445Y114153D01*
Y114445D01*
X491528Y114736D01*
X491653Y114986D01*
X491820Y115195D01*
G01X491445Y117253D02*
X493945D01*
X493445Y116753D01*
G01X491445D02*
Y117753D01*
G01X491945Y119436D02*
X491653Y119686D01*
X491487Y120020D01*
X491445Y120395D01*
X491487Y120728D01*
X491695Y121061D01*
X491945Y121270D01*
X492195Y121311D01*
X492487Y121228D01*
X492695Y120936D01*
X492778Y120645D01*
Y120270D01*
G01Y120645D02*
X492903Y120895D01*
X493112Y121103D01*
X493362Y121186D01*
X493612Y121103D01*
X493820Y120895D01*
X493945Y120520D01*
X493903Y120145D01*
X493737Y119770D01*
G01X493945Y123453D02*
X493862Y123120D01*
X493653Y122870D01*
X493403Y122703D01*
X493070Y122578D01*
X492695Y122536D01*
X492320Y122578D01*
X491987Y122703D01*
X491737Y122870D01*
X491528Y123120D01*
X491445Y123453D01*
X491528Y123786D01*
X491737Y124036D01*
X491987Y124203D01*
X492320Y124328D01*
X492695Y124370D01*
X493070Y124328D01*
X493403Y124203D01*
X493653Y124036D01*
X493862Y123786D01*
X493945Y123453D01*
G01X490172Y115050D02*
X490297Y114800D01*
X490380Y114508D01*
Y114175D01*
X490255Y113800D01*
X490047Y113508D01*
X489797Y113300D01*
X489380Y113133D01*
X489005Y113091D01*
X488630Y113175D01*
X488380Y113300D01*
X488130Y113550D01*
X487963Y113841D01*
X487880Y114133D01*
Y114425D01*
X487963Y114716D01*
X488088Y114966D01*
X488255Y115175D01*
G01X487880Y117233D02*
X490380D01*
X489880Y116733D01*
G01X487880D02*
Y117733D01*
G01X489963Y119541D02*
X490213Y119791D01*
X490338Y120083D01*
X490380Y120416D01*
X490297Y120833D01*
X490088Y121125D01*
X489838Y121208D01*
X489588Y121166D01*
X489380Y121000D01*
X488963Y120166D01*
X488672Y119791D01*
X488255Y119541D01*
X487880Y119458D01*
Y121208D01*
G01X488172Y122725D02*
X487963Y123016D01*
X487880Y123350D01*
X487963Y123683D01*
X488213Y123975D01*
X488588Y124183D01*
X488963Y124266D01*
X489422D01*
X489797Y124183D01*
X490130Y123975D01*
X490297Y123725D01*
X490380Y123433D01*
X490297Y123100D01*
X490130Y122850D01*
X489880Y122683D01*
X489547Y122600D01*
X489255Y122683D01*
X488963Y122891D01*
X488797Y123141D01*
X488755Y123433D01*
X488838Y123766D01*
X489047Y124016D01*
X489422Y124266D01*
G01X483361Y373217D02*
X485861D01*
Y374258D01*
X485736Y374592D01*
X485569Y374800D01*
X485236Y374883D01*
X484903Y374800D01*
X484694Y374550D01*
X484569Y374258D01*
Y373217D01*
G01Y374258D02*
X483361Y374883D01*
G01Y377650D02*
X485861D01*
X484069Y376108D01*
Y378192D01*
G01X483861Y379333D02*
X483569Y379583D01*
X483403Y379917D01*
X483361Y380292D01*
X483403Y380625D01*
X483611Y380958D01*
X483861Y381167D01*
X484111Y381208D01*
X484403Y381125D01*
X484611Y380833D01*
X484694Y380542D01*
Y380167D01*
G01Y380542D02*
X484819Y380792D01*
X485028Y381000D01*
X485278Y381083D01*
X485528Y381000D01*
X485736Y380792D01*
X485861Y380417D01*
X485819Y380042D01*
X485653Y379667D01*
G01X485444Y382558D02*
X485694Y382808D01*
X485819Y383100D01*
X485861Y383433D01*
X485778Y383850D01*
X485569Y384142D01*
X485319Y384225D01*
X485069Y384183D01*
X484861Y384017D01*
X484444Y383183D01*
X484153Y382808D01*
X483736Y382558D01*
X483361Y382475D01*
Y384225D01*
G01X478200Y375000D02*
X474200D01*
Y382400D01*
G01X487361Y373217D02*
X489861D01*
Y374258D01*
X489736Y374592D01*
X489569Y374800D01*
X489236Y374883D01*
X488903Y374800D01*
X488694Y374550D01*
X488569Y374258D01*
Y373217D01*
G01Y374258D02*
X487361Y374883D01*
G01Y377650D02*
X489861D01*
X488069Y376108D01*
Y378192D01*
G01X487861Y379333D02*
X487569Y379583D01*
X487403Y379917D01*
X487361Y380292D01*
X487403Y380625D01*
X487611Y380958D01*
X487861Y381167D01*
X488111Y381208D01*
X488403Y381125D01*
X488611Y380833D01*
X488694Y380542D01*
Y380167D01*
G01Y380542D02*
X488819Y380792D01*
X489028Y381000D01*
X489278Y381083D01*
X489528Y381000D01*
X489736Y380792D01*
X489861Y380417D01*
X489819Y380042D01*
X489653Y379667D01*
G01X487361Y383350D02*
X489861D01*
X489361Y382850D01*
G01X487361D02*
Y383850D01*
G01X482200Y375000D02*
X478200D01*
Y382400D01*
G01X498176Y748288D02*
X500676D01*
Y749329D01*
X500551Y749663D01*
X500384Y749871D01*
X500051Y749954D01*
X499718Y749871D01*
X499509Y749621D01*
X499384Y749329D01*
Y748288D01*
G01Y749329D02*
X498176Y749954D01*
G01X498551Y751304D02*
X498343Y751554D01*
X498218Y751846D01*
X498176Y752221D01*
X498259Y752596D01*
X498426Y752888D01*
X498718Y753096D01*
X499051Y753138D01*
X499384Y753054D01*
X499593Y752846D01*
X499759Y752554D01*
X499801Y752263D01*
X499759Y751971D01*
X499593Y751596D01*
X500676Y751721D01*
Y752846D01*
G01X498676Y754404D02*
X498384Y754654D01*
X498218Y754988D01*
X498176Y755363D01*
X498218Y755696D01*
X498426Y756029D01*
X498676Y756238D01*
X498926Y756279D01*
X499218Y756196D01*
X499426Y755904D01*
X499509Y755613D01*
Y755238D01*
G01Y755613D02*
X499634Y755863D01*
X499843Y756071D01*
X500093Y756154D01*
X500343Y756071D01*
X500551Y755863D01*
X500676Y755488D01*
X500634Y755113D01*
X500468Y754738D01*
G01X499218Y757629D02*
X499509Y757921D01*
X499676Y758171D01*
X499759Y758504D01*
X499676Y758796D01*
X499509Y759004D01*
X499259Y759171D01*
X498968Y759213D01*
X498718Y759171D01*
X498468Y759004D01*
X498259Y758754D01*
X498176Y758463D01*
X498259Y758129D01*
X498509Y757838D01*
X498884Y757671D01*
X499301Y757629D01*
X499843Y757713D01*
X500134Y757838D01*
X500426Y758046D01*
X500634Y758338D01*
X500676Y758629D01*
X500593Y758921D01*
X500384Y759129D01*
G01X501891Y748288D02*
X504391D01*
Y749329D01*
X504266Y749663D01*
X504099Y749871D01*
X503766Y749954D01*
X503433Y749871D01*
X503224Y749621D01*
X503099Y749329D01*
Y748288D01*
G01Y749329D02*
X501891Y749954D01*
G01X502266Y751304D02*
X502058Y751554D01*
X501933Y751846D01*
X501891Y752221D01*
X501974Y752596D01*
X502141Y752888D01*
X502433Y753096D01*
X502766Y753138D01*
X503099Y753054D01*
X503308Y752846D01*
X503474Y752554D01*
X503516Y752263D01*
X503474Y751971D01*
X503308Y751596D01*
X504391Y751721D01*
Y752846D01*
G01X503974Y754529D02*
X504224Y754779D01*
X504349Y755071D01*
X504391Y755404D01*
X504308Y755821D01*
X504099Y756113D01*
X503849Y756196D01*
X503599Y756154D01*
X503391Y755988D01*
X502974Y755154D01*
X502683Y754779D01*
X502266Y754529D01*
X501891Y754446D01*
Y756196D01*
G01X502266Y757504D02*
X502058Y757754D01*
X501933Y758046D01*
X501891Y758421D01*
X501974Y758796D01*
X502141Y759088D01*
X502433Y759296D01*
X502766Y759338D01*
X503099Y759254D01*
X503308Y759046D01*
X503474Y758754D01*
X503516Y758463D01*
X503474Y758171D01*
X503308Y757796D01*
X504391Y757921D01*
Y759046D01*
G01X489900Y790100D02*
X493900D01*
Y782700D01*
G01X489906Y769698D02*
X485906D01*
Y777098D01*
G01X493906Y769698D02*
X489906D01*
Y777098D01*
G01X493906D02*
X497906D01*
Y769698D01*
G01Y777098D02*
X501906D01*
Y769698D01*
G01X494222Y791769D02*
Y805169D01*
G01X484222Y791769D02*
X494222D01*
G01X484222Y805169D02*
Y791769D01*
G01X494222Y805169D02*
X484222D01*
G01X476158Y787016D02*
X474366D01*
X473991Y787183D01*
X473741Y787516D01*
X473658Y787933D01*
X473741Y788350D01*
X473991Y788683D01*
X474366Y788850D01*
X476158D01*
G01X474700Y790241D02*
X474991Y790533D01*
X475158Y790783D01*
X475241Y791116D01*
X475158Y791408D01*
X474991Y791616D01*
X474741Y791783D01*
X474450Y791825D01*
X474200Y791783D01*
X473950Y791616D01*
X473741Y791366D01*
X473658Y791075D01*
X473741Y790741D01*
X473991Y790450D01*
X474366Y790283D01*
X474783Y790241D01*
X475325Y790325D01*
X475616Y790450D01*
X475908Y790658D01*
X476116Y790950D01*
X476158Y791241D01*
X476075Y791533D01*
X475866Y791741D01*
G01X474700Y793341D02*
X474991Y793633D01*
X475158Y793883D01*
X475241Y794216D01*
X475158Y794508D01*
X474991Y794716D01*
X474741Y794883D01*
X474450Y794925D01*
X474200Y794883D01*
X473950Y794716D01*
X473741Y794466D01*
X473658Y794175D01*
X473741Y793841D01*
X473991Y793550D01*
X474366Y793383D01*
X474783Y793341D01*
X475325Y793425D01*
X475616Y793550D01*
X475908Y793758D01*
X476116Y794050D01*
X476158Y794341D01*
X476075Y794633D01*
X475866Y794841D01*
G01X501000Y791800D02*
X511000D01*
G01X501000Y805200D02*
Y791800D01*
G01X511000Y805200D02*
X501000D01*
G01X496000Y806200D02*
X500000D01*
Y798800D01*
G01X478800Y806200D02*
X482800D01*
Y798800D01*
G01X500678Y814131D02*
X504678D01*
Y806731D01*
G01X490500Y813700D02*
X494500D01*
Y806300D01*
G01X480000Y813700D02*
X484000D01*
Y806300D01*
G01X471548Y800759D02*
X474048D01*
Y801800D01*
X473923Y802134D01*
X473756Y802342D01*
X473423Y802425D01*
X473090Y802342D01*
X472881Y802092D01*
X472756Y801800D01*
Y800759D01*
G01Y801800D02*
X471548Y802425D01*
G01X472048Y803775D02*
X471756Y804025D01*
X471590Y804359D01*
X471548Y804734D01*
X471590Y805067D01*
X471798Y805400D01*
X472048Y805609D01*
X472298Y805650D01*
X472590Y805567D01*
X472798Y805275D01*
X472881Y804984D01*
Y804609D01*
G01Y804984D02*
X473006Y805234D01*
X473215Y805442D01*
X473465Y805525D01*
X473715Y805442D01*
X473923Y805234D01*
X474048Y804859D01*
X474006Y804484D01*
X473840Y804109D01*
G01X473631Y807000D02*
X473881Y807250D01*
X474006Y807542D01*
X474048Y807875D01*
X473965Y808292D01*
X473756Y808584D01*
X473506Y808667D01*
X473256Y808625D01*
X473048Y808459D01*
X472631Y807625D01*
X472340Y807250D01*
X471923Y807000D01*
X471548Y806917D01*
Y808667D01*
G01X474048Y810892D02*
X473965Y810559D01*
X473756Y810309D01*
X473506Y810142D01*
X473173Y810017D01*
X472798Y809975D01*
X472423Y810017D01*
X472090Y810142D01*
X471840Y810309D01*
X471631Y810559D01*
X471548Y810892D01*
X471631Y811225D01*
X471840Y811475D01*
X472090Y811642D01*
X472423Y811767D01*
X472798Y811809D01*
X473173Y811767D01*
X473506Y811642D01*
X473756Y811475D01*
X473965Y811225D01*
X474048Y810892D01*
G01X471548Y813909D02*
X472090Y813992D01*
X472548Y814117D01*
X472965Y814284D01*
X473423Y814492D01*
X474048Y814825D01*
Y813159D01*
G01X493878Y826131D02*
X497878D01*
Y818731D01*
G01X502406Y818698D02*
X498406D01*
Y826098D01*
G01X471467Y818065D02*
X473967D01*
Y819106D01*
X473842Y819440D01*
X473675Y819648D01*
X473342Y819731D01*
X473009Y819648D01*
X472800Y819398D01*
X472675Y819106D01*
Y818065D01*
G01Y819106D02*
X471467Y819731D01*
G01Y822498D02*
X473967D01*
X472175Y820956D01*
Y823040D01*
G01X471467Y825098D02*
X473967D01*
X473467Y824598D01*
G01X471467D02*
Y825598D01*
G01X473550Y827406D02*
X473800Y827656D01*
X473925Y827948D01*
X473967Y828281D01*
X473884Y828698D01*
X473675Y828990D01*
X473425Y829073D01*
X473175Y829031D01*
X472967Y828865D01*
X472550Y828031D01*
X472259Y827656D01*
X471842Y827406D01*
X471467Y827323D01*
Y829073D01*
G01X473550Y830506D02*
X473800Y830756D01*
X473925Y831048D01*
X473967Y831381D01*
X473884Y831798D01*
X473675Y832090D01*
X473425Y832173D01*
X473175Y832131D01*
X472967Y831965D01*
X472550Y831131D01*
X472259Y830756D01*
X471842Y830506D01*
X471467Y830423D01*
Y832173D01*
G01X532971Y17000D02*
X537138Y7000D01*
X541305Y17000D01*
G01X539805Y13500D02*
X534471D01*
G01X519820Y135770D02*
X523820D01*
Y128370D01*
G01X529320Y119337D02*
X531820D01*
Y120378D01*
X531695Y120712D01*
X531528Y120920D01*
X531195Y121003D01*
X530862Y120920D01*
X530653Y120670D01*
X530528Y120378D01*
Y119337D01*
G01Y120378D02*
X529320Y121003D01*
G01X531403Y122478D02*
X531653Y122728D01*
X531778Y123020D01*
X531820Y123353D01*
X531737Y123770D01*
X531528Y124062D01*
X531278Y124145D01*
X531028Y124103D01*
X530820Y123937D01*
X530403Y123103D01*
X530112Y122728D01*
X529695Y122478D01*
X529320Y122395D01*
Y124145D01*
G01X529612Y125662D02*
X529403Y125953D01*
X529320Y126287D01*
X529403Y126620D01*
X529653Y126912D01*
X530028Y127120D01*
X530403Y127203D01*
X530862D01*
X531237Y127120D01*
X531570Y126912D01*
X531737Y126662D01*
X531820Y126370D01*
X531737Y126037D01*
X531570Y125787D01*
X531320Y125620D01*
X530987Y125537D01*
X530695Y125620D01*
X530403Y125828D01*
X530237Y126078D01*
X530195Y126370D01*
X530278Y126703D01*
X530487Y126953D01*
X530862Y127203D01*
G01X531403Y128678D02*
X531653Y128928D01*
X531778Y129220D01*
X531820Y129553D01*
X531737Y129970D01*
X531528Y130262D01*
X531278Y130345D01*
X531028Y130303D01*
X530820Y130137D01*
X530403Y129303D01*
X530112Y128928D01*
X529695Y128678D01*
X529320Y128595D01*
Y130345D01*
G01X529695Y131653D02*
X529487Y131903D01*
X529362Y132195D01*
X529320Y132570D01*
X529403Y132945D01*
X529570Y133237D01*
X529862Y133445D01*
X530195Y133487D01*
X530528Y133403D01*
X530737Y133195D01*
X530903Y132903D01*
X530945Y132612D01*
X530903Y132320D01*
X530737Y131945D01*
X531820Y132070D01*
Y133195D01*
G01X511820Y135770D02*
X515820D01*
Y128370D01*
G01X523820Y135770D02*
X527820D01*
Y128370D01*
G01X533320Y119337D02*
X535820D01*
Y120378D01*
X535695Y120712D01*
X535528Y120920D01*
X535195Y121003D01*
X534862Y120920D01*
X534653Y120670D01*
X534528Y120378D01*
Y119337D01*
G01Y120378D02*
X533320Y121003D01*
G01X535403Y122478D02*
X535653Y122728D01*
X535778Y123020D01*
X535820Y123353D01*
X535737Y123770D01*
X535528Y124062D01*
X535278Y124145D01*
X535028Y124103D01*
X534820Y123937D01*
X534403Y123103D01*
X534112Y122728D01*
X533695Y122478D01*
X533320Y122395D01*
Y124145D01*
G01X533612Y125662D02*
X533403Y125953D01*
X533320Y126287D01*
X533403Y126620D01*
X533653Y126912D01*
X534028Y127120D01*
X534403Y127203D01*
X534862D01*
X535237Y127120D01*
X535570Y126912D01*
X535737Y126662D01*
X535820Y126370D01*
X535737Y126037D01*
X535570Y125787D01*
X535320Y125620D01*
X534987Y125537D01*
X534695Y125620D01*
X534403Y125828D01*
X534237Y126078D01*
X534195Y126370D01*
X534278Y126703D01*
X534487Y126953D01*
X534862Y127203D01*
G01X533320Y129470D02*
X535820D01*
X535320Y128970D01*
G01X533320D02*
Y129970D01*
G01Y132487D02*
X533862Y132570D01*
X534320Y132695D01*
X534737Y132862D01*
X535195Y133070D01*
X535820Y133403D01*
Y131737D01*
G01X515820Y135770D02*
X519820D01*
Y128370D01*
G01X530813Y748055D02*
X533313D01*
Y749096D01*
X533188Y749430D01*
X533021Y749638D01*
X532688Y749721D01*
X532355Y749638D01*
X532146Y749388D01*
X532021Y749096D01*
Y748055D01*
G01Y749096D02*
X530813Y749721D01*
G01Y752488D02*
X533313D01*
X531521Y750946D01*
Y753030D01*
G01X530813Y755088D02*
X533313D01*
X532813Y754588D01*
G01X530813D02*
Y755588D01*
G01X531313Y757271D02*
X531021Y757521D01*
X530855Y757855D01*
X530813Y758230D01*
X530855Y758563D01*
X531063Y758896D01*
X531313Y759105D01*
X531563Y759146D01*
X531855Y759063D01*
X532063Y758771D01*
X532146Y758480D01*
Y758105D01*
G01Y758480D02*
X532271Y758730D01*
X532480Y758938D01*
X532730Y759021D01*
X532980Y758938D01*
X533188Y758730D01*
X533313Y758355D01*
X533271Y757980D01*
X533105Y757605D01*
G01X533313Y761288D02*
X533230Y760955D01*
X533021Y760705D01*
X532771Y760538D01*
X532438Y760413D01*
X532063Y760371D01*
X531688Y760413D01*
X531355Y760538D01*
X531105Y760705D01*
X530896Y760955D01*
X530813Y761288D01*
X530896Y761621D01*
X531105Y761871D01*
X531355Y762038D01*
X531688Y762163D01*
X532063Y762205D01*
X532438Y762163D01*
X532771Y762038D01*
X533021Y761871D01*
X533230Y761621D01*
X533313Y761288D01*
G01X505961Y748507D02*
X508461D01*
Y749548D01*
X508336Y749882D01*
X508169Y750090D01*
X507836Y750173D01*
X507503Y750090D01*
X507294Y749840D01*
X507169Y749548D01*
Y748507D01*
G01Y749548D02*
X505961Y750173D01*
G01Y752940D02*
X508461D01*
X506669Y751398D01*
Y753482D01*
G01X505961Y755540D02*
X508461D01*
X507961Y755040D01*
G01X505961D02*
Y756040D01*
G01X508044Y757848D02*
X508294Y758098D01*
X508419Y758390D01*
X508461Y758723D01*
X508378Y759140D01*
X508169Y759432D01*
X507919Y759515D01*
X507669Y759473D01*
X507461Y759307D01*
X507044Y758473D01*
X506753Y758098D01*
X506336Y757848D01*
X505961Y757765D01*
Y759515D01*
G01X506253Y761032D02*
X506044Y761323D01*
X505961Y761657D01*
X506044Y761990D01*
X506294Y762282D01*
X506669Y762490D01*
X507044Y762573D01*
X507503D01*
X507878Y762490D01*
X508211Y762282D01*
X508378Y762032D01*
X508461Y761740D01*
X508378Y761407D01*
X508211Y761157D01*
X507961Y760990D01*
X507628Y760907D01*
X507336Y760990D01*
X507044Y761198D01*
X506878Y761448D01*
X506836Y761740D01*
X506919Y762073D01*
X507128Y762323D01*
X507503Y762573D01*
G01X526478Y748232D02*
X528978D01*
Y749273D01*
X528853Y749607D01*
X528686Y749815D01*
X528353Y749898D01*
X528020Y749815D01*
X527811Y749565D01*
X527686Y749273D01*
Y748232D01*
G01Y749273D02*
X526478Y749898D01*
G01Y752665D02*
X528978D01*
X527186Y751123D01*
Y753207D01*
G01X526478Y755265D02*
X528978D01*
X528478Y754765D01*
G01X526478D02*
Y755765D01*
G01X528561Y757573D02*
X528811Y757823D01*
X528936Y758115D01*
X528978Y758448D01*
X528895Y758865D01*
X528686Y759157D01*
X528436Y759240D01*
X528186Y759198D01*
X527978Y759032D01*
X527561Y758198D01*
X527270Y757823D01*
X526853Y757573D01*
X526478Y757490D01*
Y759240D01*
G01X527520Y760673D02*
X527811Y760965D01*
X527978Y761215D01*
X528061Y761548D01*
X527978Y761840D01*
X527811Y762048D01*
X527561Y762215D01*
X527270Y762257D01*
X527020Y762215D01*
X526770Y762048D01*
X526561Y761798D01*
X526478Y761507D01*
X526561Y761173D01*
X526811Y760882D01*
X527186Y760715D01*
X527603Y760673D01*
X528145Y760757D01*
X528436Y760882D01*
X528728Y761090D01*
X528936Y761382D01*
X528978Y761673D01*
X528895Y761965D01*
X528686Y762173D01*
G01X521789Y748321D02*
X524289D01*
Y749362D01*
X524164Y749696D01*
X523997Y749904D01*
X523664Y749987D01*
X523331Y749904D01*
X523122Y749654D01*
X522997Y749362D01*
Y748321D01*
G01Y749362D02*
X521789Y749987D01*
G01Y752754D02*
X524289D01*
X522497Y751212D01*
Y753296D01*
G01X521789Y755354D02*
X524289D01*
X523789Y754854D01*
G01X521789D02*
Y755854D01*
G01X523872Y757662D02*
X524122Y757912D01*
X524247Y758204D01*
X524289Y758537D01*
X524206Y758954D01*
X523997Y759246D01*
X523747Y759329D01*
X523497Y759287D01*
X523289Y759121D01*
X522872Y758287D01*
X522581Y757912D01*
X522164Y757662D01*
X521789Y757579D01*
Y759329D01*
G01X522164Y760637D02*
X521956Y760887D01*
X521831Y761179D01*
X521789Y761554D01*
X521872Y761929D01*
X522039Y762221D01*
X522331Y762429D01*
X522664Y762471D01*
X522997Y762387D01*
X523206Y762179D01*
X523372Y761887D01*
X523414Y761596D01*
X523372Y761304D01*
X523206Y760929D01*
X524289Y761054D01*
Y762179D01*
G01X517727Y748331D02*
X520227D01*
Y749372D01*
X520102Y749706D01*
X519935Y749914D01*
X519602Y749997D01*
X519269Y749914D01*
X519060Y749664D01*
X518935Y749372D01*
Y748331D01*
G01Y749372D02*
X517727Y749997D01*
G01Y752764D02*
X520227D01*
X518435Y751222D01*
Y753306D01*
G01X517727Y755364D02*
X520227D01*
X519727Y754864D01*
G01X517727D02*
Y755864D01*
G01X519810Y757672D02*
X520060Y757922D01*
X520185Y758214D01*
X520227Y758547D01*
X520144Y758964D01*
X519935Y759256D01*
X519685Y759339D01*
X519435Y759297D01*
X519227Y759131D01*
X518810Y758297D01*
X518519Y757922D01*
X518102Y757672D01*
X517727Y757589D01*
Y759339D01*
G01X518227Y760647D02*
X517935Y760897D01*
X517769Y761231D01*
X517727Y761606D01*
X517769Y761939D01*
X517977Y762272D01*
X518227Y762481D01*
X518477Y762522D01*
X518769Y762439D01*
X518977Y762147D01*
X519060Y761856D01*
Y761481D01*
G01Y761856D02*
X519185Y762106D01*
X519394Y762314D01*
X519644Y762397D01*
X519894Y762314D01*
X520102Y762106D01*
X520227Y761731D01*
X520185Y761356D01*
X520019Y760981D01*
G01X509677Y748419D02*
X512177D01*
Y749460D01*
X512052Y749794D01*
X511885Y750002D01*
X511552Y750085D01*
X511219Y750002D01*
X511010Y749752D01*
X510885Y749460D01*
Y748419D01*
G01Y749460D02*
X509677Y750085D01*
G01Y752852D02*
X512177D01*
X510385Y751310D01*
Y753394D01*
G01X509677Y755452D02*
X512177D01*
X511677Y754952D01*
G01X509677D02*
Y755952D01*
G01X511760Y757760D02*
X512010Y758010D01*
X512135Y758302D01*
X512177Y758635D01*
X512094Y759052D01*
X511885Y759344D01*
X511635Y759427D01*
X511385Y759385D01*
X511177Y759219D01*
X510760Y758385D01*
X510469Y758010D01*
X510052Y757760D01*
X509677Y757677D01*
Y759427D01*
G01X512177Y761652D02*
X512094Y761319D01*
X511885Y761069D01*
X511635Y760902D01*
X511302Y760777D01*
X510927Y760735D01*
X510552Y760777D01*
X510219Y760902D01*
X509969Y761069D01*
X509760Y761319D01*
X509677Y761652D01*
X509760Y761985D01*
X509969Y762235D01*
X510219Y762402D01*
X510552Y762527D01*
X510927Y762569D01*
X511302Y762527D01*
X511635Y762402D01*
X511885Y762235D01*
X512094Y761985D01*
X512177Y761652D01*
G01X513746Y748551D02*
X516246D01*
Y749592D01*
X516121Y749926D01*
X515954Y750134D01*
X515621Y750217D01*
X515288Y750134D01*
X515079Y749884D01*
X514954Y749592D01*
Y748551D01*
G01Y749592D02*
X513746Y750217D01*
G01X514038Y751776D02*
X513829Y752067D01*
X513746Y752401D01*
X513829Y752734D01*
X514079Y753026D01*
X514454Y753234D01*
X514829Y753317D01*
X515288D01*
X515663Y753234D01*
X515996Y753026D01*
X516163Y752776D01*
X516246Y752484D01*
X516163Y752151D01*
X515996Y751901D01*
X515746Y751734D01*
X515413Y751651D01*
X515121Y751734D01*
X514829Y751942D01*
X514663Y752192D01*
X514621Y752484D01*
X514704Y752817D01*
X514913Y753067D01*
X515288Y753317D01*
G01X516246Y755584D02*
X516163Y755251D01*
X515954Y755001D01*
X515704Y754834D01*
X515371Y754709D01*
X514996Y754667D01*
X514621Y754709D01*
X514288Y754834D01*
X514038Y755001D01*
X513829Y755251D01*
X513746Y755584D01*
X513829Y755917D01*
X514038Y756167D01*
X514288Y756334D01*
X514621Y756459D01*
X514996Y756501D01*
X515371Y756459D01*
X515704Y756334D01*
X515954Y756167D01*
X516163Y755917D01*
X516246Y755584D01*
G01X514246Y757767D02*
X513954Y758017D01*
X513788Y758351D01*
X513746Y758726D01*
X513788Y759059D01*
X513996Y759392D01*
X514246Y759601D01*
X514496Y759642D01*
X514788Y759559D01*
X514996Y759267D01*
X515079Y758976D01*
Y758601D01*
G01Y758976D02*
X515204Y759226D01*
X515413Y759434D01*
X515663Y759517D01*
X515913Y759434D01*
X516121Y759226D01*
X516246Y758851D01*
X516204Y758476D01*
X516038Y758101D01*
G01X516246Y761784D02*
X516163Y761451D01*
X515954Y761201D01*
X515704Y761034D01*
X515371Y760909D01*
X514996Y760867D01*
X514621Y760909D01*
X514288Y761034D01*
X514038Y761201D01*
X513829Y761451D01*
X513746Y761784D01*
X513829Y762117D01*
X514038Y762367D01*
X514288Y762534D01*
X514621Y762659D01*
X514996Y762701D01*
X515371Y762659D01*
X515704Y762534D01*
X515954Y762367D01*
X516163Y762117D01*
X516246Y761784D01*
G01X525000Y776900D02*
X529000D01*
Y769500D01*
G01X519900Y776800D02*
X523900D01*
Y769400D01*
G01X515800Y776900D02*
X519800D01*
Y769500D01*
G01X511700Y776900D02*
X515700D01*
Y769500D01*
G01X507600Y776900D02*
X511600D01*
Y769500D01*
G01X533000Y791800D02*
X543000D01*
G01X533000Y805200D02*
Y791800D01*
G01X543000Y805200D02*
X533000D01*
G01X527000Y791800D02*
Y805200D01*
G01X517000Y791800D02*
X527000D01*
G01X517000Y805200D02*
Y791800D01*
G01X527000Y805200D02*
X517000D01*
G01X511000Y791800D02*
Y805200D01*
G01X512000Y801200D02*
X516000D01*
Y793800D01*
G01X528000Y801200D02*
X532000D01*
Y793800D01*
G01X504678Y814131D02*
X508678D01*
Y806731D01*
G01X512400Y790700D02*
Y786700D01*
X505000D01*
G01X518178Y814131D02*
X522178D01*
Y806731D01*
G01X522678Y790131D02*
X526678D01*
Y782731D01*
G01X532678Y814131D02*
X536678D01*
Y806731D01*
G01X522178Y814131D02*
X526178D01*
Y806731D01*
G01X514679Y818650D02*
X510679D01*
Y826050D01*
G01X510579Y818650D02*
X506579D01*
Y826050D01*
G01X518906Y818698D02*
X514906D01*
Y826098D01*
G01X535067Y820265D02*
X537567D01*
Y821306D01*
X537442Y821640D01*
X537275Y821848D01*
X536942Y821931D01*
X536609Y821848D01*
X536400Y821598D01*
X536275Y821306D01*
Y820265D01*
G01Y821306D02*
X535067Y821931D01*
G01Y824698D02*
X537567D01*
X535775Y823156D01*
Y825240D01*
G01X535067Y827298D02*
X537567D01*
X537067Y826798D01*
G01X535067D02*
Y827798D01*
G01Y830398D02*
X537567D01*
X537067Y829898D01*
G01X535067D02*
Y830898D01*
G01X535359Y832790D02*
X535150Y833081D01*
X535067Y833415D01*
X535150Y833748D01*
X535400Y834040D01*
X535775Y834248D01*
X536150Y834331D01*
X536609D01*
X536984Y834248D01*
X537317Y834040D01*
X537484Y833790D01*
X537567Y833498D01*
X537484Y833165D01*
X537317Y832915D01*
X537067Y832748D01*
X536734Y832665D01*
X536442Y832748D01*
X536150Y832956D01*
X535984Y833206D01*
X535942Y833498D01*
X536025Y833831D01*
X536234Y834081D01*
X536609Y834331D01*
G01X526906Y818698D02*
X522906D01*
Y826098D01*
G01X530906Y818698D02*
X526906D01*
Y826098D01*
G01X537320Y119337D02*
X539820D01*
Y120378D01*
X539695Y120712D01*
X539528Y120920D01*
X539195Y121003D01*
X538862Y120920D01*
X538653Y120670D01*
X538528Y120378D01*
Y119337D01*
G01Y120378D02*
X537320Y121003D01*
G01X539403Y122478D02*
X539653Y122728D01*
X539778Y123020D01*
X539820Y123353D01*
X539737Y123770D01*
X539528Y124062D01*
X539278Y124145D01*
X539028Y124103D01*
X538820Y123937D01*
X538403Y123103D01*
X538112Y122728D01*
X537695Y122478D01*
X537320Y122395D01*
Y124145D01*
G01X537612Y125662D02*
X537403Y125953D01*
X537320Y126287D01*
X537403Y126620D01*
X537653Y126912D01*
X538028Y127120D01*
X538403Y127203D01*
X538862D01*
X539237Y127120D01*
X539570Y126912D01*
X539737Y126662D01*
X539820Y126370D01*
X539737Y126037D01*
X539570Y125787D01*
X539320Y125620D01*
X538987Y125537D01*
X538695Y125620D01*
X538403Y125828D01*
X538237Y126078D01*
X538195Y126370D01*
X538278Y126703D01*
X538487Y126953D01*
X538862Y127203D01*
G01X539403Y128678D02*
X539653Y128928D01*
X539778Y129220D01*
X539820Y129553D01*
X539737Y129970D01*
X539528Y130262D01*
X539278Y130345D01*
X539028Y130303D01*
X538820Y130137D01*
X538403Y129303D01*
X538112Y128928D01*
X537695Y128678D01*
X537320Y128595D01*
Y130345D01*
G01X538362Y131778D02*
X538653Y132070D01*
X538820Y132320D01*
X538903Y132653D01*
X538820Y132945D01*
X538653Y133153D01*
X538403Y133320D01*
X538112Y133362D01*
X537862Y133320D01*
X537612Y133153D01*
X537403Y132903D01*
X537320Y132612D01*
X537403Y132278D01*
X537653Y131987D01*
X538028Y131820D01*
X538445Y131778D01*
X538987Y131862D01*
X539278Y131987D01*
X539570Y132195D01*
X539778Y132487D01*
X539820Y132778D01*
X539737Y133070D01*
X539528Y133278D01*
G01X541320Y119337D02*
X543820D01*
Y120378D01*
X543695Y120712D01*
X543528Y120920D01*
X543195Y121003D01*
X542862Y120920D01*
X542653Y120670D01*
X542528Y120378D01*
Y119337D01*
G01Y120378D02*
X541320Y121003D01*
G01X543403Y122478D02*
X543653Y122728D01*
X543778Y123020D01*
X543820Y123353D01*
X543737Y123770D01*
X543528Y124062D01*
X543278Y124145D01*
X543028Y124103D01*
X542820Y123937D01*
X542403Y123103D01*
X542112Y122728D01*
X541695Y122478D01*
X541320Y122395D01*
Y124145D01*
G01X541612Y125662D02*
X541403Y125953D01*
X541320Y126287D01*
X541403Y126620D01*
X541653Y126912D01*
X542028Y127120D01*
X542403Y127203D01*
X542862D01*
X543237Y127120D01*
X543570Y126912D01*
X543737Y126662D01*
X543820Y126370D01*
X543737Y126037D01*
X543570Y125787D01*
X543320Y125620D01*
X542987Y125537D01*
X542695Y125620D01*
X542403Y125828D01*
X542237Y126078D01*
X542195Y126370D01*
X542278Y126703D01*
X542487Y126953D01*
X542862Y127203D01*
G01X541320Y129470D02*
X543820D01*
X543320Y128970D01*
G01X541320D02*
Y129970D01*
G01Y132570D02*
X541362Y132862D01*
X541487Y133195D01*
X541695Y133403D01*
X541987Y133487D01*
X542278Y133403D01*
X542528Y133153D01*
X542653Y132778D01*
Y132362D01*
X542737Y132112D01*
X542945Y131903D01*
X543237Y131820D01*
X543528Y131945D01*
X543737Y132237D01*
X543820Y132570D01*
X543737Y132903D01*
X543528Y133195D01*
X543237Y133320D01*
X542945Y133237D01*
X542737Y133028D01*
X542653Y132778D01*
Y132362D01*
X542528Y131987D01*
X542278Y131737D01*
X541987Y131653D01*
X541695Y131737D01*
X541487Y131945D01*
X541362Y132278D01*
X541320Y132570D01*
G01X568345Y135730D02*
X572345D01*
Y128330D01*
G01X555213Y128130D02*
X555463Y128255D01*
X555755Y128338D01*
X556088D01*
X556463Y128213D01*
X556755Y128005D01*
X556963Y127755D01*
X557130Y127338D01*
X557172Y126963D01*
X557088Y126588D01*
X556963Y126338D01*
X556713Y126088D01*
X556422Y125921D01*
X556130Y125838D01*
X555838D01*
X555547Y125921D01*
X555297Y126046D01*
X555088Y126213D01*
G01X553822Y127921D02*
X553572Y128171D01*
X553280Y128296D01*
X552947Y128338D01*
X552530Y128255D01*
X552238Y128046D01*
X552155Y127796D01*
X552197Y127546D01*
X552363Y127338D01*
X553197Y126921D01*
X553572Y126630D01*
X553822Y126213D01*
X553905Y125838D01*
X552155D01*
G01X550722Y127921D02*
X550472Y128171D01*
X550180Y128296D01*
X549847Y128338D01*
X549430Y128255D01*
X549138Y128046D01*
X549055Y127796D01*
X549097Y127546D01*
X549263Y127338D01*
X550097Y126921D01*
X550472Y126630D01*
X550722Y126213D01*
X550805Y125838D01*
X549055D01*
G01X546913D02*
X546830Y126380D01*
X546705Y126838D01*
X546538Y127255D01*
X546330Y127713D01*
X545997Y128338D01*
X547663D01*
G01X564894Y121462D02*
X565019Y121212D01*
X565102Y120920D01*
Y120587D01*
X564977Y120212D01*
X564769Y119920D01*
X564519Y119712D01*
X564102Y119545D01*
X563727Y119503D01*
X563352Y119587D01*
X563102Y119712D01*
X562852Y119962D01*
X562685Y120253D01*
X562602Y120545D01*
Y120837D01*
X562685Y121128D01*
X562810Y121378D01*
X562977Y121587D01*
G01X564685Y122853D02*
X564935Y123103D01*
X565060Y123395D01*
X565102Y123728D01*
X565019Y124145D01*
X564810Y124437D01*
X564560Y124520D01*
X564310Y124478D01*
X564102Y124312D01*
X563685Y123478D01*
X563394Y123103D01*
X562977Y122853D01*
X562602Y122770D01*
Y124520D01*
G01X564685Y125953D02*
X564935Y126203D01*
X565060Y126495D01*
X565102Y126828D01*
X565019Y127245D01*
X564810Y127537D01*
X564560Y127620D01*
X564310Y127578D01*
X564102Y127412D01*
X563685Y126578D01*
X563394Y126203D01*
X562977Y125953D01*
X562602Y125870D01*
Y127620D01*
G01X562977Y128928D02*
X562769Y129178D01*
X562644Y129470D01*
X562602Y129845D01*
X562685Y130220D01*
X562852Y130512D01*
X563144Y130720D01*
X563477Y130762D01*
X563810Y130678D01*
X564019Y130470D01*
X564185Y130178D01*
X564227Y129887D01*
X564185Y129595D01*
X564019Y129220D01*
X565102Y129345D01*
Y130470D01*
G01X555233Y124686D02*
X555483Y124811D01*
X555775Y124894D01*
X556108D01*
X556483Y124769D01*
X556775Y124561D01*
X556983Y124311D01*
X557150Y123894D01*
X557192Y123519D01*
X557108Y123144D01*
X556983Y122894D01*
X556733Y122644D01*
X556442Y122477D01*
X556150Y122394D01*
X555858D01*
X555567Y122477D01*
X555317Y122602D01*
X555108Y122769D01*
G01X553842Y124477D02*
X553592Y124727D01*
X553300Y124852D01*
X552967Y124894D01*
X552550Y124811D01*
X552258Y124602D01*
X552175Y124352D01*
X552217Y124102D01*
X552383Y123894D01*
X553217Y123477D01*
X553592Y123186D01*
X553842Y122769D01*
X553925Y122394D01*
X552175D01*
G01X550742Y124477D02*
X550492Y124727D01*
X550200Y124852D01*
X549867Y124894D01*
X549450Y124811D01*
X549158Y124602D01*
X549075Y124352D01*
X549117Y124102D01*
X549283Y123894D01*
X550117Y123477D01*
X550492Y123186D01*
X550742Y122769D01*
X550825Y122394D01*
X549075D01*
G01X546350D02*
Y124894D01*
X547892Y123102D01*
X545808D01*
G01X561483Y121462D02*
X561608Y121212D01*
X561691Y120920D01*
Y120587D01*
X561566Y120212D01*
X561358Y119920D01*
X561108Y119712D01*
X560691Y119545D01*
X560316Y119503D01*
X559941Y119587D01*
X559691Y119712D01*
X559441Y119962D01*
X559274Y120253D01*
X559191Y120545D01*
Y120837D01*
X559274Y121128D01*
X559399Y121378D01*
X559566Y121587D01*
G01X561274Y122853D02*
X561524Y123103D01*
X561649Y123395D01*
X561691Y123728D01*
X561608Y124145D01*
X561399Y124437D01*
X561149Y124520D01*
X560899Y124478D01*
X560691Y124312D01*
X560274Y123478D01*
X559983Y123103D01*
X559566Y122853D01*
X559191Y122770D01*
Y124520D01*
G01X561274Y125953D02*
X561524Y126203D01*
X561649Y126495D01*
X561691Y126828D01*
X561608Y127245D01*
X561399Y127537D01*
X561149Y127620D01*
X560899Y127578D01*
X560691Y127412D01*
X560274Y126578D01*
X559983Y126203D01*
X559566Y125953D01*
X559191Y125870D01*
Y127620D01*
G01X559691Y128928D02*
X559399Y129178D01*
X559233Y129512D01*
X559191Y129887D01*
X559233Y130220D01*
X559441Y130553D01*
X559691Y130762D01*
X559941Y130803D01*
X560233Y130720D01*
X560441Y130428D01*
X560524Y130137D01*
Y129762D01*
G01Y130137D02*
X560649Y130387D01*
X560858Y130595D01*
X561108Y130678D01*
X561358Y130595D01*
X561566Y130387D01*
X561691Y130012D01*
X561649Y129637D01*
X561483Y129262D01*
G01X568333Y242100D02*
Y244600D01*
X567333D01*
X567000Y244475D01*
X566750Y244183D01*
X566667Y243850D01*
X566750Y243517D01*
X566958Y243267D01*
X567333Y243142D01*
X568333D01*
G01X565233Y242100D02*
Y244600D01*
X564192D01*
X563858Y244475D01*
X563650Y244308D01*
X563567Y243975D01*
X563650Y243642D01*
X563900Y243433D01*
X564192Y243308D01*
X565233D01*
G01X564192D02*
X563567Y242100D01*
G01X561300D02*
Y244600D01*
X561800Y244100D01*
G01Y242100D02*
X560800D01*
G01X558283D02*
X558200Y242642D01*
X558075Y243100D01*
X557908Y243517D01*
X557700Y243975D01*
X557367Y244600D01*
X559033D01*
G01X555183Y242100D02*
X555100Y242642D01*
X554975Y243100D01*
X554808Y243517D01*
X554600Y243975D01*
X554267Y244600D01*
X555933D01*
G01X578833Y259200D02*
Y261700D01*
X577833D01*
X577500Y261575D01*
X577250Y261283D01*
X577167Y260950D01*
X577250Y260617D01*
X577458Y260367D01*
X577833Y260242D01*
X578833D01*
G01X573983Y261492D02*
X574233Y261617D01*
X574525Y261700D01*
X574858D01*
X575233Y261575D01*
X575525Y261367D01*
X575733Y261117D01*
X575900Y260700D01*
X575942Y260325D01*
X575858Y259950D01*
X575733Y259700D01*
X575483Y259450D01*
X575192Y259283D01*
X574900Y259200D01*
X574608D01*
X574317Y259283D01*
X574067Y259408D01*
X573858Y259575D01*
G01X571800Y259200D02*
Y261700D01*
X572300Y261200D01*
G01Y259200D02*
X571300D01*
G01X569408Y259492D02*
X569117Y259283D01*
X568783Y259200D01*
X568450Y259283D01*
X568158Y259533D01*
X567950Y259908D01*
X567867Y260283D01*
Y260742D01*
X567950Y261117D01*
X568158Y261450D01*
X568408Y261617D01*
X568700Y261700D01*
X569033Y261617D01*
X569283Y261450D01*
X569450Y261200D01*
X569533Y260867D01*
X569450Y260575D01*
X569242Y260283D01*
X568992Y260117D01*
X568700Y260075D01*
X568367Y260158D01*
X568117Y260367D01*
X567867Y260742D01*
G01X565683Y259200D02*
X565600Y259742D01*
X565475Y260200D01*
X565308Y260617D01*
X565100Y261075D01*
X564767Y261700D01*
X566433D01*
G01X545192Y357097D02*
X547692D01*
Y358097D01*
X547567Y358430D01*
X547275Y358680D01*
X546942Y358763D01*
X546609Y358680D01*
X546359Y358472D01*
X546234Y358097D01*
Y357097D01*
G01X547484Y361947D02*
X547609Y361697D01*
X547692Y361405D01*
Y361072D01*
X547567Y360697D01*
X547359Y360405D01*
X547109Y360197D01*
X546692Y360030D01*
X546317Y359988D01*
X545942Y360072D01*
X545692Y360197D01*
X545442Y360447D01*
X545275Y360738D01*
X545192Y361030D01*
Y361322D01*
X545275Y361613D01*
X545400Y361863D01*
X545567Y362072D01*
G01X545192Y364130D02*
X545234Y364422D01*
X545359Y364755D01*
X545567Y364963D01*
X545859Y365047D01*
X546150Y364963D01*
X546400Y364713D01*
X546525Y364338D01*
Y363922D01*
X546609Y363672D01*
X546817Y363463D01*
X547109Y363380D01*
X547400Y363505D01*
X547609Y363797D01*
X547692Y364130D01*
X547609Y364463D01*
X547400Y364755D01*
X547109Y364880D01*
X546817Y364797D01*
X546609Y364588D01*
X546525Y364338D01*
Y363922D01*
X546400Y363547D01*
X546150Y363297D01*
X545859Y363213D01*
X545567Y363297D01*
X545359Y363505D01*
X545234Y363838D01*
X545192Y364130D01*
G01X546234Y366438D02*
X546525Y366730D01*
X546692Y366980D01*
X546775Y367313D01*
X546692Y367605D01*
X546525Y367813D01*
X546275Y367980D01*
X545984Y368022D01*
X545734Y367980D01*
X545484Y367813D01*
X545275Y367563D01*
X545192Y367272D01*
X545275Y366938D01*
X545525Y366647D01*
X545900Y366480D01*
X546317Y366438D01*
X546859Y366522D01*
X547150Y366647D01*
X547442Y366855D01*
X547650Y367147D01*
X547692Y367438D01*
X547609Y367730D01*
X547400Y367938D01*
G01X549192Y357097D02*
X551692D01*
Y358097D01*
X551567Y358430D01*
X551275Y358680D01*
X550942Y358763D01*
X550609Y358680D01*
X550359Y358472D01*
X550234Y358097D01*
Y357097D01*
G01X551484Y361947D02*
X551609Y361697D01*
X551692Y361405D01*
Y361072D01*
X551567Y360697D01*
X551359Y360405D01*
X551109Y360197D01*
X550692Y360030D01*
X550317Y359988D01*
X549942Y360072D01*
X549692Y360197D01*
X549442Y360447D01*
X549275Y360738D01*
X549192Y361030D01*
Y361322D01*
X549275Y361613D01*
X549400Y361863D01*
X549567Y362072D01*
G01X549192Y364130D02*
X549234Y364422D01*
X549359Y364755D01*
X549567Y364963D01*
X549859Y365047D01*
X550150Y364963D01*
X550400Y364713D01*
X550525Y364338D01*
Y363922D01*
X550609Y363672D01*
X550817Y363463D01*
X551109Y363380D01*
X551400Y363505D01*
X551609Y363797D01*
X551692Y364130D01*
X551609Y364463D01*
X551400Y364755D01*
X551109Y364880D01*
X550817Y364797D01*
X550609Y364588D01*
X550525Y364338D01*
Y363922D01*
X550400Y363547D01*
X550150Y363297D01*
X549859Y363213D01*
X549567Y363297D01*
X549359Y363505D01*
X549234Y363838D01*
X549192Y364130D01*
G01X549484Y366522D02*
X549275Y366813D01*
X549192Y367147D01*
X549275Y367480D01*
X549525Y367772D01*
X549900Y367980D01*
X550275Y368063D01*
X550734D01*
X551109Y367980D01*
X551442Y367772D01*
X551609Y367522D01*
X551692Y367230D01*
X551609Y366897D01*
X551442Y366647D01*
X551192Y366480D01*
X550859Y366397D01*
X550567Y366480D01*
X550275Y366688D01*
X550109Y366938D01*
X550067Y367230D01*
X550150Y367563D01*
X550359Y367813D01*
X550734Y368063D01*
G01X568895Y773369D02*
X571395D01*
Y774410D01*
X571270Y774744D01*
X571103Y774952D01*
X570770Y775035D01*
X570437Y774952D01*
X570228Y774702D01*
X570103Y774410D01*
Y773369D01*
G01Y774410D02*
X568895Y775035D01*
G01X569395Y776385D02*
X569103Y776635D01*
X568937Y776969D01*
X568895Y777344D01*
X568937Y777677D01*
X569145Y778010D01*
X569395Y778219D01*
X569645Y778260D01*
X569937Y778177D01*
X570145Y777885D01*
X570228Y777594D01*
Y777219D01*
G01Y777594D02*
X570353Y777844D01*
X570562Y778052D01*
X570812Y778135D01*
X571062Y778052D01*
X571270Y777844D01*
X571395Y777469D01*
X571353Y777094D01*
X571187Y776719D01*
G01X570978Y779610D02*
X571228Y779860D01*
X571353Y780152D01*
X571395Y780485D01*
X571312Y780902D01*
X571103Y781194D01*
X570853Y781277D01*
X570603Y781235D01*
X570395Y781069D01*
X569978Y780235D01*
X569687Y779860D01*
X569270Y779610D01*
X568895Y779527D01*
Y781277D01*
G01X571395Y783502D02*
X571312Y783169D01*
X571103Y782919D01*
X570853Y782752D01*
X570520Y782627D01*
X570145Y782585D01*
X569770Y782627D01*
X569437Y782752D01*
X569187Y782919D01*
X568978Y783169D01*
X568895Y783502D01*
X568978Y783835D01*
X569187Y784085D01*
X569437Y784252D01*
X569770Y784377D01*
X570145Y784419D01*
X570520Y784377D01*
X570853Y784252D01*
X571103Y784085D01*
X571312Y783835D01*
X571395Y783502D01*
G01X569187Y785894D02*
X568978Y786185D01*
X568895Y786519D01*
X568978Y786852D01*
X569228Y787144D01*
X569603Y787352D01*
X569978Y787435D01*
X570437D01*
X570812Y787352D01*
X571145Y787144D01*
X571312Y786894D01*
X571395Y786602D01*
X571312Y786269D01*
X571145Y786019D01*
X570895Y785852D01*
X570562Y785769D01*
X570270Y785852D01*
X569978Y786060D01*
X569812Y786310D01*
X569770Y786602D01*
X569853Y786935D01*
X570062Y787185D01*
X570437Y787435D01*
G01X553594Y774448D02*
X556094D01*
Y775489D01*
X555969Y775823D01*
X555802Y776031D01*
X555469Y776114D01*
X555136Y776031D01*
X554927Y775781D01*
X554802Y775489D01*
Y774448D01*
G01Y775489D02*
X553594Y776114D01*
G01X554094Y777464D02*
X553802Y777714D01*
X553636Y778048D01*
X553594Y778423D01*
X553636Y778756D01*
X553844Y779089D01*
X554094Y779298D01*
X554344Y779339D01*
X554636Y779256D01*
X554844Y778964D01*
X554927Y778673D01*
Y778298D01*
G01Y778673D02*
X555052Y778923D01*
X555261Y779131D01*
X555511Y779214D01*
X555761Y779131D01*
X555969Y778923D01*
X556094Y778548D01*
X556052Y778173D01*
X555886Y777798D01*
G01X555677Y780689D02*
X555927Y780939D01*
X556052Y781231D01*
X556094Y781564D01*
X556011Y781981D01*
X555802Y782273D01*
X555552Y782356D01*
X555302Y782314D01*
X555094Y782148D01*
X554677Y781314D01*
X554386Y780939D01*
X553969Y780689D01*
X553594Y780606D01*
Y782356D01*
G01X555677Y783789D02*
X555927Y784039D01*
X556052Y784331D01*
X556094Y784664D01*
X556011Y785081D01*
X555802Y785373D01*
X555552Y785456D01*
X555302Y785414D01*
X555094Y785248D01*
X554677Y784414D01*
X554386Y784039D01*
X553969Y783789D01*
X553594Y783706D01*
Y785456D01*
G01Y788181D02*
X556094D01*
X554302Y786639D01*
Y788723D01*
G01X561786Y775809D02*
X561911Y775559D01*
X561994Y775267D01*
Y774934D01*
X561869Y774559D01*
X561661Y774267D01*
X561411Y774059D01*
X560994Y773892D01*
X560619Y773850D01*
X560244Y773934D01*
X559994Y774059D01*
X559744Y774309D01*
X559577Y774600D01*
X559494Y774892D01*
Y775184D01*
X559577Y775475D01*
X559702Y775725D01*
X559869Y775934D01*
G01X559994Y777075D02*
X559702Y777325D01*
X559536Y777659D01*
X559494Y778034D01*
X559536Y778367D01*
X559744Y778700D01*
X559994Y778909D01*
X560244Y778950D01*
X560536Y778867D01*
X560744Y778575D01*
X560827Y778284D01*
Y777909D01*
G01Y778284D02*
X560952Y778534D01*
X561161Y778742D01*
X561411Y778825D01*
X561661Y778742D01*
X561869Y778534D01*
X561994Y778159D01*
X561952Y777784D01*
X561786Y777409D01*
G01X561577Y780300D02*
X561827Y780550D01*
X561952Y780842D01*
X561994Y781175D01*
X561911Y781592D01*
X561702Y781884D01*
X561452Y781967D01*
X561202Y781925D01*
X560994Y781759D01*
X560577Y780925D01*
X560286Y780550D01*
X559869Y780300D01*
X559494Y780217D01*
Y781967D01*
G01Y784192D02*
X561994D01*
X561494Y783692D01*
G01X559494D02*
Y784692D01*
G01X561994Y787292D02*
X561911Y786959D01*
X561702Y786709D01*
X561452Y786542D01*
X561119Y786417D01*
X560744Y786375D01*
X560369Y786417D01*
X560036Y786542D01*
X559786Y786709D01*
X559577Y786959D01*
X559494Y787292D01*
X559577Y787625D01*
X559786Y787875D01*
X560036Y788042D01*
X560369Y788167D01*
X560744Y788209D01*
X561119Y788167D01*
X561452Y788042D01*
X561702Y787875D01*
X561911Y787625D01*
X561994Y787292D01*
G01X551936Y776185D02*
X552061Y775935D01*
X552144Y775643D01*
Y775310D01*
X552019Y774935D01*
X551811Y774643D01*
X551561Y774435D01*
X551144Y774268D01*
X550769Y774226D01*
X550394Y774310D01*
X550144Y774435D01*
X549894Y774685D01*
X549727Y774976D01*
X549644Y775268D01*
Y775560D01*
X549727Y775851D01*
X549852Y776101D01*
X550019Y776310D01*
G01X550144Y777451D02*
X549852Y777701D01*
X549686Y778035D01*
X549644Y778410D01*
X549686Y778743D01*
X549894Y779076D01*
X550144Y779285D01*
X550394Y779326D01*
X550686Y779243D01*
X550894Y778951D01*
X550977Y778660D01*
Y778285D01*
G01Y778660D02*
X551102Y778910D01*
X551311Y779118D01*
X551561Y779201D01*
X551811Y779118D01*
X552019Y778910D01*
X552144Y778535D01*
X552102Y778160D01*
X551936Y777785D01*
G01X551727Y780676D02*
X551977Y780926D01*
X552102Y781218D01*
X552144Y781551D01*
X552061Y781968D01*
X551852Y782260D01*
X551602Y782343D01*
X551352Y782301D01*
X551144Y782135D01*
X550727Y781301D01*
X550436Y780926D01*
X550019Y780676D01*
X549644Y780593D01*
Y782343D01*
G01X552144Y784568D02*
X552061Y784235D01*
X551852Y783985D01*
X551602Y783818D01*
X551269Y783693D01*
X550894Y783651D01*
X550519Y783693D01*
X550186Y783818D01*
X549936Y783985D01*
X549727Y784235D01*
X549644Y784568D01*
X549727Y784901D01*
X549936Y785151D01*
X550186Y785318D01*
X550519Y785443D01*
X550894Y785485D01*
X551269Y785443D01*
X551602Y785318D01*
X551852Y785151D01*
X552061Y784901D01*
X552144Y784568D01*
G01X549936Y786960D02*
X549727Y787251D01*
X549644Y787585D01*
X549727Y787918D01*
X549977Y788210D01*
X550352Y788418D01*
X550727Y788501D01*
X551186D01*
X551561Y788418D01*
X551894Y788210D01*
X552061Y787960D01*
X552144Y787668D01*
X552061Y787335D01*
X551894Y787085D01*
X551644Y786918D01*
X551311Y786835D01*
X551019Y786918D01*
X550727Y787126D01*
X550561Y787376D01*
X550519Y787668D01*
X550602Y788001D01*
X550811Y788251D01*
X551186Y788501D01*
G01X566498Y774988D02*
X566623Y774738D01*
X566706Y774446D01*
Y774113D01*
X566581Y773738D01*
X566373Y773446D01*
X566123Y773238D01*
X565706Y773071D01*
X565331Y773029D01*
X564956Y773113D01*
X564706Y773238D01*
X564456Y773488D01*
X564289Y773779D01*
X564206Y774071D01*
Y774363D01*
X564289Y774654D01*
X564414Y774904D01*
X564581Y775113D01*
G01X564206Y777671D02*
X566706D01*
X564914Y776129D01*
Y778213D01*
G01X564206Y780271D02*
X566706D01*
X566206Y779771D01*
G01X564206D02*
Y780771D01*
G01Y783371D02*
X564248Y783663D01*
X564373Y783996D01*
X564581Y784204D01*
X564873Y784288D01*
X565164Y784204D01*
X565414Y783954D01*
X565539Y783579D01*
Y783163D01*
X565623Y782913D01*
X565831Y782704D01*
X566123Y782621D01*
X566414Y782746D01*
X566623Y783038D01*
X566706Y783371D01*
X566623Y783704D01*
X566414Y783996D01*
X566123Y784121D01*
X565831Y784038D01*
X565623Y783829D01*
X565539Y783579D01*
Y783163D01*
X565414Y782788D01*
X565164Y782538D01*
X564873Y782454D01*
X564581Y782538D01*
X564373Y782746D01*
X564248Y783079D01*
X564206Y783371D01*
G01X556391Y792579D02*
X554599D01*
X554224Y792746D01*
X553974Y793079D01*
X553891Y793496D01*
X553974Y793913D01*
X554224Y794246D01*
X554599Y794413D01*
X556391D01*
G01X553891Y796513D02*
X554433Y796596D01*
X554891Y796721D01*
X555308Y796888D01*
X555766Y797096D01*
X556391Y797429D01*
Y795763D01*
G01Y799696D02*
X556308Y799363D01*
X556099Y799113D01*
X555849Y798946D01*
X555516Y798821D01*
X555141Y798779D01*
X554766Y798821D01*
X554433Y798946D01*
X554183Y799113D01*
X553974Y799363D01*
X553891Y799696D01*
X553974Y800029D01*
X554183Y800279D01*
X554433Y800446D01*
X554766Y800571D01*
X555141Y800613D01*
X555516Y800571D01*
X555849Y800446D01*
X556099Y800279D01*
X556308Y800029D01*
X556391Y799696D01*
G01X543000Y791800D02*
Y805200D01*
G01X549379Y792617D02*
X551879D01*
Y793658D01*
X551754Y793992D01*
X551587Y794200D01*
X551254Y794283D01*
X550921Y794200D01*
X550712Y793950D01*
X550587Y793658D01*
Y792617D01*
G01Y793658D02*
X549379Y794283D01*
G01Y796550D02*
X551879D01*
X551379Y796050D01*
G01X549379D02*
Y797050D01*
G01Y800150D02*
X551879D01*
X550087Y798608D01*
Y800692D01*
G01X551462Y801958D02*
X551712Y802208D01*
X551837Y802500D01*
X551879Y802833D01*
X551796Y803250D01*
X551587Y803542D01*
X551337Y803625D01*
X551087Y803583D01*
X550879Y803417D01*
X550462Y802583D01*
X550171Y802208D01*
X549754Y801958D01*
X549379Y801875D01*
Y803625D01*
G01X573958Y789244D02*
Y791744D01*
X572917D01*
X572583Y791619D01*
X572375Y791452D01*
X572292Y791119D01*
X572375Y790786D01*
X572625Y790577D01*
X572917Y790452D01*
X573958D01*
G01X572917D02*
X572292Y789244D01*
G01X570942Y789744D02*
X570692Y789452D01*
X570358Y789286D01*
X569983Y789244D01*
X569650Y789286D01*
X569317Y789494D01*
X569108Y789744D01*
X569067Y789994D01*
X569150Y790286D01*
X569442Y790494D01*
X569733Y790577D01*
X570108D01*
G01X569733D02*
X569483Y790702D01*
X569275Y790911D01*
X569192Y791161D01*
X569275Y791411D01*
X569483Y791619D01*
X569858Y791744D01*
X570233Y791702D01*
X570608Y791536D01*
G01X567717Y791327D02*
X567467Y791577D01*
X567175Y791702D01*
X566842Y791744D01*
X566425Y791661D01*
X566133Y791452D01*
X566050Y791202D01*
X566092Y790952D01*
X566258Y790744D01*
X567092Y790327D01*
X567467Y790036D01*
X567717Y789619D01*
X567800Y789244D01*
X566050D01*
G01X563825Y791744D02*
X564158Y791661D01*
X564408Y791452D01*
X564575Y791202D01*
X564700Y790869D01*
X564742Y790494D01*
X564700Y790119D01*
X564575Y789786D01*
X564408Y789536D01*
X564158Y789327D01*
X563825Y789244D01*
X563492Y789327D01*
X563242Y789536D01*
X563075Y789786D01*
X562950Y790119D01*
X562908Y790494D01*
X562950Y790869D01*
X563075Y791202D01*
X563242Y791452D01*
X563492Y791661D01*
X563825Y791744D01*
G01X561517Y790286D02*
X561225Y790577D01*
X560975Y790744D01*
X560642Y790827D01*
X560350Y790744D01*
X560142Y790577D01*
X559975Y790327D01*
X559933Y790036D01*
X559975Y789786D01*
X560142Y789536D01*
X560392Y789327D01*
X560683Y789244D01*
X561017Y789327D01*
X561308Y789577D01*
X561475Y789952D01*
X561517Y790369D01*
X561433Y790911D01*
X561308Y791202D01*
X561100Y791494D01*
X560808Y791702D01*
X560517Y791744D01*
X560225Y791661D01*
X560017Y791452D01*
G01X554952Y806194D02*
X557452D01*
Y807235D01*
X557327Y807569D01*
X557160Y807777D01*
X556827Y807860D01*
X556494Y807777D01*
X556285Y807527D01*
X556160Y807235D01*
Y806194D01*
G01Y807235D02*
X554952Y807860D01*
G01X555452Y809210D02*
X555160Y809460D01*
X554994Y809794D01*
X554952Y810169D01*
X554994Y810502D01*
X555202Y810835D01*
X555452Y811044D01*
X555702Y811085D01*
X555994Y811002D01*
X556202Y810710D01*
X556285Y810419D01*
Y810044D01*
G01Y810419D02*
X556410Y810669D01*
X556619Y810877D01*
X556869Y810960D01*
X557119Y810877D01*
X557327Y810669D01*
X557452Y810294D01*
X557410Y809919D01*
X557244Y809544D01*
G01X557035Y812435D02*
X557285Y812685D01*
X557410Y812977D01*
X557452Y813310D01*
X557369Y813727D01*
X557160Y814019D01*
X556910Y814102D01*
X556660Y814060D01*
X556452Y813894D01*
X556035Y813060D01*
X555744Y812685D01*
X555327Y812435D01*
X554952Y812352D01*
Y814102D01*
G01Y816327D02*
X557452D01*
X556952Y815827D01*
G01X554952D02*
Y816827D01*
G01X555244Y818719D02*
X555035Y819010D01*
X554952Y819344D01*
X555035Y819677D01*
X555285Y819969D01*
X555660Y820177D01*
X556035Y820260D01*
X556494D01*
X556869Y820177D01*
X557202Y819969D01*
X557369Y819719D01*
X557452Y819427D01*
X557369Y819094D01*
X557202Y818844D01*
X556952Y818677D01*
X556619Y818594D01*
X556327Y818677D01*
X556035Y818885D01*
X555869Y819135D01*
X555827Y819427D01*
X555910Y819760D01*
X556119Y820010D01*
X556494Y820260D01*
G01X536678Y814131D02*
X540678D01*
Y806731D01*
G01X550794Y806282D02*
X553294D01*
Y807323D01*
X553169Y807657D01*
X553002Y807865D01*
X552669Y807948D01*
X552336Y807865D01*
X552127Y807615D01*
X552002Y807323D01*
Y806282D01*
G01Y807323D02*
X550794Y807948D01*
G01X551294Y809298D02*
X551002Y809548D01*
X550836Y809882D01*
X550794Y810257D01*
X550836Y810590D01*
X551044Y810923D01*
X551294Y811132D01*
X551544Y811173D01*
X551836Y811090D01*
X552044Y810798D01*
X552127Y810507D01*
Y810132D01*
G01Y810507D02*
X552252Y810757D01*
X552461Y810965D01*
X552711Y811048D01*
X552961Y810965D01*
X553169Y810757D01*
X553294Y810382D01*
X553252Y810007D01*
X553086Y809632D01*
G01X552877Y812523D02*
X553127Y812773D01*
X553252Y813065D01*
X553294Y813398D01*
X553211Y813815D01*
X553002Y814107D01*
X552752Y814190D01*
X552502Y814148D01*
X552294Y813982D01*
X551877Y813148D01*
X551586Y812773D01*
X551169Y812523D01*
X550794Y812440D01*
Y814190D01*
G01X552877Y815623D02*
X553127Y815873D01*
X553252Y816165D01*
X553294Y816498D01*
X553211Y816915D01*
X553002Y817207D01*
X552752Y817290D01*
X552502Y817248D01*
X552294Y817082D01*
X551877Y816248D01*
X551586Y815873D01*
X551169Y815623D01*
X550794Y815540D01*
Y817290D01*
G01X553294Y819515D02*
X553211Y819182D01*
X553002Y818932D01*
X552752Y818765D01*
X552419Y818640D01*
X552044Y818598D01*
X551669Y818640D01*
X551336Y818765D01*
X551086Y818932D01*
X550877Y819182D01*
X550794Y819515D01*
X550877Y819848D01*
X551086Y820098D01*
X551336Y820265D01*
X551669Y820390D01*
X552044Y820432D01*
X552419Y820390D01*
X552752Y820265D01*
X553002Y820098D01*
X553211Y819848D01*
X553294Y819515D01*
G01X538678Y790131D02*
X542678D01*
Y782731D01*
G01X559287Y806283D02*
X561787D01*
Y807324D01*
X561662Y807658D01*
X561495Y807866D01*
X561162Y807949D01*
X560829Y807866D01*
X560620Y807616D01*
X560495Y807324D01*
Y806283D01*
G01Y807324D02*
X559287Y807949D01*
G01X559579Y809508D02*
X559370Y809799D01*
X559287Y810133D01*
X559370Y810466D01*
X559620Y810758D01*
X559995Y810966D01*
X560370Y811049D01*
X560829D01*
X561204Y810966D01*
X561537Y810758D01*
X561704Y810508D01*
X561787Y810216D01*
X561704Y809883D01*
X561537Y809633D01*
X561287Y809466D01*
X560954Y809383D01*
X560662Y809466D01*
X560370Y809674D01*
X560204Y809924D01*
X560162Y810216D01*
X560245Y810549D01*
X560454Y810799D01*
X560829Y811049D01*
G01X561787Y813316D02*
X561704Y812983D01*
X561495Y812733D01*
X561245Y812566D01*
X560912Y812441D01*
X560537Y812399D01*
X560162Y812441D01*
X559829Y812566D01*
X559579Y812733D01*
X559370Y812983D01*
X559287Y813316D01*
X559370Y813649D01*
X559579Y813899D01*
X559829Y814066D01*
X560162Y814191D01*
X560537Y814233D01*
X560912Y814191D01*
X561245Y814066D01*
X561495Y813899D01*
X561704Y813649D01*
X561787Y813316D01*
G01X559787Y815499D02*
X559495Y815749D01*
X559329Y816083D01*
X559287Y816458D01*
X559329Y816791D01*
X559537Y817124D01*
X559787Y817333D01*
X560037Y817374D01*
X560329Y817291D01*
X560537Y816999D01*
X560620Y816708D01*
Y816333D01*
G01Y816708D02*
X560745Y816958D01*
X560954Y817166D01*
X561204Y817249D01*
X561454Y817166D01*
X561662Y816958D01*
X561787Y816583D01*
X561745Y816208D01*
X561579Y815833D01*
G01X559662Y818599D02*
X559454Y818849D01*
X559329Y819141D01*
X559287Y819516D01*
X559370Y819891D01*
X559537Y820183D01*
X559829Y820391D01*
X560162Y820433D01*
X560495Y820349D01*
X560704Y820141D01*
X560870Y819849D01*
X560912Y819558D01*
X560870Y819266D01*
X560704Y818891D01*
X561787Y819016D01*
Y820141D01*
G01X540800Y814500D02*
X544800D01*
Y807100D01*
G01X539067Y820265D02*
X541567D01*
Y821306D01*
X541442Y821640D01*
X541275Y821848D01*
X540942Y821931D01*
X540609Y821848D01*
X540400Y821598D01*
X540275Y821306D01*
Y820265D01*
G01Y821306D02*
X539067Y821931D01*
G01Y824698D02*
X541567D01*
X539775Y823156D01*
Y825240D01*
G01X539067Y827298D02*
X541567D01*
X541067Y826798D01*
G01X539067D02*
Y827798D01*
G01Y830398D02*
X541567D01*
X541067Y829898D01*
G01X539067D02*
Y830898D01*
G01Y833498D02*
X539109Y833790D01*
X539234Y834123D01*
X539442Y834331D01*
X539734Y834415D01*
X540025Y834331D01*
X540275Y834081D01*
X540400Y833706D01*
Y833290D01*
X540484Y833040D01*
X540692Y832831D01*
X540984Y832748D01*
X541275Y832873D01*
X541484Y833165D01*
X541567Y833498D01*
X541484Y833831D01*
X541275Y834123D01*
X540984Y834248D01*
X540692Y834165D01*
X540484Y833956D01*
X540400Y833706D01*
Y833290D01*
X540275Y832915D01*
X540025Y832665D01*
X539734Y832581D01*
X539442Y832665D01*
X539234Y832873D01*
X539109Y833206D01*
X539067Y833498D01*
G01X582471Y11667D02*
X583138Y11167D01*
X583638Y10334D01*
X583971Y9167D01*
X583638Y8167D01*
X582971Y7500D01*
X581805Y7000D01*
X577305D01*
Y17000D01*
X582805D01*
X583971Y16333D01*
X584638Y15333D01*
X584971Y14167D01*
X584638Y13000D01*
X583638Y12000D01*
X582471Y11667D01*
X577305D01*
G01X584367Y109797D02*
X586867D01*
Y110838D01*
X586742Y111172D01*
X586575Y111380D01*
X586242Y111463D01*
X585909Y111380D01*
X585700Y111130D01*
X585575Y110838D01*
Y109797D01*
G01Y110838D02*
X584367Y111463D01*
G01X586450Y112938D02*
X586700Y113188D01*
X586825Y113480D01*
X586867Y113813D01*
X586784Y114230D01*
X586575Y114522D01*
X586325Y114605D01*
X586075Y114563D01*
X585867Y114397D01*
X585450Y113563D01*
X585159Y113188D01*
X584742Y112938D01*
X584367Y112855D01*
Y114605D01*
G01X584659Y116122D02*
X584450Y116413D01*
X584367Y116747D01*
X584450Y117080D01*
X584700Y117372D01*
X585075Y117580D01*
X585450Y117663D01*
X585909D01*
X586284Y117580D01*
X586617Y117372D01*
X586784Y117122D01*
X586867Y116830D01*
X586784Y116497D01*
X586617Y116247D01*
X586367Y116080D01*
X586034Y115997D01*
X585742Y116080D01*
X585450Y116288D01*
X585284Y116538D01*
X585242Y116830D01*
X585325Y117163D01*
X585534Y117413D01*
X585909Y117663D01*
G01X586450Y119138D02*
X586700Y119388D01*
X586825Y119680D01*
X586867Y120013D01*
X586784Y120430D01*
X586575Y120722D01*
X586325Y120805D01*
X586075Y120763D01*
X585867Y120597D01*
X585450Y119763D01*
X585159Y119388D01*
X584742Y119138D01*
X584367Y119055D01*
Y120805D01*
G01Y123030D02*
X584409Y123322D01*
X584534Y123655D01*
X584742Y123863D01*
X585034Y123947D01*
X585325Y123863D01*
X585575Y123613D01*
X585700Y123238D01*
Y122822D01*
X585784Y122572D01*
X585992Y122363D01*
X586284Y122280D01*
X586575Y122405D01*
X586784Y122697D01*
X586867Y123030D01*
X586784Y123363D01*
X586575Y123655D01*
X586284Y123780D01*
X585992Y123697D01*
X585784Y123488D01*
X585700Y123238D01*
Y122822D01*
X585575Y122447D01*
X585325Y122197D01*
X585034Y122113D01*
X584742Y122197D01*
X584534Y122405D01*
X584409Y122738D01*
X584367Y123030D01*
G01X576467Y135730D02*
X580467D01*
Y128330D01*
G01X588367Y109797D02*
X590867D01*
Y110838D01*
X590742Y111172D01*
X590575Y111380D01*
X590242Y111463D01*
X589909Y111380D01*
X589700Y111130D01*
X589575Y110838D01*
Y109797D01*
G01Y110838D02*
X588367Y111463D01*
G01X590450Y112938D02*
X590700Y113188D01*
X590825Y113480D01*
X590867Y113813D01*
X590784Y114230D01*
X590575Y114522D01*
X590325Y114605D01*
X590075Y114563D01*
X589867Y114397D01*
X589450Y113563D01*
X589159Y113188D01*
X588742Y112938D01*
X588367Y112855D01*
Y114605D01*
G01X588659Y116122D02*
X588450Y116413D01*
X588367Y116747D01*
X588450Y117080D01*
X588700Y117372D01*
X589075Y117580D01*
X589450Y117663D01*
X589909D01*
X590284Y117580D01*
X590617Y117372D01*
X590784Y117122D01*
X590867Y116830D01*
X590784Y116497D01*
X590617Y116247D01*
X590367Y116080D01*
X590034Y115997D01*
X589742Y116080D01*
X589450Y116288D01*
X589284Y116538D01*
X589242Y116830D01*
X589325Y117163D01*
X589534Y117413D01*
X589909Y117663D01*
G01X590450Y119138D02*
X590700Y119388D01*
X590825Y119680D01*
X590867Y120013D01*
X590784Y120430D01*
X590575Y120722D01*
X590325Y120805D01*
X590075Y120763D01*
X589867Y120597D01*
X589450Y119763D01*
X589159Y119388D01*
X588742Y119138D01*
X588367Y119055D01*
Y120805D01*
G01X590867Y123030D02*
X590784Y122697D01*
X590575Y122447D01*
X590325Y122280D01*
X589992Y122155D01*
X589617Y122113D01*
X589242Y122155D01*
X588909Y122280D01*
X588659Y122447D01*
X588450Y122697D01*
X588367Y123030D01*
X588450Y123363D01*
X588659Y123613D01*
X588909Y123780D01*
X589242Y123905D01*
X589617Y123947D01*
X589992Y123905D01*
X590325Y123780D01*
X590575Y123613D01*
X590784Y123363D01*
X590867Y123030D01*
G01X580467Y135730D02*
X584467D01*
Y128330D01*
G01X576245Y109797D02*
X578745D01*
Y110838D01*
X578620Y111172D01*
X578453Y111380D01*
X578120Y111463D01*
X577787Y111380D01*
X577578Y111130D01*
X577453Y110838D01*
Y109797D01*
G01Y110838D02*
X576245Y111463D01*
G01X578328Y112938D02*
X578578Y113188D01*
X578703Y113480D01*
X578745Y113813D01*
X578662Y114230D01*
X578453Y114522D01*
X578203Y114605D01*
X577953Y114563D01*
X577745Y114397D01*
X577328Y113563D01*
X577037Y113188D01*
X576620Y112938D01*
X576245Y112855D01*
Y114605D01*
G01X576537Y116122D02*
X576328Y116413D01*
X576245Y116747D01*
X576328Y117080D01*
X576578Y117372D01*
X576953Y117580D01*
X577328Y117663D01*
X577787D01*
X578162Y117580D01*
X578495Y117372D01*
X578662Y117122D01*
X578745Y116830D01*
X578662Y116497D01*
X578495Y116247D01*
X578245Y116080D01*
X577912Y115997D01*
X577620Y116080D01*
X577328Y116288D01*
X577162Y116538D01*
X577120Y116830D01*
X577203Y117163D01*
X577412Y117413D01*
X577787Y117663D01*
G01X578328Y119138D02*
X578578Y119388D01*
X578703Y119680D01*
X578745Y120013D01*
X578662Y120430D01*
X578453Y120722D01*
X578203Y120805D01*
X577953Y120763D01*
X577745Y120597D01*
X577328Y119763D01*
X577037Y119388D01*
X576620Y119138D01*
X576245Y119055D01*
Y120805D01*
G01Y122947D02*
X576787Y123030D01*
X577245Y123155D01*
X577662Y123322D01*
X578120Y123530D01*
X578745Y123863D01*
Y122197D01*
G01X580245Y109797D02*
X582745D01*
Y110838D01*
X582620Y111172D01*
X582453Y111380D01*
X582120Y111463D01*
X581787Y111380D01*
X581578Y111130D01*
X581453Y110838D01*
Y109797D01*
G01Y110838D02*
X580245Y111463D01*
G01X582328Y112938D02*
X582578Y113188D01*
X582703Y113480D01*
X582745Y113813D01*
X582662Y114230D01*
X582453Y114522D01*
X582203Y114605D01*
X581953Y114563D01*
X581745Y114397D01*
X581328Y113563D01*
X581037Y113188D01*
X580620Y112938D01*
X580245Y112855D01*
Y114605D01*
G01X580537Y116122D02*
X580328Y116413D01*
X580245Y116747D01*
X580328Y117080D01*
X580578Y117372D01*
X580953Y117580D01*
X581328Y117663D01*
X581787D01*
X582162Y117580D01*
X582495Y117372D01*
X582662Y117122D01*
X582745Y116830D01*
X582662Y116497D01*
X582495Y116247D01*
X582245Y116080D01*
X581912Y115997D01*
X581620Y116080D01*
X581328Y116288D01*
X581162Y116538D01*
X581120Y116830D01*
X581203Y117163D01*
X581412Y117413D01*
X581787Y117663D01*
G01X580245Y119930D02*
X582745D01*
X582245Y119430D01*
G01X580245D02*
Y120430D01*
G01X580537Y122322D02*
X580328Y122613D01*
X580245Y122947D01*
X580328Y123280D01*
X580578Y123572D01*
X580953Y123780D01*
X581328Y123863D01*
X581787D01*
X582162Y123780D01*
X582495Y123572D01*
X582662Y123322D01*
X582745Y123030D01*
X582662Y122697D01*
X582495Y122447D01*
X582245Y122280D01*
X581912Y122197D01*
X581620Y122280D01*
X581328Y122488D01*
X581162Y122738D01*
X581120Y123030D01*
X581203Y123363D01*
X581412Y123613D01*
X581787Y123863D01*
G01X572345Y135730D02*
X576345D01*
Y128330D01*
G01X599803Y117140D02*
X599928Y116890D01*
X600011Y116598D01*
Y116265D01*
X599886Y115890D01*
X599678Y115598D01*
X599428Y115390D01*
X599011Y115223D01*
X598636Y115181D01*
X598261Y115265D01*
X598011Y115390D01*
X597761Y115640D01*
X597594Y115931D01*
X597511Y116223D01*
Y116515D01*
X597594Y116806D01*
X597719Y117056D01*
X597886Y117265D01*
G01X599594Y118531D02*
X599844Y118781D01*
X599969Y119073D01*
X600011Y119406D01*
X599928Y119823D01*
X599719Y120115D01*
X599469Y120198D01*
X599219Y120156D01*
X599011Y119990D01*
X598594Y119156D01*
X598303Y118781D01*
X597886Y118531D01*
X597511Y118448D01*
Y120198D01*
G01X599594Y121631D02*
X599844Y121881D01*
X599969Y122173D01*
X600011Y122506D01*
X599928Y122923D01*
X599719Y123215D01*
X599469Y123298D01*
X599219Y123256D01*
X599011Y123090D01*
X598594Y122256D01*
X598303Y121881D01*
X597886Y121631D01*
X597511Y121548D01*
Y123298D01*
G01X597803Y124815D02*
X597594Y125106D01*
X597511Y125440D01*
X597594Y125773D01*
X597844Y126065D01*
X598219Y126273D01*
X598594Y126356D01*
X599053D01*
X599428Y126273D01*
X599761Y126065D01*
X599928Y125815D01*
X600011Y125523D01*
X599928Y125190D01*
X599761Y124940D01*
X599511Y124773D01*
X599178Y124690D01*
X598886Y124773D01*
X598594Y124981D01*
X598428Y125231D01*
X598386Y125523D01*
X598469Y125856D01*
X598678Y126106D01*
X599053Y126356D01*
G01X595803Y117140D02*
X595928Y116890D01*
X596011Y116598D01*
Y116265D01*
X595886Y115890D01*
X595678Y115598D01*
X595428Y115390D01*
X595011Y115223D01*
X594636Y115181D01*
X594261Y115265D01*
X594011Y115390D01*
X593761Y115640D01*
X593594Y115931D01*
X593511Y116223D01*
Y116515D01*
X593594Y116806D01*
X593719Y117056D01*
X593886Y117265D01*
G01X595594Y118531D02*
X595844Y118781D01*
X595969Y119073D01*
X596011Y119406D01*
X595928Y119823D01*
X595719Y120115D01*
X595469Y120198D01*
X595219Y120156D01*
X595011Y119990D01*
X594594Y119156D01*
X594303Y118781D01*
X593886Y118531D01*
X593511Y118448D01*
Y120198D01*
G01X595594Y121631D02*
X595844Y121881D01*
X595969Y122173D01*
X596011Y122506D01*
X595928Y122923D01*
X595719Y123215D01*
X595469Y123298D01*
X595219Y123256D01*
X595011Y123090D01*
X594594Y122256D01*
X594303Y121881D01*
X593886Y121631D01*
X593511Y121548D01*
Y123298D01*
G01Y125523D02*
X593553Y125815D01*
X593678Y126148D01*
X593886Y126356D01*
X594178Y126440D01*
X594469Y126356D01*
X594719Y126106D01*
X594844Y125731D01*
Y125315D01*
X594928Y125065D01*
X595136Y124856D01*
X595428Y124773D01*
X595719Y124898D01*
X595928Y125190D01*
X596011Y125523D01*
X595928Y125856D01*
X595719Y126148D01*
X595428Y126273D01*
X595136Y126190D01*
X594928Y125981D01*
X594844Y125731D01*
Y125315D01*
X594719Y124940D01*
X594469Y124690D01*
X594178Y124606D01*
X593886Y124690D01*
X593678Y124898D01*
X593553Y125231D01*
X593511Y125523D01*
G01X603803Y117140D02*
X603928Y116890D01*
X604011Y116598D01*
Y116265D01*
X603886Y115890D01*
X603678Y115598D01*
X603428Y115390D01*
X603011Y115223D01*
X602636Y115181D01*
X602261Y115265D01*
X602011Y115390D01*
X601761Y115640D01*
X601594Y115931D01*
X601511Y116223D01*
Y116515D01*
X601594Y116806D01*
X601719Y117056D01*
X601886Y117265D01*
G01X603594Y118531D02*
X603844Y118781D01*
X603969Y119073D01*
X604011Y119406D01*
X603928Y119823D01*
X603719Y120115D01*
X603469Y120198D01*
X603219Y120156D01*
X603011Y119990D01*
X602594Y119156D01*
X602303Y118781D01*
X601886Y118531D01*
X601511Y118448D01*
Y120198D01*
G01X603594Y121631D02*
X603844Y121881D01*
X603969Y122173D01*
X604011Y122506D01*
X603928Y122923D01*
X603719Y123215D01*
X603469Y123298D01*
X603219Y123256D01*
X603011Y123090D01*
X602594Y122256D01*
X602303Y121881D01*
X601886Y121631D01*
X601511Y121548D01*
Y123298D01*
G01X602553Y124731D02*
X602844Y125023D01*
X603011Y125273D01*
X603094Y125606D01*
X603011Y125898D01*
X602844Y126106D01*
X602594Y126273D01*
X602303Y126315D01*
X602053Y126273D01*
X601803Y126106D01*
X601594Y125856D01*
X601511Y125565D01*
X601594Y125231D01*
X601844Y124940D01*
X602219Y124773D01*
X602636Y124731D01*
X603178Y124815D01*
X603469Y124940D01*
X603761Y125148D01*
X603969Y125440D01*
X604011Y125731D01*
X603928Y126023D01*
X603719Y126231D01*
G01X580562Y203114D02*
X583062D01*
Y204114D01*
X582937Y204447D01*
X582645Y204697D01*
X582312Y204780D01*
X581979Y204697D01*
X581729Y204489D01*
X581604Y204114D01*
Y203114D01*
G01X580562Y206214D02*
X583062D01*
Y207255D01*
X582937Y207589D01*
X582770Y207797D01*
X582437Y207880D01*
X582104Y207797D01*
X581895Y207547D01*
X581770Y207255D01*
Y206214D01*
G01Y207255D02*
X580562Y207880D01*
G01Y210147D02*
X583062D01*
X582562Y209647D01*
G01X580562D02*
Y210647D01*
G01Y213164D02*
X581104Y213247D01*
X581562Y213372D01*
X581979Y213539D01*
X582437Y213747D01*
X583062Y214080D01*
Y212414D01*
G01X581062Y215430D02*
X580770Y215680D01*
X580604Y216014D01*
X580562Y216389D01*
X580604Y216722D01*
X580812Y217055D01*
X581062Y217264D01*
X581312Y217305D01*
X581604Y217222D01*
X581812Y216930D01*
X581895Y216639D01*
Y216264D01*
G01Y216639D02*
X582020Y216889D01*
X582229Y217097D01*
X582479Y217180D01*
X582729Y217097D01*
X582937Y216889D01*
X583062Y216514D01*
X583020Y216139D01*
X582854Y215764D01*
G01X588789Y203291D02*
X591289D01*
Y204291D01*
X591164Y204624D01*
X590872Y204874D01*
X590539Y204957D01*
X590206Y204874D01*
X589956Y204666D01*
X589831Y204291D01*
Y203291D01*
G01X588789Y206391D02*
X591289D01*
Y207432D01*
X591164Y207766D01*
X590997Y207974D01*
X590664Y208057D01*
X590331Y207974D01*
X590122Y207724D01*
X589997Y207432D01*
Y206391D01*
G01Y207432D02*
X588789Y208057D01*
G01Y210324D02*
X591289D01*
X590789Y209824D01*
G01X588789D02*
Y210824D01*
G01X589831Y212632D02*
X590122Y212924D01*
X590289Y213174D01*
X590372Y213507D01*
X590289Y213799D01*
X590122Y214007D01*
X589872Y214174D01*
X589581Y214216D01*
X589331Y214174D01*
X589081Y214007D01*
X588872Y213757D01*
X588789Y213466D01*
X588872Y213132D01*
X589122Y212841D01*
X589497Y212674D01*
X589914Y212632D01*
X590456Y212716D01*
X590747Y212841D01*
X591039Y213049D01*
X591247Y213341D01*
X591289Y213632D01*
X591206Y213924D01*
X590997Y214132D01*
G01X589081Y215816D02*
X588872Y216107D01*
X588789Y216441D01*
X588872Y216774D01*
X589122Y217066D01*
X589497Y217274D01*
X589872Y217357D01*
X590331D01*
X590706Y217274D01*
X591039Y217066D01*
X591206Y216816D01*
X591289Y216524D01*
X591206Y216191D01*
X591039Y215941D01*
X590789Y215774D01*
X590456Y215691D01*
X590164Y215774D01*
X589872Y215982D01*
X589706Y216232D01*
X589664Y216524D01*
X589747Y216857D01*
X589956Y217107D01*
X590331Y217357D01*
G01X584720Y209576D02*
X587220D01*
Y210576D01*
X587095Y210909D01*
X586803Y211159D01*
X586470Y211242D01*
X586137Y211159D01*
X585887Y210951D01*
X585762Y210576D01*
Y209576D01*
G01X584720Y212676D02*
X587220D01*
Y213717D01*
X587095Y214051D01*
X586928Y214259D01*
X586595Y214342D01*
X586262Y214259D01*
X586053Y214009D01*
X585928Y213717D01*
Y212676D01*
G01Y213717D02*
X584720Y214342D01*
G01X585220Y215692D02*
X584928Y215942D01*
X584762Y216276D01*
X584720Y216651D01*
X584762Y216984D01*
X584970Y217317D01*
X585220Y217526D01*
X585470Y217567D01*
X585762Y217484D01*
X585970Y217192D01*
X586053Y216901D01*
Y216526D01*
G01Y216901D02*
X586178Y217151D01*
X586387Y217359D01*
X586637Y217442D01*
X586887Y217359D01*
X587095Y217151D01*
X587220Y216776D01*
X587178Y216401D01*
X587012Y216026D01*
G01X571200Y223667D02*
X573700D01*
Y224667D01*
X573575Y225000D01*
X573283Y225250D01*
X572950Y225333D01*
X572617Y225250D01*
X572367Y225042D01*
X572242Y224667D01*
Y223667D01*
G01X573492Y228517D02*
X573617Y228267D01*
X573700Y227975D01*
Y227642D01*
X573575Y227267D01*
X573367Y226975D01*
X573117Y226767D01*
X572700Y226600D01*
X572325Y226558D01*
X571950Y226642D01*
X571700Y226767D01*
X571450Y227017D01*
X571283Y227308D01*
X571200Y227600D01*
Y227892D01*
X571283Y228183D01*
X571408Y228433D01*
X571575Y228642D01*
G01X573283Y229908D02*
X573533Y230158D01*
X573658Y230450D01*
X573700Y230783D01*
X573617Y231200D01*
X573408Y231492D01*
X573158Y231575D01*
X572908Y231533D01*
X572700Y231367D01*
X572283Y230533D01*
X571992Y230158D01*
X571575Y229908D01*
X571200Y229825D01*
Y231575D01*
G01Y233800D02*
X573700D01*
X573200Y233300D01*
G01X571200D02*
Y234300D01*
G01X573283Y236108D02*
X573533Y236358D01*
X573658Y236650D01*
X573700Y236983D01*
X573617Y237400D01*
X573408Y237692D01*
X573158Y237775D01*
X572908Y237733D01*
X572700Y237567D01*
X572283Y236733D01*
X571992Y236358D01*
X571575Y236108D01*
X571200Y236025D01*
Y237775D01*
G01X582363Y226308D02*
X586363D01*
Y218908D01*
G01X590363Y226308D02*
X594363D01*
Y218908D01*
G01X586363Y226308D02*
X590363D01*
Y218908D01*
G01X605233Y261000D02*
Y263500D01*
X604233D01*
X603900Y263375D01*
X603650Y263083D01*
X603567Y262750D01*
X603650Y262417D01*
X603858Y262167D01*
X604233Y262042D01*
X605233D01*
G01X600383Y263292D02*
X600633Y263417D01*
X600925Y263500D01*
X601258D01*
X601633Y263375D01*
X601925Y263167D01*
X602133Y262917D01*
X602300Y262500D01*
X602342Y262125D01*
X602258Y261750D01*
X602133Y261500D01*
X601883Y261250D01*
X601592Y261083D01*
X601300Y261000D01*
X601008D01*
X600717Y261083D01*
X600467Y261208D01*
X600258Y261375D01*
G01X598200Y261000D02*
Y263500D01*
X598700Y263000D01*
G01Y261000D02*
X597700D01*
G01X595808Y261292D02*
X595517Y261083D01*
X595183Y261000D01*
X594850Y261083D01*
X594558Y261333D01*
X594350Y261708D01*
X594267Y262083D01*
Y262542D01*
X594350Y262917D01*
X594558Y263250D01*
X594808Y263417D01*
X595100Y263500D01*
X595433Y263417D01*
X595683Y263250D01*
X595850Y263000D01*
X595933Y262667D01*
X595850Y262375D01*
X595642Y262083D01*
X595392Y261917D01*
X595100Y261875D01*
X594767Y261958D01*
X594517Y262167D01*
X594267Y262542D01*
G01X592917Y261375D02*
X592667Y261167D01*
X592375Y261042D01*
X592000Y261000D01*
X591625Y261083D01*
X591333Y261250D01*
X591125Y261542D01*
X591083Y261875D01*
X591167Y262208D01*
X591375Y262417D01*
X591667Y262583D01*
X591958Y262625D01*
X592250Y262583D01*
X592625Y262417D01*
X592500Y263500D01*
X591375D01*
G01X605753Y342121D02*
X605878Y341871D01*
X605961Y341579D01*
Y341246D01*
X605836Y340871D01*
X605628Y340579D01*
X605378Y340371D01*
X604961Y340204D01*
X604586Y340162D01*
X604211Y340246D01*
X603961Y340371D01*
X603711Y340621D01*
X603544Y340912D01*
X603461Y341204D01*
Y341496D01*
X603544Y341787D01*
X603669Y342037D01*
X603836Y342246D01*
G01X603461Y344221D02*
X604003Y344304D01*
X604461Y344429D01*
X604878Y344596D01*
X605336Y344804D01*
X605961Y345137D01*
Y343471D01*
G01X603461Y347404D02*
X605961D01*
X605461Y346904D01*
G01X603461D02*
Y347904D01*
G01X605544Y349712D02*
X605794Y349962D01*
X605919Y350254D01*
X605961Y350587D01*
X605878Y351004D01*
X605669Y351296D01*
X605419Y351379D01*
X605169Y351337D01*
X604961Y351171D01*
X604544Y350337D01*
X604253Y349962D01*
X603836Y349712D01*
X603461Y349629D01*
Y351379D01*
G01X613011Y365418D02*
X613261Y365543D01*
X613553Y365626D01*
X613886D01*
X614261Y365501D01*
X614553Y365293D01*
X614761Y365043D01*
X614928Y364626D01*
X614970Y364251D01*
X614886Y363876D01*
X614761Y363626D01*
X614511Y363376D01*
X614220Y363209D01*
X613928Y363126D01*
X613636D01*
X613345Y363209D01*
X613095Y363334D01*
X612886Y363501D01*
G01X610911Y363126D02*
X610828Y363668D01*
X610703Y364126D01*
X610536Y364543D01*
X610328Y365001D01*
X609995Y365626D01*
X611661D01*
G01X608645Y363626D02*
X608395Y363334D01*
X608061Y363168D01*
X607686Y363126D01*
X607353Y363168D01*
X607020Y363376D01*
X606811Y363626D01*
X606770Y363876D01*
X606853Y364168D01*
X607145Y364376D01*
X607436Y364459D01*
X607811D01*
G01X607436D02*
X607186Y364584D01*
X606978Y364793D01*
X606895Y365043D01*
X606978Y365293D01*
X607186Y365501D01*
X607561Y365626D01*
X607936Y365584D01*
X608311Y365418D01*
G01X604628Y363126D02*
Y365626D01*
X605128Y365126D01*
G01Y363126D02*
X604128D01*
G01X577826Y773673D02*
X580326D01*
Y774714D01*
X580201Y775048D01*
X580034Y775256D01*
X579701Y775339D01*
X579368Y775256D01*
X579159Y775006D01*
X579034Y774714D01*
Y773673D01*
G01Y774714D02*
X577826Y775339D01*
G01X578326Y776689D02*
X578034Y776939D01*
X577868Y777273D01*
X577826Y777648D01*
X577868Y777981D01*
X578076Y778314D01*
X578326Y778523D01*
X578576Y778564D01*
X578868Y778481D01*
X579076Y778189D01*
X579159Y777898D01*
Y777523D01*
G01Y777898D02*
X579284Y778148D01*
X579493Y778356D01*
X579743Y778439D01*
X579993Y778356D01*
X580201Y778148D01*
X580326Y777773D01*
X580284Y777398D01*
X580118Y777023D01*
G01X579909Y779914D02*
X580159Y780164D01*
X580284Y780456D01*
X580326Y780789D01*
X580243Y781206D01*
X580034Y781498D01*
X579784Y781581D01*
X579534Y781539D01*
X579326Y781373D01*
X578909Y780539D01*
X578618Y780164D01*
X578201Y779914D01*
X577826Y779831D01*
Y781581D01*
G01X579909Y783014D02*
X580159Y783264D01*
X580284Y783556D01*
X580326Y783889D01*
X580243Y784306D01*
X580034Y784598D01*
X579784Y784681D01*
X579534Y784639D01*
X579326Y784473D01*
X578909Y783639D01*
X578618Y783264D01*
X578201Y783014D01*
X577826Y782931D01*
Y784681D01*
G01Y786906D02*
X580326D01*
X579826Y786406D01*
G01X577826D02*
Y787406D01*
G01X575841Y775165D02*
X575966Y774915D01*
X576049Y774623D01*
Y774290D01*
X575924Y773915D01*
X575716Y773623D01*
X575466Y773415D01*
X575049Y773248D01*
X574674Y773206D01*
X574299Y773290D01*
X574049Y773415D01*
X573799Y773665D01*
X573632Y773956D01*
X573549Y774248D01*
Y774540D01*
X573632Y774831D01*
X573757Y775081D01*
X573924Y775290D01*
G01X574049Y776431D02*
X573757Y776681D01*
X573591Y777015D01*
X573549Y777390D01*
X573591Y777723D01*
X573799Y778056D01*
X574049Y778265D01*
X574299Y778306D01*
X574591Y778223D01*
X574799Y777931D01*
X574882Y777640D01*
Y777265D01*
G01Y777640D02*
X575007Y777890D01*
X575216Y778098D01*
X575466Y778181D01*
X575716Y778098D01*
X575924Y777890D01*
X576049Y777515D01*
X576007Y777140D01*
X575841Y776765D01*
G01X575632Y779656D02*
X575882Y779906D01*
X576007Y780198D01*
X576049Y780531D01*
X575966Y780948D01*
X575757Y781240D01*
X575507Y781323D01*
X575257Y781281D01*
X575049Y781115D01*
X574632Y780281D01*
X574341Y779906D01*
X573924Y779656D01*
X573549Y779573D01*
Y781323D01*
G01X576049Y783548D02*
X575966Y783215D01*
X575757Y782965D01*
X575507Y782798D01*
X575174Y782673D01*
X574799Y782631D01*
X574424Y782673D01*
X574091Y782798D01*
X573841Y782965D01*
X573632Y783215D01*
X573549Y783548D01*
X573632Y783881D01*
X573841Y784131D01*
X574091Y784298D01*
X574424Y784423D01*
X574799Y784465D01*
X575174Y784423D01*
X575507Y784298D01*
X575757Y784131D01*
X575966Y783881D01*
X576049Y783548D01*
G01X573549Y786565D02*
X574091Y786648D01*
X574549Y786773D01*
X574966Y786940D01*
X575424Y787148D01*
X576049Y787481D01*
Y785815D01*
G01X625305Y7833D02*
X624305Y7333D01*
X623138Y7000D01*
X621805D01*
X620304Y7500D01*
X619138Y8333D01*
X618305Y9333D01*
X617638Y11000D01*
X617471Y12500D01*
X617805Y14000D01*
X618305Y15000D01*
X619305Y16000D01*
X620471Y16667D01*
X621638Y17000D01*
X622805D01*
X623971Y16667D01*
X624971Y16167D01*
X625805Y15500D01*
G01X635356Y122053D02*
X637856D01*
Y123094D01*
X637731Y123428D01*
X637564Y123636D01*
X637231Y123719D01*
X636898Y123636D01*
X636689Y123386D01*
X636564Y123094D01*
Y122053D01*
G01Y123094D02*
X635356Y123719D01*
G01X637439Y125194D02*
X637689Y125444D01*
X637814Y125736D01*
X637856Y126069D01*
X637773Y126486D01*
X637564Y126778D01*
X637314Y126861D01*
X637064Y126819D01*
X636856Y126653D01*
X636439Y125819D01*
X636148Y125444D01*
X635731Y125194D01*
X635356Y125111D01*
Y126861D01*
G01X635648Y128378D02*
X635439Y128669D01*
X635356Y129003D01*
X635439Y129336D01*
X635689Y129628D01*
X636064Y129836D01*
X636439Y129919D01*
X636898D01*
X637273Y129836D01*
X637606Y129628D01*
X637773Y129378D01*
X637856Y129086D01*
X637773Y128753D01*
X637606Y128503D01*
X637356Y128336D01*
X637023Y128253D01*
X636731Y128336D01*
X636439Y128544D01*
X636273Y128794D01*
X636231Y129086D01*
X636314Y129419D01*
X636523Y129669D01*
X636898Y129919D01*
G01X635856Y131269D02*
X635564Y131519D01*
X635398Y131853D01*
X635356Y132228D01*
X635398Y132561D01*
X635606Y132894D01*
X635856Y133103D01*
X636106Y133144D01*
X636398Y133061D01*
X636606Y132769D01*
X636689Y132478D01*
Y132103D01*
G01Y132478D02*
X636814Y132728D01*
X637023Y132936D01*
X637273Y133019D01*
X637523Y132936D01*
X637731Y132728D01*
X637856Y132353D01*
X637814Y131978D01*
X637648Y131603D01*
G01X637439Y134494D02*
X637689Y134744D01*
X637814Y135036D01*
X637856Y135369D01*
X637773Y135786D01*
X637564Y136078D01*
X637314Y136161D01*
X637064Y136119D01*
X636856Y135953D01*
X636439Y135119D01*
X636148Y134744D01*
X635731Y134494D01*
X635356Y134411D01*
Y136161D01*
G01X618048Y135944D02*
X622048D01*
Y128544D01*
G01X627722Y122258D02*
X630222D01*
Y123299D01*
X630097Y123633D01*
X629930Y123841D01*
X629597Y123924D01*
X629264Y123841D01*
X629055Y123591D01*
X628930Y123299D01*
Y122258D01*
G01Y123299D02*
X627722Y123924D01*
G01X629805Y125399D02*
X630055Y125649D01*
X630180Y125941D01*
X630222Y126274D01*
X630139Y126691D01*
X629930Y126983D01*
X629680Y127066D01*
X629430Y127024D01*
X629222Y126858D01*
X628805Y126024D01*
X628514Y125649D01*
X628097Y125399D01*
X627722Y125316D01*
Y127066D01*
G01X628014Y128583D02*
X627805Y128874D01*
X627722Y129208D01*
X627805Y129541D01*
X628055Y129833D01*
X628430Y130041D01*
X628805Y130124D01*
X629264D01*
X629639Y130041D01*
X629972Y129833D01*
X630139Y129583D01*
X630222Y129291D01*
X630139Y128958D01*
X629972Y128708D01*
X629722Y128541D01*
X629389Y128458D01*
X629097Y128541D01*
X628805Y128749D01*
X628639Y128999D01*
X628597Y129291D01*
X628680Y129624D01*
X628889Y129874D01*
X629264Y130124D01*
G01X628222Y131474D02*
X627930Y131724D01*
X627764Y132058D01*
X627722Y132433D01*
X627764Y132766D01*
X627972Y133099D01*
X628222Y133308D01*
X628472Y133349D01*
X628764Y133266D01*
X628972Y132974D01*
X629055Y132683D01*
Y132308D01*
G01Y132683D02*
X629180Y132933D01*
X629389Y133141D01*
X629639Y133224D01*
X629889Y133141D01*
X630097Y132933D01*
X630222Y132558D01*
X630180Y132183D01*
X630014Y131808D01*
G01X627722Y135491D02*
X630222D01*
X629722Y134991D01*
G01X627722D02*
Y135991D01*
G01X610026Y135952D02*
X614026D01*
Y128552D01*
G01X622048Y135944D02*
X626048D01*
Y128544D01*
G01X631591Y122197D02*
X634091D01*
Y123238D01*
X633966Y123572D01*
X633799Y123780D01*
X633466Y123863D01*
X633133Y123780D01*
X632924Y123530D01*
X632799Y123238D01*
Y122197D01*
G01Y123238D02*
X631591Y123863D01*
G01X633674Y125338D02*
X633924Y125588D01*
X634049Y125880D01*
X634091Y126213D01*
X634008Y126630D01*
X633799Y126922D01*
X633549Y127005D01*
X633299Y126963D01*
X633091Y126797D01*
X632674Y125963D01*
X632383Y125588D01*
X631966Y125338D01*
X631591Y125255D01*
Y127005D01*
G01X631883Y128522D02*
X631674Y128813D01*
X631591Y129147D01*
X631674Y129480D01*
X631924Y129772D01*
X632299Y129980D01*
X632674Y130063D01*
X633133D01*
X633508Y129980D01*
X633841Y129772D01*
X634008Y129522D01*
X634091Y129230D01*
X634008Y128897D01*
X633841Y128647D01*
X633591Y128480D01*
X633258Y128397D01*
X632966Y128480D01*
X632674Y128688D01*
X632508Y128938D01*
X632466Y129230D01*
X632549Y129563D01*
X632758Y129813D01*
X633133Y130063D01*
G01X633674Y131538D02*
X633924Y131788D01*
X634049Y132080D01*
X634091Y132413D01*
X634008Y132830D01*
X633799Y133122D01*
X633549Y133205D01*
X633299Y133163D01*
X633091Y132997D01*
X632674Y132163D01*
X632383Y131788D01*
X631966Y131538D01*
X631591Y131455D01*
Y133205D01*
G01X632091Y134513D02*
X631799Y134763D01*
X631633Y135097D01*
X631591Y135472D01*
X631633Y135805D01*
X631841Y136138D01*
X632091Y136347D01*
X632341Y136388D01*
X632633Y136305D01*
X632841Y136013D01*
X632924Y135722D01*
Y135347D01*
G01Y135722D02*
X633049Y135972D01*
X633258Y136180D01*
X633508Y136263D01*
X633758Y136180D01*
X633966Y135972D01*
X634091Y135597D01*
X634049Y135222D01*
X633883Y134847D01*
G01X614026Y135952D02*
X618026D01*
Y128552D01*
G01X607803Y117140D02*
X607928Y116890D01*
X608011Y116598D01*
Y116265D01*
X607886Y115890D01*
X607678Y115598D01*
X607428Y115390D01*
X607011Y115223D01*
X606636Y115181D01*
X606261Y115265D01*
X606011Y115390D01*
X605761Y115640D01*
X605594Y115931D01*
X605511Y116223D01*
Y116515D01*
X605594Y116806D01*
X605719Y117056D01*
X605886Y117265D01*
G01X607594Y118531D02*
X607844Y118781D01*
X607969Y119073D01*
X608011Y119406D01*
X607928Y119823D01*
X607719Y120115D01*
X607469Y120198D01*
X607219Y120156D01*
X607011Y119990D01*
X606594Y119156D01*
X606303Y118781D01*
X605886Y118531D01*
X605511Y118448D01*
Y120198D01*
G01X607594Y121631D02*
X607844Y121881D01*
X607969Y122173D01*
X608011Y122506D01*
X607928Y122923D01*
X607719Y123215D01*
X607469Y123298D01*
X607219Y123256D01*
X607011Y123090D01*
X606594Y122256D01*
X606303Y121881D01*
X605886Y121631D01*
X605511Y121548D01*
Y123298D01*
G01X607594Y124731D02*
X607844Y124981D01*
X607969Y125273D01*
X608011Y125606D01*
X607928Y126023D01*
X607719Y126315D01*
X607469Y126398D01*
X607219Y126356D01*
X607011Y126190D01*
X606594Y125356D01*
X606303Y124981D01*
X605886Y124731D01*
X605511Y124648D01*
Y126398D01*
G01X624083Y227565D02*
Y230065D01*
X623083D01*
X622750Y229940D01*
X622500Y229648D01*
X622417Y229315D01*
X622500Y228982D01*
X622708Y228732D01*
X623083Y228607D01*
X624083D01*
G01X619233Y229857D02*
X619483Y229982D01*
X619775Y230065D01*
X620108D01*
X620483Y229940D01*
X620775Y229732D01*
X620983Y229482D01*
X621150Y229065D01*
X621192Y228690D01*
X621108Y228315D01*
X620983Y228065D01*
X620733Y227815D01*
X620442Y227648D01*
X620150Y227565D01*
X619858D01*
X619567Y227648D01*
X619317Y227773D01*
X619108Y227940D01*
G01X617842Y229648D02*
X617592Y229898D01*
X617300Y230023D01*
X616967Y230065D01*
X616550Y229982D01*
X616258Y229773D01*
X616175Y229523D01*
X616217Y229273D01*
X616383Y229065D01*
X617217Y228648D01*
X617592Y228357D01*
X617842Y227940D01*
X617925Y227565D01*
X616175D01*
G01X613950Y230065D02*
X614283Y229982D01*
X614533Y229773D01*
X614700Y229523D01*
X614825Y229190D01*
X614867Y228815D01*
X614825Y228440D01*
X614700Y228107D01*
X614533Y227857D01*
X614283Y227648D01*
X613950Y227565D01*
X613617Y227648D01*
X613367Y227857D01*
X613200Y228107D01*
X613075Y228440D01*
X613033Y228815D01*
X613075Y229190D01*
X613200Y229523D01*
X613367Y229773D01*
X613617Y229982D01*
X613950Y230065D01*
G01X610850D02*
X611183Y229982D01*
X611433Y229773D01*
X611600Y229523D01*
X611725Y229190D01*
X611767Y228815D01*
X611725Y228440D01*
X611600Y228107D01*
X611433Y227857D01*
X611183Y227648D01*
X610850Y227565D01*
X610517Y227648D01*
X610267Y227857D01*
X610100Y228107D01*
X609975Y228440D01*
X609933Y228815D01*
X609975Y229190D01*
X610100Y229523D01*
X610267Y229773D01*
X610517Y229982D01*
X610850Y230065D01*
G01X632996Y241708D02*
Y244208D01*
X631996D01*
X631663Y244083D01*
X631413Y243791D01*
X631330Y243458D01*
X631413Y243125D01*
X631621Y242875D01*
X631996Y242750D01*
X632996D01*
G01X629896Y241708D02*
Y244208D01*
X628855D01*
X628521Y244083D01*
X628313Y243916D01*
X628230Y243583D01*
X628313Y243250D01*
X628563Y243041D01*
X628855Y242916D01*
X629896D01*
G01X628855D02*
X628230Y241708D01*
G01X625963D02*
Y244208D01*
X626463Y243708D01*
G01Y241708D02*
X625463D01*
G01X623780Y242083D02*
X623530Y241875D01*
X623238Y241750D01*
X622863Y241708D01*
X622488Y241791D01*
X622196Y241958D01*
X621988Y242250D01*
X621946Y242583D01*
X622030Y242916D01*
X622238Y243125D01*
X622530Y243291D01*
X622821Y243333D01*
X623113Y243291D01*
X623488Y243125D01*
X623363Y244208D01*
X622238D01*
G01X620471Y242000D02*
X620180Y241791D01*
X619846Y241708D01*
X619513Y241791D01*
X619221Y242041D01*
X619013Y242416D01*
X618930Y242791D01*
Y243250D01*
X619013Y243625D01*
X619221Y243958D01*
X619471Y244125D01*
X619763Y244208D01*
X620096Y244125D01*
X620346Y243958D01*
X620513Y243708D01*
X620596Y243375D01*
X620513Y243083D01*
X620305Y242791D01*
X620055Y242625D01*
X619763Y242583D01*
X619430Y242666D01*
X619180Y242875D01*
X618930Y243250D01*
G01X640209Y259722D02*
Y262222D01*
X639209D01*
X638876Y262097D01*
X638626Y261805D01*
X638543Y261472D01*
X638626Y261139D01*
X638834Y260889D01*
X639209Y260764D01*
X640209D01*
G01X637109Y259722D02*
Y262222D01*
X636068D01*
X635734Y262097D01*
X635526Y261930D01*
X635443Y261597D01*
X635526Y261264D01*
X635776Y261055D01*
X636068Y260930D01*
X637109D01*
G01X636068D02*
X635443Y259722D01*
G01X633176D02*
Y262222D01*
X633676Y261722D01*
G01Y259722D02*
X632676D01*
G01X630868Y260764D02*
X630576Y261055D01*
X630326Y261222D01*
X629993Y261305D01*
X629701Y261222D01*
X629493Y261055D01*
X629326Y260805D01*
X629284Y260514D01*
X629326Y260264D01*
X629493Y260014D01*
X629743Y259805D01*
X630034Y259722D01*
X630368Y259805D01*
X630659Y260055D01*
X630826Y260430D01*
X630868Y260847D01*
X630784Y261389D01*
X630659Y261680D01*
X630451Y261972D01*
X630159Y262180D01*
X629868Y262222D01*
X629576Y262139D01*
X629368Y261930D01*
G01X627768Y260764D02*
X627476Y261055D01*
X627226Y261222D01*
X626893Y261305D01*
X626601Y261222D01*
X626393Y261055D01*
X626226Y260805D01*
X626184Y260514D01*
X626226Y260264D01*
X626393Y260014D01*
X626643Y259805D01*
X626934Y259722D01*
X627268Y259805D01*
X627559Y260055D01*
X627726Y260430D01*
X627768Y260847D01*
X627684Y261389D01*
X627559Y261680D01*
X627351Y261972D01*
X627059Y262180D01*
X626768Y262222D01*
X626476Y262139D01*
X626268Y261930D01*
G01X624763Y251108D02*
X618363D01*
G01D02*
Y258108D01*
G01D02*
X627063D01*
G01X631763D02*
Y251108D01*
G01D02*
X623963D01*
G01X631763Y258108D02*
X626563D01*
G01X624127Y259457D02*
Y261957D01*
X623127D01*
X622794Y261832D01*
X622544Y261540D01*
X622461Y261207D01*
X622544Y260874D01*
X622752Y260624D01*
X623127Y260499D01*
X624127D01*
G01X619277Y261749D02*
X619527Y261874D01*
X619819Y261957D01*
X620152D01*
X620527Y261832D01*
X620819Y261624D01*
X621027Y261374D01*
X621194Y260957D01*
X621236Y260582D01*
X621152Y260207D01*
X621027Y259957D01*
X620777Y259707D01*
X620486Y259540D01*
X620194Y259457D01*
X619902D01*
X619611Y259540D01*
X619361Y259665D01*
X619152Y259832D01*
G01X617886Y261540D02*
X617636Y261790D01*
X617344Y261915D01*
X617011Y261957D01*
X616594Y261874D01*
X616302Y261665D01*
X616219Y261415D01*
X616261Y261165D01*
X616427Y260957D01*
X617261Y260540D01*
X617636Y260249D01*
X617886Y259832D01*
X617969Y259457D01*
X616219D01*
G01X613994Y261957D02*
X614327Y261874D01*
X614577Y261665D01*
X614744Y261415D01*
X614869Y261082D01*
X614911Y260707D01*
X614869Y260332D01*
X614744Y259999D01*
X614577Y259749D01*
X614327Y259540D01*
X613994Y259457D01*
X613661Y259540D01*
X613411Y259749D01*
X613244Y259999D01*
X613119Y260332D01*
X613077Y260707D01*
X613119Y261082D01*
X613244Y261415D01*
X613411Y261665D01*
X613661Y261874D01*
X613994Y261957D01*
G01X610977Y259457D02*
X610894Y259999D01*
X610769Y260457D01*
X610602Y260874D01*
X610394Y261332D01*
X610061Y261957D01*
X611727D01*
G01X615414Y341721D02*
X615539Y341471D01*
X615622Y341179D01*
Y340846D01*
X615497Y340471D01*
X615289Y340179D01*
X615039Y339971D01*
X614622Y339804D01*
X614247Y339762D01*
X613872Y339846D01*
X613622Y339971D01*
X613372Y340221D01*
X613205Y340512D01*
X613122Y340804D01*
Y341096D01*
X613205Y341387D01*
X613330Y341637D01*
X613497Y341846D01*
G01X613122Y343821D02*
X613664Y343904D01*
X614122Y344029D01*
X614539Y344196D01*
X614997Y344404D01*
X615622Y344737D01*
Y343071D01*
G01X613122Y347004D02*
X615622D01*
X615122Y346504D01*
G01X613122D02*
Y347504D01*
G01Y350104D02*
X613164Y350396D01*
X613289Y350729D01*
X613497Y350937D01*
X613789Y351021D01*
X614080Y350937D01*
X614330Y350687D01*
X614455Y350312D01*
Y349896D01*
X614539Y349646D01*
X614747Y349437D01*
X615039Y349354D01*
X615330Y349479D01*
X615539Y349771D01*
X615622Y350104D01*
X615539Y350437D01*
X615330Y350729D01*
X615039Y350854D01*
X614747Y350771D01*
X614539Y350562D01*
X614455Y350312D01*
Y349896D01*
X614330Y349521D01*
X614080Y349271D01*
X613789Y349187D01*
X613497Y349271D01*
X613289Y349479D01*
X613164Y349812D01*
X613122Y350104D01*
G01X610414Y341721D02*
X610539Y341471D01*
X610622Y341179D01*
Y340846D01*
X610497Y340471D01*
X610289Y340179D01*
X610039Y339971D01*
X609622Y339804D01*
X609247Y339762D01*
X608872Y339846D01*
X608622Y339971D01*
X608372Y340221D01*
X608205Y340512D01*
X608122Y340804D01*
Y341096D01*
X608205Y341387D01*
X608330Y341637D01*
X608497Y341846D01*
G01X608122Y343821D02*
X608664Y343904D01*
X609122Y344029D01*
X609539Y344196D01*
X609997Y344404D01*
X610622Y344737D01*
Y343071D01*
G01X608122Y347004D02*
X610622D01*
X610122Y346504D01*
G01X608122D02*
Y347504D01*
G01X608497Y349187D02*
X608289Y349437D01*
X608164Y349729D01*
X608122Y350104D01*
X608205Y350479D01*
X608372Y350771D01*
X608664Y350979D01*
X608997Y351021D01*
X609330Y350937D01*
X609539Y350729D01*
X609705Y350437D01*
X609747Y350146D01*
X609705Y349854D01*
X609539Y349479D01*
X610622Y349604D01*
Y350729D01*
G01X620253Y341621D02*
X620378Y341371D01*
X620461Y341079D01*
Y340746D01*
X620336Y340371D01*
X620128Y340079D01*
X619878Y339871D01*
X619461Y339704D01*
X619086Y339662D01*
X618711Y339746D01*
X618461Y339871D01*
X618211Y340121D01*
X618044Y340412D01*
X617961Y340704D01*
Y340996D01*
X618044Y341287D01*
X618169Y341537D01*
X618336Y341746D01*
G01X617961Y343721D02*
X618503Y343804D01*
X618961Y343929D01*
X619378Y344096D01*
X619836Y344304D01*
X620461Y344637D01*
Y342971D01*
G01X617961Y346904D02*
X620461D01*
X619961Y346404D01*
G01X617961D02*
Y347404D01*
G01X618461Y349087D02*
X618169Y349337D01*
X618003Y349671D01*
X617961Y350046D01*
X618003Y350379D01*
X618211Y350712D01*
X618461Y350921D01*
X618711Y350962D01*
X619003Y350879D01*
X619211Y350587D01*
X619294Y350296D01*
Y349921D01*
G01Y350296D02*
X619419Y350546D01*
X619628Y350754D01*
X619878Y350837D01*
X620128Y350754D01*
X620336Y350546D01*
X620461Y350171D01*
X620419Y349796D01*
X620253Y349421D01*
G01X633899Y371942D02*
X634024Y371692D01*
X634107Y371400D01*
Y371067D01*
X633982Y370692D01*
X633774Y370400D01*
X633524Y370192D01*
X633107Y370025D01*
X632732Y369983D01*
X632357Y370067D01*
X632107Y370192D01*
X631857Y370442D01*
X631690Y370733D01*
X631607Y371025D01*
Y371317D01*
X631690Y371608D01*
X631815Y371858D01*
X631982Y372067D01*
G01X631607Y374042D02*
X632149Y374125D01*
X632607Y374250D01*
X633024Y374417D01*
X633482Y374625D01*
X634107Y374958D01*
Y373292D01*
G01X631607Y377225D02*
X634107D01*
X633607Y376725D01*
G01X631607D02*
Y377725D01*
G01Y380242D02*
X632149Y380325D01*
X632607Y380450D01*
X633024Y380617D01*
X633482Y380825D01*
X634107Y381158D01*
Y379492D01*
G01X613733Y355553D02*
X613983Y355678D01*
X614275Y355761D01*
X614608D01*
X614983Y355636D01*
X615275Y355428D01*
X615483Y355178D01*
X615650Y354761D01*
X615692Y354386D01*
X615608Y354011D01*
X615483Y353761D01*
X615233Y353511D01*
X614942Y353344D01*
X614650Y353261D01*
X614358D01*
X614067Y353344D01*
X613817Y353469D01*
X613608Y353636D01*
G01X611633Y353261D02*
X611550Y353803D01*
X611425Y354261D01*
X611258Y354678D01*
X611050Y355136D01*
X610717Y355761D01*
X612383D01*
G01X608450Y353261D02*
Y355761D01*
X608950Y355261D01*
G01Y353261D02*
X607950D01*
G01X606142Y354303D02*
X605850Y354594D01*
X605600Y354761D01*
X605267Y354844D01*
X604975Y354761D01*
X604767Y354594D01*
X604600Y354344D01*
X604558Y354053D01*
X604600Y353803D01*
X604767Y353553D01*
X605017Y353344D01*
X605308Y353261D01*
X605642Y353344D01*
X605933Y353594D01*
X606100Y353969D01*
X606142Y354386D01*
X606058Y354928D01*
X605933Y355219D01*
X605725Y355511D01*
X605433Y355719D01*
X605142Y355761D01*
X604850Y355678D01*
X604642Y355469D01*
G01X637899Y371942D02*
X638024Y371692D01*
X638107Y371400D01*
Y371067D01*
X637982Y370692D01*
X637774Y370400D01*
X637524Y370192D01*
X637107Y370025D01*
X636732Y369983D01*
X636357Y370067D01*
X636107Y370192D01*
X635857Y370442D01*
X635690Y370733D01*
X635607Y371025D01*
Y371317D01*
X635690Y371608D01*
X635815Y371858D01*
X635982Y372067D01*
G01X635607Y374042D02*
X636149Y374125D01*
X636607Y374250D01*
X637024Y374417D01*
X637482Y374625D01*
X638107Y374958D01*
Y373292D01*
G01X635607Y377225D02*
X638107D01*
X637607Y376725D01*
G01X635607D02*
Y377725D01*
G01Y380825D02*
X638107D01*
X636315Y379283D01*
Y381367D01*
G01X662971Y17000D02*
Y7000D01*
X666305D01*
X667638Y7500D01*
X668638Y8167D01*
X669471Y9167D01*
X670138Y10334D01*
X670305Y12000D01*
X670138Y13667D01*
X669471Y14833D01*
X668638Y15834D01*
X667638Y16500D01*
X666305Y17000D01*
X662971D01*
G01X657500Y135700D02*
X661500D01*
Y128300D01*
G01X667780Y122433D02*
X670280D01*
Y123474D01*
X670155Y123808D01*
X669988Y124016D01*
X669655Y124099D01*
X669322Y124016D01*
X669113Y123766D01*
X668988Y123474D01*
Y122433D01*
G01Y123474D02*
X667780Y124099D01*
G01X669863Y125574D02*
X670113Y125824D01*
X670238Y126116D01*
X670280Y126449D01*
X670197Y126866D01*
X669988Y127158D01*
X669738Y127241D01*
X669488Y127199D01*
X669280Y127033D01*
X668863Y126199D01*
X668572Y125824D01*
X668155Y125574D01*
X667780Y125491D01*
Y127241D01*
G01X668072Y128758D02*
X667863Y129049D01*
X667780Y129383D01*
X667863Y129716D01*
X668113Y130008D01*
X668488Y130216D01*
X668863Y130299D01*
X669322D01*
X669697Y130216D01*
X670030Y130008D01*
X670197Y129758D01*
X670280Y129466D01*
X670197Y129133D01*
X670030Y128883D01*
X669780Y128716D01*
X669447Y128633D01*
X669155Y128716D01*
X668863Y128924D01*
X668697Y129174D01*
X668655Y129466D01*
X668738Y129799D01*
X668947Y130049D01*
X669322Y130299D01*
G01X669863Y131774D02*
X670113Y132024D01*
X670238Y132316D01*
X670280Y132649D01*
X670197Y133066D01*
X669988Y133358D01*
X669738Y133441D01*
X669488Y133399D01*
X669280Y133233D01*
X668863Y132399D01*
X668572Y132024D01*
X668155Y131774D01*
X667780Y131691D01*
Y133441D01*
G01X668072Y134958D02*
X667863Y135249D01*
X667780Y135583D01*
X667863Y135916D01*
X668113Y136208D01*
X668488Y136416D01*
X668863Y136499D01*
X669322D01*
X669697Y136416D01*
X670030Y136208D01*
X670197Y135958D01*
X670280Y135666D01*
X670197Y135333D01*
X670030Y135083D01*
X669780Y134916D01*
X669447Y134833D01*
X669155Y134916D01*
X668863Y135124D01*
X668697Y135374D01*
X668655Y135666D01*
X668738Y135999D01*
X668947Y136249D01*
X669322Y136499D01*
G01X648500Y135700D02*
X652500D01*
Y128300D01*
G01X653000Y135700D02*
X657000D01*
Y128300D01*
G01X663280Y122433D02*
X665780D01*
Y123474D01*
X665655Y123808D01*
X665488Y124016D01*
X665155Y124099D01*
X664822Y124016D01*
X664613Y123766D01*
X664488Y123474D01*
Y122433D01*
G01Y123474D02*
X663280Y124099D01*
G01X665363Y125574D02*
X665613Y125824D01*
X665738Y126116D01*
X665780Y126449D01*
X665697Y126866D01*
X665488Y127158D01*
X665238Y127241D01*
X664988Y127199D01*
X664780Y127033D01*
X664363Y126199D01*
X664072Y125824D01*
X663655Y125574D01*
X663280Y125491D01*
Y127241D01*
G01X663572Y128758D02*
X663363Y129049D01*
X663280Y129383D01*
X663363Y129716D01*
X663613Y130008D01*
X663988Y130216D01*
X664363Y130299D01*
X664822D01*
X665197Y130216D01*
X665530Y130008D01*
X665697Y129758D01*
X665780Y129466D01*
X665697Y129133D01*
X665530Y128883D01*
X665280Y128716D01*
X664947Y128633D01*
X664655Y128716D01*
X664363Y128924D01*
X664197Y129174D01*
X664155Y129466D01*
X664238Y129799D01*
X664447Y130049D01*
X664822Y130299D01*
G01X665363Y131774D02*
X665613Y132024D01*
X665738Y132316D01*
X665780Y132649D01*
X665697Y133066D01*
X665488Y133358D01*
X665238Y133441D01*
X664988Y133399D01*
X664780Y133233D01*
X664363Y132399D01*
X664072Y132024D01*
X663655Y131774D01*
X663280Y131691D01*
Y133441D01*
G01Y135666D02*
X665780D01*
X665280Y135166D01*
G01X663280D02*
Y136166D01*
G01X644000Y135700D02*
X648000D01*
Y128300D01*
G01X638995Y122153D02*
X641495D01*
Y123194D01*
X641370Y123528D01*
X641203Y123736D01*
X640870Y123819D01*
X640537Y123736D01*
X640328Y123486D01*
X640203Y123194D01*
Y122153D01*
G01Y123194D02*
X638995Y123819D01*
G01X641078Y125294D02*
X641328Y125544D01*
X641453Y125836D01*
X641495Y126169D01*
X641412Y126586D01*
X641203Y126878D01*
X640953Y126961D01*
X640703Y126919D01*
X640495Y126753D01*
X640078Y125919D01*
X639787Y125544D01*
X639370Y125294D01*
X638995Y125211D01*
Y126961D01*
G01X639287Y128478D02*
X639078Y128769D01*
X638995Y129103D01*
X639078Y129436D01*
X639328Y129728D01*
X639703Y129936D01*
X640078Y130019D01*
X640537D01*
X640912Y129936D01*
X641245Y129728D01*
X641412Y129478D01*
X641495Y129186D01*
X641412Y128853D01*
X641245Y128603D01*
X640995Y128436D01*
X640662Y128353D01*
X640370Y128436D01*
X640078Y128644D01*
X639912Y128894D01*
X639870Y129186D01*
X639953Y129519D01*
X640162Y129769D01*
X640537Y130019D01*
G01X641078Y131494D02*
X641328Y131744D01*
X641453Y132036D01*
X641495Y132369D01*
X641412Y132786D01*
X641203Y133078D01*
X640953Y133161D01*
X640703Y133119D01*
X640495Y132953D01*
X640078Y132119D01*
X639787Y131744D01*
X639370Y131494D01*
X638995Y131411D01*
Y133161D01*
G01Y135886D02*
X641495D01*
X639703Y134344D01*
Y136428D01*
G01X648624Y230575D02*
X651124D01*
Y231575D01*
X650999Y231908D01*
X650707Y232158D01*
X650374Y232241D01*
X650041Y232158D01*
X649791Y231950D01*
X649666Y231575D01*
Y230575D01*
G01X648624Y233675D02*
X651124D01*
Y234716D01*
X650999Y235050D01*
X650832Y235258D01*
X650499Y235341D01*
X650166Y235258D01*
X649957Y235008D01*
X649832Y234716D01*
Y233675D01*
G01Y234716D02*
X648624Y235341D01*
G01Y237608D02*
X651124D01*
X650624Y237108D01*
G01X648624D02*
Y238108D01*
G01Y240625D02*
X649166Y240708D01*
X649624Y240833D01*
X650041Y241000D01*
X650499Y241208D01*
X651124Y241541D01*
Y239875D01*
G01X648624Y244308D02*
X651124D01*
X649332Y242766D01*
Y244850D01*
G01X639963Y240308D02*
X643963D01*
Y232908D01*
G01X655263Y230975D02*
X657763D01*
Y231975D01*
X657638Y232308D01*
X657346Y232558D01*
X657013Y232641D01*
X656680Y232558D01*
X656430Y232350D01*
X656305Y231975D01*
Y230975D01*
G01X657555Y235825D02*
X657680Y235575D01*
X657763Y235283D01*
Y234950D01*
X657638Y234575D01*
X657430Y234283D01*
X657180Y234075D01*
X656763Y233908D01*
X656388Y233866D01*
X656013Y233950D01*
X655763Y234075D01*
X655513Y234325D01*
X655346Y234616D01*
X655263Y234908D01*
Y235200D01*
X655346Y235491D01*
X655471Y235741D01*
X655638Y235950D01*
G01X657346Y237216D02*
X657596Y237466D01*
X657721Y237758D01*
X657763Y238091D01*
X657680Y238508D01*
X657471Y238800D01*
X657221Y238883D01*
X656971Y238841D01*
X656763Y238675D01*
X656346Y237841D01*
X656055Y237466D01*
X655638Y237216D01*
X655263Y237133D01*
Y238883D01*
G01X657763Y241108D02*
X657680Y240775D01*
X657471Y240525D01*
X657221Y240358D01*
X656888Y240233D01*
X656513Y240191D01*
X656138Y240233D01*
X655805Y240358D01*
X655555Y240525D01*
X655346Y240775D01*
X655263Y241108D01*
X655346Y241441D01*
X655555Y241691D01*
X655805Y241858D01*
X656138Y241983D01*
X656513Y242025D01*
X656888Y241983D01*
X657221Y241858D01*
X657471Y241691D01*
X657680Y241441D01*
X657763Y241108D01*
G01X655263Y244208D02*
X655305Y244500D01*
X655430Y244833D01*
X655638Y245041D01*
X655930Y245125D01*
X656221Y245041D01*
X656471Y244791D01*
X656596Y244416D01*
Y244000D01*
X656680Y243750D01*
X656888Y243541D01*
X657180Y243458D01*
X657471Y243583D01*
X657680Y243875D01*
X657763Y244208D01*
X657680Y244541D01*
X657471Y244833D01*
X657180Y244958D01*
X656888Y244875D01*
X656680Y244666D01*
X656596Y244416D01*
Y244000D01*
X656471Y243625D01*
X656221Y243375D01*
X655930Y243291D01*
X655638Y243375D01*
X655430Y243583D01*
X655305Y243916D01*
X655263Y244208D01*
G01X644863Y247875D02*
X647363D01*
Y248875D01*
X647238Y249208D01*
X646946Y249458D01*
X646613Y249541D01*
X646280Y249458D01*
X646030Y249250D01*
X645905Y248875D01*
Y247875D01*
G01X647155Y252725D02*
X647280Y252475D01*
X647363Y252183D01*
Y251850D01*
X647238Y251475D01*
X647030Y251183D01*
X646780Y250975D01*
X646363Y250808D01*
X645988Y250766D01*
X645613Y250850D01*
X645363Y250975D01*
X645113Y251225D01*
X644946Y251516D01*
X644863Y251808D01*
Y252100D01*
X644946Y252391D01*
X645071Y252641D01*
X645238Y252850D01*
G01X646946Y254116D02*
X647196Y254366D01*
X647321Y254658D01*
X647363Y254991D01*
X647280Y255408D01*
X647071Y255700D01*
X646821Y255783D01*
X646571Y255741D01*
X646363Y255575D01*
X645946Y254741D01*
X645655Y254366D01*
X645238Y254116D01*
X644863Y254033D01*
Y255783D01*
G01X647363Y258008D02*
X647280Y257675D01*
X647071Y257425D01*
X646821Y257258D01*
X646488Y257133D01*
X646113Y257091D01*
X645738Y257133D01*
X645405Y257258D01*
X645155Y257425D01*
X644946Y257675D01*
X644863Y258008D01*
X644946Y258341D01*
X645155Y258591D01*
X645405Y258758D01*
X645738Y258883D01*
X646113Y258925D01*
X646488Y258883D01*
X646821Y258758D01*
X647071Y258591D01*
X647280Y258341D01*
X647363Y258008D01*
G01X645155Y260400D02*
X644946Y260691D01*
X644863Y261025D01*
X644946Y261358D01*
X645196Y261650D01*
X645571Y261858D01*
X645946Y261941D01*
X646405D01*
X646780Y261858D01*
X647113Y261650D01*
X647280Y261400D01*
X647363Y261108D01*
X647280Y260775D01*
X647113Y260525D01*
X646863Y260358D01*
X646530Y260275D01*
X646238Y260358D01*
X645946Y260566D01*
X645780Y260816D01*
X645738Y261108D01*
X645821Y261441D01*
X646030Y261691D01*
X646405Y261941D01*
G01X659824Y247875D02*
X662324D01*
Y248875D01*
X662199Y249208D01*
X661907Y249458D01*
X661574Y249541D01*
X661241Y249458D01*
X660991Y249250D01*
X660866Y248875D01*
Y247875D01*
G01X662116Y252725D02*
X662241Y252475D01*
X662324Y252183D01*
Y251850D01*
X662199Y251475D01*
X661991Y251183D01*
X661741Y250975D01*
X661324Y250808D01*
X660949Y250766D01*
X660574Y250850D01*
X660324Y250975D01*
X660074Y251225D01*
X659907Y251516D01*
X659824Y251808D01*
Y252100D01*
X659907Y252391D01*
X660032Y252641D01*
X660199Y252850D01*
G01X661907Y254116D02*
X662157Y254366D01*
X662282Y254658D01*
X662324Y254991D01*
X662241Y255408D01*
X662032Y255700D01*
X661782Y255783D01*
X661532Y255741D01*
X661324Y255575D01*
X660907Y254741D01*
X660616Y254366D01*
X660199Y254116D01*
X659824Y254033D01*
Y255783D01*
G01X662324Y258008D02*
X662241Y257675D01*
X662032Y257425D01*
X661782Y257258D01*
X661449Y257133D01*
X661074Y257091D01*
X660699Y257133D01*
X660366Y257258D01*
X660116Y257425D01*
X659907Y257675D01*
X659824Y258008D01*
X659907Y258341D01*
X660116Y258591D01*
X660366Y258758D01*
X660699Y258883D01*
X661074Y258925D01*
X661449Y258883D01*
X661782Y258758D01*
X662032Y258591D01*
X662241Y258341D01*
X662324Y258008D01*
G01X660199Y260191D02*
X659991Y260441D01*
X659866Y260733D01*
X659824Y261108D01*
X659907Y261483D01*
X660074Y261775D01*
X660366Y261983D01*
X660699Y262025D01*
X661032Y261941D01*
X661241Y261733D01*
X661407Y261441D01*
X661449Y261150D01*
X661407Y260858D01*
X661241Y260483D01*
X662324Y260608D01*
Y261733D01*
G01X649824Y247875D02*
X652324D01*
Y248875D01*
X652199Y249208D01*
X651907Y249458D01*
X651574Y249541D01*
X651241Y249458D01*
X650991Y249250D01*
X650866Y248875D01*
Y247875D01*
G01X652116Y252725D02*
X652241Y252475D01*
X652324Y252183D01*
Y251850D01*
X652199Y251475D01*
X651991Y251183D01*
X651741Y250975D01*
X651324Y250808D01*
X650949Y250766D01*
X650574Y250850D01*
X650324Y250975D01*
X650074Y251225D01*
X649907Y251516D01*
X649824Y251808D01*
Y252100D01*
X649907Y252391D01*
X650032Y252641D01*
X650199Y252850D01*
G01X651907Y254116D02*
X652157Y254366D01*
X652282Y254658D01*
X652324Y254991D01*
X652241Y255408D01*
X652032Y255700D01*
X651782Y255783D01*
X651532Y255741D01*
X651324Y255575D01*
X650907Y254741D01*
X650616Y254366D01*
X650199Y254116D01*
X649824Y254033D01*
Y255783D01*
G01X652324Y258008D02*
X652241Y257675D01*
X652032Y257425D01*
X651782Y257258D01*
X651449Y257133D01*
X651074Y257091D01*
X650699Y257133D01*
X650366Y257258D01*
X650116Y257425D01*
X649907Y257675D01*
X649824Y258008D01*
X649907Y258341D01*
X650116Y258591D01*
X650366Y258758D01*
X650699Y258883D01*
X651074Y258925D01*
X651449Y258883D01*
X651782Y258758D01*
X652032Y258591D01*
X652241Y258341D01*
X652324Y258008D01*
G01X651907Y260316D02*
X652157Y260566D01*
X652282Y260858D01*
X652324Y261191D01*
X652241Y261608D01*
X652032Y261900D01*
X651782Y261983D01*
X651532Y261941D01*
X651324Y261775D01*
X650907Y260941D01*
X650616Y260566D01*
X650199Y260316D01*
X649824Y260233D01*
Y261983D01*
G01X654824Y247875D02*
X657324D01*
Y248875D01*
X657199Y249208D01*
X656907Y249458D01*
X656574Y249541D01*
X656241Y249458D01*
X655991Y249250D01*
X655866Y248875D01*
Y247875D01*
G01X657116Y252725D02*
X657241Y252475D01*
X657324Y252183D01*
Y251850D01*
X657199Y251475D01*
X656991Y251183D01*
X656741Y250975D01*
X656324Y250808D01*
X655949Y250766D01*
X655574Y250850D01*
X655324Y250975D01*
X655074Y251225D01*
X654907Y251516D01*
X654824Y251808D01*
Y252100D01*
X654907Y252391D01*
X655032Y252641D01*
X655199Y252850D01*
G01X654824Y254908D02*
X657324D01*
X656824Y254408D01*
G01X654824D02*
Y255408D01*
G01X655116Y257300D02*
X654907Y257591D01*
X654824Y257925D01*
X654907Y258258D01*
X655157Y258550D01*
X655532Y258758D01*
X655907Y258841D01*
X656366D01*
X656741Y258758D01*
X657074Y258550D01*
X657241Y258300D01*
X657324Y258008D01*
X657241Y257675D01*
X657074Y257425D01*
X656824Y257258D01*
X656491Y257175D01*
X656199Y257258D01*
X655907Y257466D01*
X655741Y257716D01*
X655699Y258008D01*
X655782Y258341D01*
X655991Y258591D01*
X656366Y258841D01*
G01X654824Y261608D02*
X657324D01*
X655532Y260066D01*
Y262150D01*
G01X671216Y276702D02*
X673716D01*
Y277702D01*
X673591Y278035D01*
X673299Y278285D01*
X672966Y278368D01*
X672633Y278285D01*
X672383Y278077D01*
X672258Y277702D01*
Y276702D01*
G01X672466Y280885D02*
Y281718D01*
X671716D01*
X671466Y281468D01*
X671299Y281177D01*
X671216Y280760D01*
X671299Y280343D01*
X671466Y280052D01*
X671716Y279802D01*
X672008Y279635D01*
X672341Y279552D01*
X672633D01*
X672883Y279635D01*
X673174Y279802D01*
X673424Y280052D01*
X673591Y280302D01*
X673716Y280635D01*
Y280927D01*
X673633Y281260D01*
X673466Y281510D01*
G01X671716Y282818D02*
X671424Y283068D01*
X671258Y283402D01*
X671216Y283777D01*
X671258Y284110D01*
X671466Y284443D01*
X671716Y284652D01*
X671966Y284693D01*
X672258Y284610D01*
X672466Y284318D01*
X672549Y284027D01*
Y283652D01*
G01Y284027D02*
X672674Y284277D01*
X672883Y284485D01*
X673133Y284568D01*
X673383Y284485D01*
X673591Y284277D01*
X673716Y283902D01*
X673674Y283527D01*
X673508Y283152D01*
G01X671216Y287335D02*
X673716D01*
X671924Y285793D01*
Y287877D01*
G01X651233Y347292D02*
X651483Y347417D01*
X651775Y347500D01*
X652108D01*
X652483Y347375D01*
X652775Y347167D01*
X652983Y346917D01*
X653150Y346500D01*
X653192Y346125D01*
X653108Y345750D01*
X652983Y345500D01*
X652733Y345250D01*
X652442Y345083D01*
X652150Y345000D01*
X651858D01*
X651567Y345083D01*
X651317Y345208D01*
X651108Y345375D01*
G01X649133Y345000D02*
X649050Y345542D01*
X648925Y346000D01*
X648758Y346417D01*
X648550Y346875D01*
X648217Y347500D01*
X649883D01*
G01X646742Y347083D02*
X646492Y347333D01*
X646200Y347458D01*
X645867Y347500D01*
X645450Y347417D01*
X645158Y347208D01*
X645075Y346958D01*
X645117Y346708D01*
X645283Y346500D01*
X646117Y346083D01*
X646492Y345792D01*
X646742Y345375D01*
X646825Y345000D01*
X645075D01*
G01X642850D02*
Y347500D01*
X643350Y347000D01*
G01Y345000D02*
X642350D01*
G01X651233Y352053D02*
X651483Y352178D01*
X651775Y352261D01*
X652108D01*
X652483Y352136D01*
X652775Y351928D01*
X652983Y351678D01*
X653150Y351261D01*
X653192Y350886D01*
X653108Y350511D01*
X652983Y350261D01*
X652733Y350011D01*
X652442Y349844D01*
X652150Y349761D01*
X651858D01*
X651567Y349844D01*
X651317Y349969D01*
X651108Y350136D01*
G01X649133Y349761D02*
X649050Y350303D01*
X648925Y350761D01*
X648758Y351178D01*
X648550Y351636D01*
X648217Y352261D01*
X649883D01*
G01X646742Y351844D02*
X646492Y352094D01*
X646200Y352219D01*
X645867Y352261D01*
X645450Y352178D01*
X645158Y351969D01*
X645075Y351719D01*
X645117Y351469D01*
X645283Y351261D01*
X646117Y350844D01*
X646492Y350553D01*
X646742Y350136D01*
X646825Y349761D01*
X645075D01*
G01X642850Y352261D02*
X643183Y352178D01*
X643433Y351969D01*
X643600Y351719D01*
X643725Y351386D01*
X643767Y351011D01*
X643725Y350636D01*
X643600Y350303D01*
X643433Y350053D01*
X643183Y349844D01*
X642850Y349761D01*
X642517Y349844D01*
X642267Y350053D01*
X642100Y350303D01*
X641975Y350636D01*
X641933Y351011D01*
X641975Y351386D01*
X642100Y351719D01*
X642267Y351969D01*
X642517Y352178D01*
X642850Y352261D01*
G01X654935Y796480D02*
X655185Y796605D01*
X655477Y796688D01*
X655810D01*
X656185Y796563D01*
X656477Y796355D01*
X656685Y796105D01*
X656852Y795688D01*
X656894Y795313D01*
X656810Y794938D01*
X656685Y794688D01*
X656435Y794438D01*
X656144Y794271D01*
X655852Y794188D01*
X655560D01*
X655269Y794271D01*
X655019Y794396D01*
X654810Y794563D01*
G01X652252Y794188D02*
Y796688D01*
X653794Y794896D01*
X651710D01*
G01X649652Y794188D02*
Y796688D01*
X650152Y796188D01*
G01Y794188D02*
X649152D01*
G01X646552D02*
Y796688D01*
X647052Y796188D01*
G01Y794188D02*
X646052D01*
G01X644244Y795230D02*
X643952Y795521D01*
X643702Y795688D01*
X643369Y795771D01*
X643077Y795688D01*
X642869Y795521D01*
X642702Y795271D01*
X642660Y794980D01*
X642702Y794730D01*
X642869Y794480D01*
X643119Y794271D01*
X643410Y794188D01*
X643744Y794271D01*
X644035Y794521D01*
X644202Y794896D01*
X644244Y795313D01*
X644160Y795855D01*
X644035Y796146D01*
X643827Y796438D01*
X643535Y796646D01*
X643244Y796688D01*
X642952Y796605D01*
X642744Y796396D01*
G01X713812Y39060D02*
Y41560D01*
X712771D01*
X712437Y41435D01*
X712229Y41268D01*
X712146Y40935D01*
X712229Y40602D01*
X712479Y40393D01*
X712771Y40268D01*
X713812D01*
G01X712771D02*
X712146Y39060D01*
G01X710671Y41143D02*
X710421Y41393D01*
X710129Y41518D01*
X709796Y41560D01*
X709379Y41477D01*
X709087Y41268D01*
X709004Y41018D01*
X709046Y40768D01*
X709212Y40560D01*
X710046Y40143D01*
X710421Y39852D01*
X710671Y39435D01*
X710754Y39060D01*
X709004D01*
G01X706779Y41560D02*
X707112Y41477D01*
X707362Y41268D01*
X707529Y41018D01*
X707654Y40685D01*
X707696Y40310D01*
X707654Y39935D01*
X707529Y39602D01*
X707362Y39352D01*
X707112Y39143D01*
X706779Y39060D01*
X706446Y39143D01*
X706196Y39352D01*
X706029Y39602D01*
X705904Y39935D01*
X705862Y40310D01*
X705904Y40685D01*
X706029Y41018D01*
X706196Y41268D01*
X706446Y41477D01*
X706779Y41560D01*
G01X703762Y39060D02*
X703679Y39602D01*
X703554Y40060D01*
X703387Y40477D01*
X703179Y40935D01*
X702846Y41560D01*
X704512D01*
G01X689090Y34855D02*
Y37355D01*
X688049D01*
X687715Y37230D01*
X687507Y37063D01*
X687424Y36730D01*
X687507Y36397D01*
X687757Y36188D01*
X688049Y36063D01*
X689090D01*
G01X688049D02*
X687424Y34855D01*
G01X686074Y35355D02*
X685824Y35063D01*
X685490Y34897D01*
X685115Y34855D01*
X684782Y34897D01*
X684449Y35105D01*
X684240Y35355D01*
X684199Y35605D01*
X684282Y35897D01*
X684574Y36105D01*
X684865Y36188D01*
X685240D01*
G01X684865D02*
X684615Y36313D01*
X684407Y36522D01*
X684324Y36772D01*
X684407Y37022D01*
X684615Y37230D01*
X684990Y37355D01*
X685365Y37313D01*
X685740Y37147D01*
G01X682849Y36938D02*
X682599Y37188D01*
X682307Y37313D01*
X681974Y37355D01*
X681557Y37272D01*
X681265Y37063D01*
X681182Y36813D01*
X681224Y36563D01*
X681390Y36355D01*
X682224Y35938D01*
X682599Y35647D01*
X682849Y35230D01*
X682932Y34855D01*
X681182D01*
G01X679665Y35147D02*
X679374Y34938D01*
X679040Y34855D01*
X678707Y34938D01*
X678415Y35188D01*
X678207Y35563D01*
X678124Y35938D01*
Y36397D01*
X678207Y36772D01*
X678415Y37105D01*
X678665Y37272D01*
X678957Y37355D01*
X679290Y37272D01*
X679540Y37105D01*
X679707Y36855D01*
X679790Y36522D01*
X679707Y36230D01*
X679499Y35938D01*
X679249Y35772D01*
X678957Y35730D01*
X678624Y35813D01*
X678374Y36022D01*
X678124Y36397D01*
G01X689090Y38522D02*
Y41022D01*
X688049D01*
X687715Y40897D01*
X687507Y40730D01*
X687424Y40397D01*
X687507Y40064D01*
X687757Y39855D01*
X688049Y39730D01*
X689090D01*
G01X688049D02*
X687424Y38522D01*
G01X685949Y40605D02*
X685699Y40855D01*
X685407Y40980D01*
X685074Y41022D01*
X684657Y40939D01*
X684365Y40730D01*
X684282Y40480D01*
X684324Y40230D01*
X684490Y40022D01*
X685324Y39605D01*
X685699Y39314D01*
X685949Y38897D01*
X686032Y38522D01*
X684282D01*
G01X682849Y39564D02*
X682557Y39855D01*
X682307Y40022D01*
X681974Y40105D01*
X681682Y40022D01*
X681474Y39855D01*
X681307Y39605D01*
X681265Y39314D01*
X681307Y39064D01*
X681474Y38814D01*
X681724Y38605D01*
X682015Y38522D01*
X682349Y38605D01*
X682640Y38855D01*
X682807Y39230D01*
X682849Y39647D01*
X682765Y40189D01*
X682640Y40480D01*
X682432Y40772D01*
X682140Y40980D01*
X681849Y41022D01*
X681557Y40939D01*
X681349Y40730D01*
G01X678957Y38522D02*
X678665Y38564D01*
X678332Y38689D01*
X678124Y38897D01*
X678040Y39189D01*
X678124Y39480D01*
X678374Y39730D01*
X678749Y39855D01*
X679165D01*
X679415Y39939D01*
X679624Y40147D01*
X679707Y40439D01*
X679582Y40730D01*
X679290Y40939D01*
X678957Y41022D01*
X678624Y40939D01*
X678332Y40730D01*
X678207Y40439D01*
X678290Y40147D01*
X678499Y39939D01*
X678749Y39855D01*
X679165D01*
X679540Y39730D01*
X679790Y39480D01*
X679874Y39189D01*
X679790Y38897D01*
X679582Y38689D01*
X679249Y38564D01*
X678957Y38522D01*
G01X676780Y122433D02*
X679280D01*
Y123474D01*
X679155Y123808D01*
X678988Y124016D01*
X678655Y124099D01*
X678322Y124016D01*
X678113Y123766D01*
X677988Y123474D01*
Y122433D01*
G01Y123474D02*
X676780Y124099D01*
G01X678863Y125574D02*
X679113Y125824D01*
X679238Y126116D01*
X679280Y126449D01*
X679197Y126866D01*
X678988Y127158D01*
X678738Y127241D01*
X678488Y127199D01*
X678280Y127033D01*
X677863Y126199D01*
X677572Y125824D01*
X677155Y125574D01*
X676780Y125491D01*
Y127241D01*
G01X677072Y128758D02*
X676863Y129049D01*
X676780Y129383D01*
X676863Y129716D01*
X677113Y130008D01*
X677488Y130216D01*
X677863Y130299D01*
X678322D01*
X678697Y130216D01*
X679030Y130008D01*
X679197Y129758D01*
X679280Y129466D01*
X679197Y129133D01*
X679030Y128883D01*
X678780Y128716D01*
X678447Y128633D01*
X678155Y128716D01*
X677863Y128924D01*
X677697Y129174D01*
X677655Y129466D01*
X677738Y129799D01*
X677947Y130049D01*
X678322Y130299D01*
G01X677280Y131649D02*
X676988Y131899D01*
X676822Y132233D01*
X676780Y132608D01*
X676822Y132941D01*
X677030Y133274D01*
X677280Y133483D01*
X677530Y133524D01*
X677822Y133441D01*
X678030Y133149D01*
X678113Y132858D01*
Y132483D01*
G01Y132858D02*
X678238Y133108D01*
X678447Y133316D01*
X678697Y133399D01*
X678947Y133316D01*
X679155Y133108D01*
X679280Y132733D01*
X679238Y132358D01*
X679072Y131983D01*
G01X679280Y135666D02*
X679197Y135333D01*
X678988Y135083D01*
X678738Y134916D01*
X678405Y134791D01*
X678030Y134749D01*
X677655Y134791D01*
X677322Y134916D01*
X677072Y135083D01*
X676863Y135333D01*
X676780Y135666D01*
X676863Y135999D01*
X677072Y136249D01*
X677322Y136416D01*
X677655Y136541D01*
X678030Y136583D01*
X678405Y136541D01*
X678738Y136416D01*
X678988Y136249D01*
X679197Y135999D01*
X679280Y135666D01*
G01X672280Y122433D02*
X674780D01*
Y123474D01*
X674655Y123808D01*
X674488Y124016D01*
X674155Y124099D01*
X673822Y124016D01*
X673613Y123766D01*
X673488Y123474D01*
Y122433D01*
G01Y123474D02*
X672280Y124099D01*
G01X674363Y125574D02*
X674613Y125824D01*
X674738Y126116D01*
X674780Y126449D01*
X674697Y126866D01*
X674488Y127158D01*
X674238Y127241D01*
X673988Y127199D01*
X673780Y127033D01*
X673363Y126199D01*
X673072Y125824D01*
X672655Y125574D01*
X672280Y125491D01*
Y127241D01*
G01X672572Y128758D02*
X672363Y129049D01*
X672280Y129383D01*
X672363Y129716D01*
X672613Y130008D01*
X672988Y130216D01*
X673363Y130299D01*
X673822D01*
X674197Y130216D01*
X674530Y130008D01*
X674697Y129758D01*
X674780Y129466D01*
X674697Y129133D01*
X674530Y128883D01*
X674280Y128716D01*
X673947Y128633D01*
X673655Y128716D01*
X673363Y128924D01*
X673197Y129174D01*
X673155Y129466D01*
X673238Y129799D01*
X673447Y130049D01*
X673822Y130299D01*
G01X674363Y131774D02*
X674613Y132024D01*
X674738Y132316D01*
X674780Y132649D01*
X674697Y133066D01*
X674488Y133358D01*
X674238Y133441D01*
X673988Y133399D01*
X673780Y133233D01*
X673363Y132399D01*
X673072Y132024D01*
X672655Y131774D01*
X672280Y131691D01*
Y133441D01*
G01X674363Y134874D02*
X674613Y135124D01*
X674738Y135416D01*
X674780Y135749D01*
X674697Y136166D01*
X674488Y136458D01*
X674238Y136541D01*
X673988Y136499D01*
X673780Y136333D01*
X673363Y135499D01*
X673072Y135124D01*
X672655Y134874D01*
X672280Y134791D01*
Y136541D01*
G01X675157Y276873D02*
X677657D01*
Y277873D01*
X677532Y278206D01*
X677240Y278456D01*
X676907Y278539D01*
X676574Y278456D01*
X676324Y278248D01*
X676199Y277873D01*
Y276873D01*
G01X676407Y281056D02*
Y281889D01*
X675657D01*
X675407Y281639D01*
X675240Y281348D01*
X675157Y280931D01*
X675240Y280514D01*
X675407Y280223D01*
X675657Y279973D01*
X675949Y279806D01*
X676282Y279723D01*
X676574D01*
X676824Y279806D01*
X677115Y279973D01*
X677365Y280223D01*
X677532Y280473D01*
X677657Y280806D01*
Y281098D01*
X677574Y281431D01*
X677407Y281681D01*
G01X675657Y282989D02*
X675365Y283239D01*
X675199Y283573D01*
X675157Y283948D01*
X675199Y284281D01*
X675407Y284614D01*
X675657Y284823D01*
X675907Y284864D01*
X676199Y284781D01*
X676407Y284489D01*
X676490Y284198D01*
Y283823D01*
G01Y284198D02*
X676615Y284448D01*
X676824Y284656D01*
X677074Y284739D01*
X677324Y284656D01*
X677532Y284448D01*
X677657Y284073D01*
X677615Y283698D01*
X677449Y283323D01*
G01X675532Y286089D02*
X675324Y286339D01*
X675199Y286631D01*
X675157Y287006D01*
X675240Y287381D01*
X675407Y287673D01*
X675699Y287881D01*
X676032Y287923D01*
X676365Y287839D01*
X676574Y287631D01*
X676740Y287339D01*
X676782Y287048D01*
X676740Y286756D01*
X676574Y286381D01*
X677657Y286506D01*
Y287631D01*
G01X679093Y276829D02*
X681593D01*
Y277829D01*
X681468Y278162D01*
X681176Y278412D01*
X680843Y278495D01*
X680510Y278412D01*
X680260Y278204D01*
X680135Y277829D01*
Y276829D01*
G01X680343Y281012D02*
Y281845D01*
X679593D01*
X679343Y281595D01*
X679176Y281304D01*
X679093Y280887D01*
X679176Y280470D01*
X679343Y280179D01*
X679593Y279929D01*
X679885Y279762D01*
X680218Y279679D01*
X680510D01*
X680760Y279762D01*
X681051Y279929D01*
X681301Y280179D01*
X681468Y280429D01*
X681593Y280762D01*
Y281054D01*
X681510Y281387D01*
X681343Y281637D01*
G01X681176Y283070D02*
X681426Y283320D01*
X681551Y283612D01*
X681593Y283945D01*
X681510Y284362D01*
X681301Y284654D01*
X681051Y284737D01*
X680801Y284695D01*
X680593Y284529D01*
X680176Y283695D01*
X679885Y283320D01*
X679468Y283070D01*
X679093Y282987D01*
Y284737D01*
G01X679385Y286254D02*
X679176Y286545D01*
X679093Y286879D01*
X679176Y287212D01*
X679426Y287504D01*
X679801Y287712D01*
X680176Y287795D01*
X680635D01*
X681010Y287712D01*
X681343Y287504D01*
X681510Y287254D01*
X681593Y286962D01*
X681510Y286629D01*
X681343Y286379D01*
X681093Y286212D01*
X680760Y286129D01*
X680468Y286212D01*
X680176Y286420D01*
X680010Y286670D01*
X679968Y286962D01*
X680051Y287295D01*
X680260Y287545D01*
X680635Y287795D01*
G01X709401Y310843D02*
Y313343D01*
X708401D01*
X708068Y313218D01*
X707818Y312926D01*
X707735Y312593D01*
X707818Y312260D01*
X708026Y312010D01*
X708401Y311885D01*
X709401D01*
G01X705218Y312093D02*
X704385D01*
Y311343D01*
X704635Y311093D01*
X704926Y310926D01*
X705343Y310843D01*
X705760Y310926D01*
X706051Y311093D01*
X706301Y311343D01*
X706468Y311635D01*
X706551Y311968D01*
Y312260D01*
X706468Y312510D01*
X706301Y312801D01*
X706051Y313051D01*
X705801Y313218D01*
X705468Y313343D01*
X705176D01*
X704843Y313260D01*
X704593Y313093D01*
G01X703160Y312926D02*
X702910Y313176D01*
X702618Y313301D01*
X702285Y313343D01*
X701868Y313260D01*
X701576Y313051D01*
X701493Y312801D01*
X701535Y312551D01*
X701701Y312343D01*
X702535Y311926D01*
X702910Y311635D01*
X703160Y311218D01*
X703243Y310843D01*
X701493D01*
G01X700185Y311343D02*
X699935Y311051D01*
X699601Y310885D01*
X699226Y310843D01*
X698893Y310885D01*
X698560Y311093D01*
X698351Y311343D01*
X698310Y311593D01*
X698393Y311885D01*
X698685Y312093D01*
X698976Y312176D01*
X699351D01*
G01X698976D02*
X698726Y312301D01*
X698518Y312510D01*
X698435Y312760D01*
X698518Y313010D01*
X698726Y313218D01*
X699101Y313343D01*
X699476Y313301D01*
X699851Y313135D01*
G01X709401Y306843D02*
Y309343D01*
X708401D01*
X708068Y309218D01*
X707818Y308926D01*
X707735Y308593D01*
X707818Y308260D01*
X708026Y308010D01*
X708401Y307885D01*
X709401D01*
G01X705218Y308093D02*
X704385D01*
Y307343D01*
X704635Y307093D01*
X704926Y306926D01*
X705343Y306843D01*
X705760Y306926D01*
X706051Y307093D01*
X706301Y307343D01*
X706468Y307635D01*
X706551Y307968D01*
Y308260D01*
X706468Y308510D01*
X706301Y308801D01*
X706051Y309051D01*
X705801Y309218D01*
X705468Y309343D01*
X705176D01*
X704843Y309260D01*
X704593Y309093D01*
G01X703160Y308926D02*
X702910Y309176D01*
X702618Y309301D01*
X702285Y309343D01*
X701868Y309260D01*
X701576Y309051D01*
X701493Y308801D01*
X701535Y308551D01*
X701701Y308343D01*
X702535Y307926D01*
X702910Y307635D01*
X703160Y307218D01*
X703243Y306843D01*
X701493D01*
G01X700060Y308926D02*
X699810Y309176D01*
X699518Y309301D01*
X699185Y309343D01*
X698768Y309260D01*
X698476Y309051D01*
X698393Y308801D01*
X698435Y308551D01*
X698601Y308343D01*
X699435Y307926D01*
X699810Y307635D01*
X700060Y307218D01*
X700143Y306843D01*
X698393D01*
G01X709401Y298843D02*
Y301343D01*
X708401D01*
X708068Y301218D01*
X707818Y300926D01*
X707735Y300593D01*
X707818Y300260D01*
X708026Y300010D01*
X708401Y299885D01*
X709401D01*
G01X705218Y300093D02*
X704385D01*
Y299343D01*
X704635Y299093D01*
X704926Y298926D01*
X705343Y298843D01*
X705760Y298926D01*
X706051Y299093D01*
X706301Y299343D01*
X706468Y299635D01*
X706551Y299968D01*
Y300260D01*
X706468Y300510D01*
X706301Y300801D01*
X706051Y301051D01*
X705801Y301218D01*
X705468Y301343D01*
X705176D01*
X704843Y301260D01*
X704593Y301093D01*
G01X702368Y298843D02*
Y301343D01*
X702868Y300843D01*
G01Y298843D02*
X701868D01*
G01X699268D02*
X698976Y298885D01*
X698643Y299010D01*
X698435Y299218D01*
X698351Y299510D01*
X698435Y299801D01*
X698685Y300051D01*
X699060Y300176D01*
X699476D01*
X699726Y300260D01*
X699935Y300468D01*
X700018Y300760D01*
X699893Y301051D01*
X699601Y301260D01*
X699268Y301343D01*
X698935Y301260D01*
X698643Y301051D01*
X698518Y300760D01*
X698601Y300468D01*
X698810Y300260D01*
X699060Y300176D01*
X699476D01*
X699851Y300051D01*
X700101Y299801D01*
X700185Y299510D01*
X700101Y299218D01*
X699893Y299010D01*
X699560Y298885D01*
X699268Y298843D01*
G01X709401Y302843D02*
Y305343D01*
X708401D01*
X708068Y305218D01*
X707818Y304926D01*
X707735Y304593D01*
X707818Y304260D01*
X708026Y304010D01*
X708401Y303885D01*
X709401D01*
G01X705218Y304093D02*
X704385D01*
Y303343D01*
X704635Y303093D01*
X704926Y302926D01*
X705343Y302843D01*
X705760Y302926D01*
X706051Y303093D01*
X706301Y303343D01*
X706468Y303635D01*
X706551Y303968D01*
Y304260D01*
X706468Y304510D01*
X706301Y304801D01*
X706051Y305051D01*
X705801Y305218D01*
X705468Y305343D01*
X705176D01*
X704843Y305260D01*
X704593Y305093D01*
G01X703160Y304926D02*
X702910Y305176D01*
X702618Y305301D01*
X702285Y305343D01*
X701868Y305260D01*
X701576Y305051D01*
X701493Y304801D01*
X701535Y304551D01*
X701701Y304343D01*
X702535Y303926D01*
X702910Y303635D01*
X703160Y303218D01*
X703243Y302843D01*
X701493D01*
G01X699351D02*
X699268Y303385D01*
X699143Y303843D01*
X698976Y304260D01*
X698768Y304718D01*
X698435Y305343D01*
X700101D01*
G01X709401Y322843D02*
Y325343D01*
X708401D01*
X708068Y325218D01*
X707818Y324926D01*
X707735Y324593D01*
X707818Y324260D01*
X708026Y324010D01*
X708401Y323885D01*
X709401D01*
G01X705218Y324093D02*
X704385D01*
Y323343D01*
X704635Y323093D01*
X704926Y322926D01*
X705343Y322843D01*
X705760Y322926D01*
X706051Y323093D01*
X706301Y323343D01*
X706468Y323635D01*
X706551Y323968D01*
Y324260D01*
X706468Y324510D01*
X706301Y324801D01*
X706051Y325051D01*
X705801Y325218D01*
X705468Y325343D01*
X705176D01*
X704843Y325260D01*
X704593Y325093D01*
G01X703160Y324926D02*
X702910Y325176D01*
X702618Y325301D01*
X702285Y325343D01*
X701868Y325260D01*
X701576Y325051D01*
X701493Y324801D01*
X701535Y324551D01*
X701701Y324343D01*
X702535Y323926D01*
X702910Y323635D01*
X703160Y323218D01*
X703243Y322843D01*
X701493D01*
G01X700060Y323885D02*
X699768Y324176D01*
X699518Y324343D01*
X699185Y324426D01*
X698893Y324343D01*
X698685Y324176D01*
X698518Y323926D01*
X698476Y323635D01*
X698518Y323385D01*
X698685Y323135D01*
X698935Y322926D01*
X699226Y322843D01*
X699560Y322926D01*
X699851Y323176D01*
X700018Y323551D01*
X700060Y323968D01*
X699976Y324510D01*
X699851Y324801D01*
X699643Y325093D01*
X699351Y325301D01*
X699060Y325343D01*
X698768Y325260D01*
X698560Y325051D01*
G01X709401Y318843D02*
Y321343D01*
X708401D01*
X708068Y321218D01*
X707818Y320926D01*
X707735Y320593D01*
X707818Y320260D01*
X708026Y320010D01*
X708401Y319885D01*
X709401D01*
G01X705218Y320093D02*
X704385D01*
Y319343D01*
X704635Y319093D01*
X704926Y318926D01*
X705343Y318843D01*
X705760Y318926D01*
X706051Y319093D01*
X706301Y319343D01*
X706468Y319635D01*
X706551Y319968D01*
Y320260D01*
X706468Y320510D01*
X706301Y320801D01*
X706051Y321051D01*
X705801Y321218D01*
X705468Y321343D01*
X705176D01*
X704843Y321260D01*
X704593Y321093D01*
G01X703160Y320926D02*
X702910Y321176D01*
X702618Y321301D01*
X702285Y321343D01*
X701868Y321260D01*
X701576Y321051D01*
X701493Y320801D01*
X701535Y320551D01*
X701701Y320343D01*
X702535Y319926D01*
X702910Y319635D01*
X703160Y319218D01*
X703243Y318843D01*
X701493D01*
G01X700185Y319218D02*
X699935Y319010D01*
X699643Y318885D01*
X699268Y318843D01*
X698893Y318926D01*
X698601Y319093D01*
X698393Y319385D01*
X698351Y319718D01*
X698435Y320051D01*
X698643Y320260D01*
X698935Y320426D01*
X699226Y320468D01*
X699518Y320426D01*
X699893Y320260D01*
X699768Y321343D01*
X698643D01*
G01X709401Y314843D02*
Y317343D01*
X708401D01*
X708068Y317218D01*
X707818Y316926D01*
X707735Y316593D01*
X707818Y316260D01*
X708026Y316010D01*
X708401Y315885D01*
X709401D01*
G01X705218Y316093D02*
X704385D01*
Y315343D01*
X704635Y315093D01*
X704926Y314926D01*
X705343Y314843D01*
X705760Y314926D01*
X706051Y315093D01*
X706301Y315343D01*
X706468Y315635D01*
X706551Y315968D01*
Y316260D01*
X706468Y316510D01*
X706301Y316801D01*
X706051Y317051D01*
X705801Y317218D01*
X705468Y317343D01*
X705176D01*
X704843Y317260D01*
X704593Y317093D01*
G01X703160Y316926D02*
X702910Y317176D01*
X702618Y317301D01*
X702285Y317343D01*
X701868Y317260D01*
X701576Y317051D01*
X701493Y316801D01*
X701535Y316551D01*
X701701Y316343D01*
X702535Y315926D01*
X702910Y315635D01*
X703160Y315218D01*
X703243Y314843D01*
X701493D01*
G01X698768D02*
Y317343D01*
X700310Y315551D01*
X698226D01*
G01X709401Y326843D02*
Y329343D01*
X708401D01*
X708068Y329218D01*
X707818Y328926D01*
X707735Y328593D01*
X707818Y328260D01*
X708026Y328010D01*
X708401Y327885D01*
X709401D01*
G01X705218Y328093D02*
X704385D01*
Y327343D01*
X704635Y327093D01*
X704926Y326926D01*
X705343Y326843D01*
X705760Y326926D01*
X706051Y327093D01*
X706301Y327343D01*
X706468Y327635D01*
X706551Y327968D01*
Y328260D01*
X706468Y328510D01*
X706301Y328801D01*
X706051Y329051D01*
X705801Y329218D01*
X705468Y329343D01*
X705176D01*
X704843Y329260D01*
X704593Y329093D01*
G01X702368Y326843D02*
Y329343D01*
X702868Y328843D01*
G01Y326843D02*
X701868D01*
G01X699351D02*
X699268Y327385D01*
X699143Y327843D01*
X698976Y328260D01*
X698768Y328718D01*
X698435Y329343D01*
X700101D01*
G01X685613Y817778D02*
X685863Y817903D01*
X686155Y817986D01*
X686488D01*
X686863Y817861D01*
X687155Y817653D01*
X687363Y817403D01*
X687530Y816986D01*
X687572Y816611D01*
X687488Y816236D01*
X687363Y815986D01*
X687113Y815736D01*
X686822Y815569D01*
X686530Y815486D01*
X686238D01*
X685947Y815569D01*
X685697Y815694D01*
X685488Y815861D01*
G01X682930Y815486D02*
Y817986D01*
X684472Y816194D01*
X682388D01*
G01X680330Y815486D02*
Y817986D01*
X680830Y817486D01*
G01Y815486D02*
X679830D01*
G01X676730D02*
Y817986D01*
X678272Y816194D01*
X676188D01*
G01X674130Y815486D02*
X673838Y815528D01*
X673505Y815653D01*
X673297Y815861D01*
X673213Y816153D01*
X673297Y816444D01*
X673547Y816694D01*
X673922Y816819D01*
X674338D01*
X674588Y816903D01*
X674797Y817111D01*
X674880Y817403D01*
X674755Y817694D01*
X674463Y817903D01*
X674130Y817986D01*
X673797Y817903D01*
X673505Y817694D01*
X673380Y817403D01*
X673463Y817111D01*
X673672Y816903D01*
X673922Y816819D01*
X674338D01*
X674713Y816694D01*
X674963Y816444D01*
X675047Y816153D01*
X674963Y815861D01*
X674755Y815653D01*
X674422Y815528D01*
X674130Y815486D01*
G01X716167Y3017D02*
X718667D01*
Y4058D01*
X718542Y4392D01*
X718375Y4600D01*
X718042Y4683D01*
X717709Y4600D01*
X717500Y4350D01*
X717375Y4058D01*
Y3017D01*
G01Y4058D02*
X716167Y4683D01*
G01X718250Y6158D02*
X718500Y6408D01*
X718625Y6700D01*
X718667Y7033D01*
X718584Y7450D01*
X718375Y7742D01*
X718125Y7825D01*
X717875Y7783D01*
X717667Y7617D01*
X717250Y6783D01*
X716959Y6408D01*
X716542Y6158D01*
X716167Y6075D01*
Y7825D01*
G01Y10050D02*
X718667D01*
X718167Y9550D01*
G01X716167D02*
Y10550D01*
G01X716667Y12233D02*
X716375Y12483D01*
X716209Y12817D01*
X716167Y13192D01*
X716209Y13525D01*
X716417Y13858D01*
X716667Y14067D01*
X716917Y14108D01*
X717209Y14025D01*
X717417Y13733D01*
X717500Y13442D01*
Y13067D01*
G01Y13442D02*
X717625Y13692D01*
X717834Y13900D01*
X718084Y13983D01*
X718334Y13900D01*
X718542Y13692D01*
X718667Y13317D01*
X718625Y12942D01*
X718459Y12567D01*
G01X728078Y36017D02*
X730578D01*
Y37058D01*
X730453Y37392D01*
X730286Y37600D01*
X729953Y37683D01*
X729620Y37600D01*
X729411Y37350D01*
X729286Y37058D01*
Y36017D01*
G01Y37058D02*
X728078Y37683D01*
G01X730161Y39158D02*
X730411Y39408D01*
X730536Y39700D01*
X730578Y40033D01*
X730495Y40450D01*
X730286Y40742D01*
X730036Y40825D01*
X729786Y40783D01*
X729578Y40617D01*
X729161Y39783D01*
X728870Y39408D01*
X728453Y39158D01*
X728078Y39075D01*
Y40825D01*
G01X728453Y42133D02*
X728245Y42383D01*
X728120Y42675D01*
X728078Y43050D01*
X728161Y43425D01*
X728328Y43717D01*
X728620Y43925D01*
X728953Y43967D01*
X729286Y43883D01*
X729495Y43675D01*
X729661Y43383D01*
X729703Y43092D01*
X729661Y42800D01*
X729495Y42425D01*
X730578Y42550D01*
Y43675D01*
G01Y46150D02*
X730495Y45817D01*
X730286Y45567D01*
X730036Y45400D01*
X729703Y45275D01*
X729328Y45233D01*
X728953Y45275D01*
X728620Y45400D01*
X728370Y45567D01*
X728161Y45817D01*
X728078Y46150D01*
X728161Y46483D01*
X728370Y46733D01*
X728620Y46900D01*
X728953Y47025D01*
X729328Y47067D01*
X729703Y47025D01*
X730036Y46900D01*
X730286Y46733D01*
X730495Y46483D01*
X730578Y46150D01*
G01X718100Y43500D02*
X722100D01*
Y36100D01*
G01X713510Y8480D02*
X709510D01*
Y15880D01*
G01X717563Y39236D02*
Y35236D01*
X710163D01*
G01X730983Y13096D02*
Y15596D01*
X729942D01*
X729608Y15471D01*
X729400Y15304D01*
X729317Y14971D01*
X729400Y14638D01*
X729650Y14429D01*
X729942Y14304D01*
X730983D01*
G01X729942D02*
X729317Y13096D01*
G01X727842Y15179D02*
X727592Y15429D01*
X727300Y15554D01*
X726967Y15596D01*
X726550Y15513D01*
X726258Y15304D01*
X726175Y15054D01*
X726217Y14804D01*
X726383Y14596D01*
X727217Y14179D01*
X727592Y13888D01*
X727842Y13471D01*
X727925Y13096D01*
X726175D01*
G01X723950Y15596D02*
X724283Y15513D01*
X724533Y15304D01*
X724700Y15054D01*
X724825Y14721D01*
X724867Y14346D01*
X724825Y13971D01*
X724700Y13638D01*
X724533Y13388D01*
X724283Y13179D01*
X723950Y13096D01*
X723617Y13179D01*
X723367Y13388D01*
X723200Y13638D01*
X723075Y13971D01*
X723033Y14346D01*
X723075Y14721D01*
X723200Y15054D01*
X723367Y15304D01*
X723617Y15513D01*
X723950Y15596D01*
G01X721767Y13471D02*
X721517Y13263D01*
X721225Y13138D01*
X720850Y13096D01*
X720475Y13179D01*
X720183Y13346D01*
X719975Y13638D01*
X719933Y13971D01*
X720017Y14304D01*
X720225Y14513D01*
X720517Y14679D01*
X720808Y14721D01*
X721100Y14679D01*
X721475Y14513D01*
X721350Y15596D01*
X720225D01*
G01X713350Y15920D02*
Y19920D01*
X720750D01*
G01X717380Y20080D02*
X713380D01*
Y27480D01*
G01X740304Y28107D02*
Y30607D01*
X739263D01*
X738929Y30482D01*
X738721Y30315D01*
X738638Y29982D01*
X738721Y29649D01*
X738971Y29440D01*
X739263Y29315D01*
X740304D01*
G01X739263D02*
X738638Y28107D01*
G01X737163Y30190D02*
X736913Y30440D01*
X736621Y30565D01*
X736288Y30607D01*
X735871Y30524D01*
X735579Y30315D01*
X735496Y30065D01*
X735538Y29815D01*
X735704Y29607D01*
X736538Y29190D01*
X736913Y28899D01*
X737163Y28482D01*
X737246Y28107D01*
X735496D01*
G01X733979Y28399D02*
X733688Y28190D01*
X733354Y28107D01*
X733021Y28190D01*
X732729Y28440D01*
X732521Y28815D01*
X732438Y29190D01*
Y29649D01*
X732521Y30024D01*
X732729Y30357D01*
X732979Y30524D01*
X733271Y30607D01*
X733604Y30524D01*
X733854Y30357D01*
X734021Y30107D01*
X734104Y29774D01*
X734021Y29482D01*
X733813Y29190D01*
X733563Y29024D01*
X733271Y28982D01*
X732938Y29065D01*
X732688Y29274D01*
X732438Y29649D01*
G01X731088Y28482D02*
X730838Y28274D01*
X730546Y28149D01*
X730171Y28107D01*
X729796Y28190D01*
X729504Y28357D01*
X729296Y28649D01*
X729254Y28982D01*
X729338Y29315D01*
X729546Y29524D01*
X729838Y29690D01*
X730129Y29732D01*
X730421Y29690D01*
X730796Y29524D01*
X730671Y30607D01*
X729546D01*
G01X727863Y30190D02*
X727613Y30440D01*
X727321Y30565D01*
X726988Y30607D01*
X726571Y30524D01*
X726279Y30315D01*
X726196Y30065D01*
X726238Y29815D01*
X726404Y29607D01*
X727238Y29190D01*
X727613Y28899D01*
X727863Y28482D01*
X727946Y28107D01*
X726196D01*
G01X720770Y31700D02*
Y27700D01*
X713370D01*
G01X740304Y24513D02*
Y27013D01*
X739263D01*
X738929Y26888D01*
X738721Y26721D01*
X738638Y26388D01*
X738721Y26055D01*
X738971Y25846D01*
X739263Y25721D01*
X740304D01*
G01X739263D02*
X738638Y24513D01*
G01X737163Y26596D02*
X736913Y26846D01*
X736621Y26971D01*
X736288Y27013D01*
X735871Y26930D01*
X735579Y26721D01*
X735496Y26471D01*
X735538Y26221D01*
X735704Y26013D01*
X736538Y25596D01*
X736913Y25305D01*
X737163Y24888D01*
X737246Y24513D01*
X735496D01*
G01X733979Y24805D02*
X733688Y24596D01*
X733354Y24513D01*
X733021Y24596D01*
X732729Y24846D01*
X732521Y25221D01*
X732438Y25596D01*
Y26055D01*
X732521Y26430D01*
X732729Y26763D01*
X732979Y26930D01*
X733271Y27013D01*
X733604Y26930D01*
X733854Y26763D01*
X734021Y26513D01*
X734104Y26180D01*
X734021Y25888D01*
X733813Y25596D01*
X733563Y25430D01*
X733271Y25388D01*
X732938Y25471D01*
X732688Y25680D01*
X732438Y26055D01*
G01X731088Y25013D02*
X730838Y24721D01*
X730504Y24555D01*
X730129Y24513D01*
X729796Y24555D01*
X729463Y24763D01*
X729254Y25013D01*
X729213Y25263D01*
X729296Y25555D01*
X729588Y25763D01*
X729879Y25846D01*
X730254D01*
G01X729879D02*
X729629Y25971D01*
X729421Y26180D01*
X729338Y26430D01*
X729421Y26680D01*
X729629Y26888D01*
X730004Y27013D01*
X730379Y26971D01*
X730754Y26805D01*
G01X727863Y25555D02*
X727571Y25846D01*
X727321Y26013D01*
X726988Y26096D01*
X726696Y26013D01*
X726488Y25846D01*
X726321Y25596D01*
X726279Y25305D01*
X726321Y25055D01*
X726488Y24805D01*
X726738Y24596D01*
X727029Y24513D01*
X727363Y24596D01*
X727654Y24846D01*
X727821Y25221D01*
X727863Y25638D01*
X727779Y26180D01*
X727654Y26471D01*
X727446Y26763D01*
X727154Y26971D01*
X726863Y27013D01*
X726571Y26930D01*
X726363Y26721D01*
G01X720790Y27490D02*
Y23490D01*
X713390D01*
G01Y35080D02*
X717390D01*
Y27680D01*
G01X707911Y52980D02*
X710411D01*
Y54021D01*
X710286Y54355D01*
X710119Y54563D01*
X709786Y54646D01*
X709453Y54563D01*
X709244Y54313D01*
X709119Y54021D01*
Y52980D01*
G01Y54021D02*
X707911Y54646D01*
G01X708411Y55996D02*
X708119Y56246D01*
X707953Y56580D01*
X707911Y56955D01*
X707953Y57288D01*
X708161Y57621D01*
X708411Y57830D01*
X708661Y57871D01*
X708953Y57788D01*
X709161Y57496D01*
X709244Y57205D01*
Y56830D01*
G01Y57205D02*
X709369Y57455D01*
X709578Y57663D01*
X709828Y57746D01*
X710078Y57663D01*
X710286Y57455D01*
X710411Y57080D01*
X710369Y56705D01*
X710203Y56330D01*
G01X710411Y60013D02*
X710328Y59680D01*
X710119Y59430D01*
X709869Y59263D01*
X709536Y59138D01*
X709161Y59096D01*
X708786Y59138D01*
X708453Y59263D01*
X708203Y59430D01*
X707994Y59680D01*
X707911Y60013D01*
X707994Y60346D01*
X708203Y60596D01*
X708453Y60763D01*
X708786Y60888D01*
X709161Y60930D01*
X709536Y60888D01*
X709869Y60763D01*
X710119Y60596D01*
X710328Y60346D01*
X710411Y60013D01*
G01X708411Y62196D02*
X708119Y62446D01*
X707953Y62780D01*
X707911Y63155D01*
X707953Y63488D01*
X708161Y63821D01*
X708411Y64030D01*
X708661Y64071D01*
X708953Y63988D01*
X709161Y63696D01*
X709244Y63405D01*
Y63030D01*
G01Y63405D02*
X709369Y63655D01*
X709578Y63863D01*
X709828Y63946D01*
X710078Y63863D01*
X710286Y63655D01*
X710411Y63280D01*
X710369Y62905D01*
X710203Y62530D01*
G01X717130Y43700D02*
X713130D01*
Y51100D01*
G01X736363Y59700D02*
Y62200D01*
X735322D01*
X734988Y62075D01*
X734780Y61908D01*
X734697Y61575D01*
X734780Y61242D01*
X735030Y61033D01*
X735322Y60908D01*
X736363D01*
G01X735322D02*
X734697Y59700D01*
G01X733222Y61783D02*
X732972Y62033D01*
X732680Y62158D01*
X732347Y62200D01*
X731930Y62117D01*
X731638Y61908D01*
X731555Y61658D01*
X731597Y61408D01*
X731763Y61200D01*
X732597Y60783D01*
X732972Y60492D01*
X733222Y60075D01*
X733305Y59700D01*
X731555D01*
G01X730038Y59992D02*
X729747Y59783D01*
X729413Y59700D01*
X729080Y59783D01*
X728788Y60033D01*
X728580Y60408D01*
X728497Y60783D01*
Y61242D01*
X728580Y61617D01*
X728788Y61950D01*
X729038Y62117D01*
X729330Y62200D01*
X729663Y62117D01*
X729913Y61950D01*
X730080Y61700D01*
X730163Y61367D01*
X730080Y61075D01*
X729872Y60783D01*
X729622Y60617D01*
X729330Y60575D01*
X728997Y60658D01*
X728747Y60867D01*
X728497Y61242D01*
G01X727147Y60075D02*
X726897Y59867D01*
X726605Y59742D01*
X726230Y59700D01*
X725855Y59783D01*
X725563Y59950D01*
X725355Y60242D01*
X725313Y60575D01*
X725397Y60908D01*
X725605Y61117D01*
X725897Y61283D01*
X726188Y61325D01*
X726480Y61283D01*
X726855Y61117D01*
X726730Y62200D01*
X725605D01*
G01X724047Y60200D02*
X723797Y59908D01*
X723463Y59742D01*
X723088Y59700D01*
X722755Y59742D01*
X722422Y59950D01*
X722213Y60200D01*
X722172Y60450D01*
X722255Y60742D01*
X722547Y60950D01*
X722838Y61033D01*
X723213D01*
G01X722838D02*
X722588Y61158D01*
X722380Y61367D01*
X722297Y61617D01*
X722380Y61867D01*
X722588Y62075D01*
X722963Y62200D01*
X723338Y62158D01*
X723713Y61992D01*
G01X720530Y55200D02*
Y51200D01*
X713130D01*
G01X736363Y55600D02*
Y58100D01*
X735322D01*
X734988Y57975D01*
X734780Y57808D01*
X734697Y57475D01*
X734780Y57142D01*
X735030Y56933D01*
X735322Y56808D01*
X736363D01*
G01X735322D02*
X734697Y55600D01*
G01X733222Y57683D02*
X732972Y57933D01*
X732680Y58058D01*
X732347Y58100D01*
X731930Y58017D01*
X731638Y57808D01*
X731555Y57558D01*
X731597Y57308D01*
X731763Y57100D01*
X732597Y56683D01*
X732972Y56392D01*
X733222Y55975D01*
X733305Y55600D01*
X731555D01*
G01X730038Y55892D02*
X729747Y55683D01*
X729413Y55600D01*
X729080Y55683D01*
X728788Y55933D01*
X728580Y56308D01*
X728497Y56683D01*
Y57142D01*
X728580Y57517D01*
X728788Y57850D01*
X729038Y58017D01*
X729330Y58100D01*
X729663Y58017D01*
X729913Y57850D01*
X730080Y57600D01*
X730163Y57267D01*
X730080Y56975D01*
X729872Y56683D01*
X729622Y56517D01*
X729330Y56475D01*
X728997Y56558D01*
X728747Y56767D01*
X728497Y57142D01*
G01X727147Y56100D02*
X726897Y55808D01*
X726563Y55642D01*
X726188Y55600D01*
X725855Y55642D01*
X725522Y55850D01*
X725313Y56100D01*
X725272Y56350D01*
X725355Y56642D01*
X725647Y56850D01*
X725938Y56933D01*
X726313D01*
G01X725938D02*
X725688Y57058D01*
X725480Y57267D01*
X725397Y57517D01*
X725480Y57767D01*
X725688Y57975D01*
X726063Y58100D01*
X726438Y58058D01*
X726813Y57892D01*
G01X723213Y55600D02*
X723130Y56142D01*
X723005Y56600D01*
X722838Y57017D01*
X722630Y57475D01*
X722297Y58100D01*
X723963D01*
G01X720530Y51100D02*
Y47100D01*
X713130D01*
G01X714167Y60517D02*
X716667D01*
Y61558D01*
X716542Y61892D01*
X716375Y62100D01*
X716042Y62183D01*
X715709Y62100D01*
X715500Y61850D01*
X715375Y61558D01*
Y60517D01*
G01Y61558D02*
X714167Y62183D01*
G01X716250Y63658D02*
X716500Y63908D01*
X716625Y64200D01*
X716667Y64533D01*
X716584Y64950D01*
X716375Y65242D01*
X716125Y65325D01*
X715875Y65283D01*
X715667Y65117D01*
X715250Y64283D01*
X714959Y63908D01*
X714542Y63658D01*
X714167Y63575D01*
Y65325D01*
G01Y67467D02*
X714709Y67550D01*
X715167Y67675D01*
X715584Y67842D01*
X716042Y68050D01*
X716667Y68383D01*
Y66717D01*
G01X714667Y69733D02*
X714375Y69983D01*
X714209Y70317D01*
X714167Y70692D01*
X714209Y71025D01*
X714417Y71358D01*
X714667Y71567D01*
X714917Y71608D01*
X715209Y71525D01*
X715417Y71233D01*
X715500Y70942D01*
Y70567D01*
G01Y70942D02*
X715625Y71192D01*
X715834Y71400D01*
X716084Y71483D01*
X716334Y71400D01*
X716542Y71192D01*
X716667Y70817D01*
X716625Y70442D01*
X716459Y70067D01*
G01X713130Y58600D02*
X717130D01*
Y51200D01*
G01X722770Y205992D02*
Y208492D01*
X721729D01*
X721395Y208367D01*
X721187Y208200D01*
X721104Y207867D01*
X721187Y207534D01*
X721437Y207325D01*
X721729Y207200D01*
X722770D01*
G01X721729D02*
X721104Y205992D01*
G01X718337D02*
Y208492D01*
X719879Y206700D01*
X717795D01*
G01X716654Y206492D02*
X716404Y206200D01*
X716070Y206034D01*
X715695Y205992D01*
X715362Y206034D01*
X715029Y206242D01*
X714820Y206492D01*
X714779Y206742D01*
X714862Y207034D01*
X715154Y207242D01*
X715445Y207325D01*
X715820D01*
G01X715445D02*
X715195Y207450D01*
X714987Y207659D01*
X714904Y207909D01*
X714987Y208159D01*
X715195Y208367D01*
X715570Y208492D01*
X715945Y208450D01*
X716320Y208284D01*
G01X740053Y238267D02*
X740178Y238017D01*
X740261Y237725D01*
Y237392D01*
X740136Y237017D01*
X739928Y236725D01*
X739678Y236517D01*
X739261Y236350D01*
X738886Y236308D01*
X738511Y236392D01*
X738261Y236517D01*
X738011Y236767D01*
X737844Y237058D01*
X737761Y237350D01*
Y237642D01*
X737844Y237933D01*
X737969Y238183D01*
X738136Y238392D01*
G01Y239533D02*
X737928Y239783D01*
X737803Y240075D01*
X737761Y240450D01*
X737844Y240825D01*
X738011Y241117D01*
X738303Y241325D01*
X738636Y241367D01*
X738969Y241283D01*
X739178Y241075D01*
X739344Y240783D01*
X739386Y240492D01*
X739344Y240200D01*
X739178Y239825D01*
X740261Y239950D01*
Y241075D01*
G01X737761Y243550D02*
X737803Y243842D01*
X737928Y244175D01*
X738136Y244383D01*
X738428Y244467D01*
X738719Y244383D01*
X738969Y244133D01*
X739094Y243758D01*
Y243342D01*
X739178Y243092D01*
X739386Y242883D01*
X739678Y242800D01*
X739969Y242925D01*
X740178Y243217D01*
X740261Y243550D01*
X740178Y243883D01*
X739969Y244175D01*
X739678Y244300D01*
X739386Y244217D01*
X739178Y244008D01*
X739094Y243758D01*
Y243342D01*
X738969Y242967D01*
X738719Y242717D01*
X738428Y242633D01*
X738136Y242717D01*
X737928Y242925D01*
X737803Y243258D01*
X737761Y243550D01*
G01X738803Y245858D02*
X739094Y246150D01*
X739261Y246400D01*
X739344Y246733D01*
X739261Y247025D01*
X739094Y247233D01*
X738844Y247400D01*
X738553Y247442D01*
X738303Y247400D01*
X738053Y247233D01*
X737844Y246983D01*
X737761Y246692D01*
X737844Y246358D01*
X738094Y246067D01*
X738469Y245900D01*
X738886Y245858D01*
X739428Y245942D01*
X739719Y246067D01*
X740011Y246275D01*
X740219Y246567D01*
X740261Y246858D01*
X740178Y247150D01*
X739969Y247358D01*
G01X745053Y238267D02*
X745178Y238017D01*
X745261Y237725D01*
Y237392D01*
X745136Y237017D01*
X744928Y236725D01*
X744678Y236517D01*
X744261Y236350D01*
X743886Y236308D01*
X743511Y236392D01*
X743261Y236517D01*
X743011Y236767D01*
X742844Y237058D01*
X742761Y237350D01*
Y237642D01*
X742844Y237933D01*
X742969Y238183D01*
X743136Y238392D01*
G01Y239533D02*
X742928Y239783D01*
X742803Y240075D01*
X742761Y240450D01*
X742844Y240825D01*
X743011Y241117D01*
X743303Y241325D01*
X743636Y241367D01*
X743969Y241283D01*
X744178Y241075D01*
X744344Y240783D01*
X744386Y240492D01*
X744344Y240200D01*
X744178Y239825D01*
X745261Y239950D01*
Y241075D01*
G01X742761Y243550D02*
X742803Y243842D01*
X742928Y244175D01*
X743136Y244383D01*
X743428Y244467D01*
X743719Y244383D01*
X743969Y244133D01*
X744094Y243758D01*
Y243342D01*
X744178Y243092D01*
X744386Y242883D01*
X744678Y242800D01*
X744969Y242925D01*
X745178Y243217D01*
X745261Y243550D01*
X745178Y243883D01*
X744969Y244175D01*
X744678Y244300D01*
X744386Y244217D01*
X744178Y244008D01*
X744094Y243758D01*
Y243342D01*
X743969Y242967D01*
X743719Y242717D01*
X743428Y242633D01*
X743136Y242717D01*
X742928Y242925D01*
X742803Y243258D01*
X742761Y243550D01*
G01X743136Y245733D02*
X742928Y245983D01*
X742803Y246275D01*
X742761Y246650D01*
X742844Y247025D01*
X743011Y247317D01*
X743303Y247525D01*
X743636Y247567D01*
X743969Y247483D01*
X744178Y247275D01*
X744344Y246983D01*
X744386Y246692D01*
X744344Y246400D01*
X744178Y246025D01*
X745261Y246150D01*
Y247275D01*
G01X750053Y238267D02*
X750178Y238017D01*
X750261Y237725D01*
Y237392D01*
X750136Y237017D01*
X749928Y236725D01*
X749678Y236517D01*
X749261Y236350D01*
X748886Y236308D01*
X748511Y236392D01*
X748261Y236517D01*
X748011Y236767D01*
X747844Y237058D01*
X747761Y237350D01*
Y237642D01*
X747844Y237933D01*
X747969Y238183D01*
X748136Y238392D01*
G01Y239533D02*
X747928Y239783D01*
X747803Y240075D01*
X747761Y240450D01*
X747844Y240825D01*
X748011Y241117D01*
X748303Y241325D01*
X748636Y241367D01*
X748969Y241283D01*
X749178Y241075D01*
X749344Y240783D01*
X749386Y240492D01*
X749344Y240200D01*
X749178Y239825D01*
X750261Y239950D01*
Y241075D01*
G01X747761Y243550D02*
X747803Y243842D01*
X747928Y244175D01*
X748136Y244383D01*
X748428Y244467D01*
X748719Y244383D01*
X748969Y244133D01*
X749094Y243758D01*
Y243342D01*
X749178Y243092D01*
X749386Y242883D01*
X749678Y242800D01*
X749969Y242925D01*
X750178Y243217D01*
X750261Y243550D01*
X750178Y243883D01*
X749969Y244175D01*
X749678Y244300D01*
X749386Y244217D01*
X749178Y244008D01*
X749094Y243758D01*
Y243342D01*
X748969Y242967D01*
X748719Y242717D01*
X748428Y242633D01*
X748136Y242717D01*
X747928Y242925D01*
X747803Y243258D01*
X747761Y243550D01*
G01Y247150D02*
X750261D01*
X748469Y245608D01*
Y247692D01*
G01X755092Y238267D02*
X755217Y238017D01*
X755300Y237725D01*
Y237392D01*
X755175Y237017D01*
X754967Y236725D01*
X754717Y236517D01*
X754300Y236350D01*
X753925Y236308D01*
X753550Y236392D01*
X753300Y236517D01*
X753050Y236767D01*
X752883Y237058D01*
X752800Y237350D01*
Y237642D01*
X752883Y237933D01*
X753008Y238183D01*
X753175Y238392D01*
G01Y239533D02*
X752967Y239783D01*
X752842Y240075D01*
X752800Y240450D01*
X752883Y240825D01*
X753050Y241117D01*
X753342Y241325D01*
X753675Y241367D01*
X754008Y241283D01*
X754217Y241075D01*
X754383Y240783D01*
X754425Y240492D01*
X754383Y240200D01*
X754217Y239825D01*
X755300Y239950D01*
Y241075D01*
G01X752800Y243550D02*
X752842Y243842D01*
X752967Y244175D01*
X753175Y244383D01*
X753467Y244467D01*
X753758Y244383D01*
X754008Y244133D01*
X754133Y243758D01*
Y243342D01*
X754217Y243092D01*
X754425Y242883D01*
X754717Y242800D01*
X755008Y242925D01*
X755217Y243217D01*
X755300Y243550D01*
X755217Y243883D01*
X755008Y244175D01*
X754717Y244300D01*
X754425Y244217D01*
X754217Y244008D01*
X754133Y243758D01*
Y243342D01*
X754008Y242967D01*
X753758Y242717D01*
X753467Y242633D01*
X753175Y242717D01*
X752967Y242925D01*
X752842Y243258D01*
X752800Y243550D01*
G01X753300Y245733D02*
X753008Y245983D01*
X752842Y246317D01*
X752800Y246692D01*
X752842Y247025D01*
X753050Y247358D01*
X753300Y247567D01*
X753550Y247608D01*
X753842Y247525D01*
X754050Y247233D01*
X754133Y246942D01*
Y246567D01*
G01Y246942D02*
X754258Y247192D01*
X754467Y247400D01*
X754717Y247483D01*
X754967Y247400D01*
X755175Y247192D01*
X755300Y246817D01*
X755258Y246442D01*
X755092Y246067D01*
G01X750433Y278292D02*
X750558Y278042D01*
X750641Y277750D01*
Y277417D01*
X750516Y277042D01*
X750308Y276750D01*
X750058Y276542D01*
X749641Y276375D01*
X749266Y276333D01*
X748891Y276417D01*
X748641Y276542D01*
X748391Y276792D01*
X748224Y277083D01*
X748141Y277375D01*
Y277667D01*
X748224Y277958D01*
X748349Y278208D01*
X748516Y278417D01*
G01X749183Y279683D02*
X749474Y279975D01*
X749641Y280225D01*
X749724Y280558D01*
X749641Y280850D01*
X749474Y281058D01*
X749224Y281225D01*
X748933Y281267D01*
X748683Y281225D01*
X748433Y281058D01*
X748224Y280808D01*
X748141Y280517D01*
X748224Y280183D01*
X748474Y279892D01*
X748849Y279725D01*
X749266Y279683D01*
X749808Y279767D01*
X750099Y279892D01*
X750391Y280100D01*
X750599Y280392D01*
X750641Y280683D01*
X750558Y280975D01*
X750349Y281183D01*
G01X748141Y283575D02*
X750641D01*
X750141Y283075D01*
G01X748141D02*
Y284075D01*
G01X748433Y285967D02*
X748224Y286258D01*
X748141Y286592D01*
X748224Y286925D01*
X748474Y287217D01*
X748849Y287425D01*
X749224Y287508D01*
X749683D01*
X750058Y287425D01*
X750391Y287217D01*
X750558Y286967D01*
X750641Y286675D01*
X750558Y286342D01*
X750391Y286092D01*
X750141Y285925D01*
X749808Y285842D01*
X749516Y285925D01*
X749224Y286133D01*
X749058Y286383D01*
X749016Y286675D01*
X749099Y287008D01*
X749308Y287258D01*
X749683Y287508D01*
G01X746433Y278292D02*
X746558Y278042D01*
X746641Y277750D01*
Y277417D01*
X746516Y277042D01*
X746308Y276750D01*
X746058Y276542D01*
X745641Y276375D01*
X745266Y276333D01*
X744891Y276417D01*
X744641Y276542D01*
X744391Y276792D01*
X744224Y277083D01*
X744141Y277375D01*
Y277667D01*
X744224Y277958D01*
X744349Y278208D01*
X744516Y278417D01*
G01X745183Y279683D02*
X745474Y279975D01*
X745641Y280225D01*
X745724Y280558D01*
X745641Y280850D01*
X745474Y281058D01*
X745224Y281225D01*
X744933Y281267D01*
X744683Y281225D01*
X744433Y281058D01*
X744224Y280808D01*
X744141Y280517D01*
X744224Y280183D01*
X744474Y279892D01*
X744849Y279725D01*
X745266Y279683D01*
X745808Y279767D01*
X746099Y279892D01*
X746391Y280100D01*
X746599Y280392D01*
X746641Y280683D01*
X746558Y280975D01*
X746349Y281183D01*
G01X744141Y283575D02*
X746641D01*
X746141Y283075D01*
G01X744141D02*
Y284075D01*
G01Y286675D02*
X744183Y286967D01*
X744308Y287300D01*
X744516Y287508D01*
X744808Y287592D01*
X745099Y287508D01*
X745349Y287258D01*
X745474Y286883D01*
Y286467D01*
X745558Y286217D01*
X745766Y286008D01*
X746058Y285925D01*
X746349Y286050D01*
X746558Y286342D01*
X746641Y286675D01*
X746558Y287008D01*
X746349Y287300D01*
X746058Y287425D01*
X745766Y287342D01*
X745558Y287133D01*
X745474Y286883D01*
Y286467D01*
X745349Y286092D01*
X745099Y285842D01*
X744808Y285758D01*
X744516Y285842D01*
X744308Y286050D01*
X744183Y286383D01*
X744141Y286675D01*
G01X742433Y278292D02*
X742558Y278042D01*
X742641Y277750D01*
Y277417D01*
X742516Y277042D01*
X742308Y276750D01*
X742058Y276542D01*
X741641Y276375D01*
X741266Y276333D01*
X740891Y276417D01*
X740641Y276542D01*
X740391Y276792D01*
X740224Y277083D01*
X740141Y277375D01*
Y277667D01*
X740224Y277958D01*
X740349Y278208D01*
X740516Y278417D01*
G01X741183Y279683D02*
X741474Y279975D01*
X741641Y280225D01*
X741724Y280558D01*
X741641Y280850D01*
X741474Y281058D01*
X741224Y281225D01*
X740933Y281267D01*
X740683Y281225D01*
X740433Y281058D01*
X740224Y280808D01*
X740141Y280517D01*
X740224Y280183D01*
X740474Y279892D01*
X740849Y279725D01*
X741266Y279683D01*
X741808Y279767D01*
X742099Y279892D01*
X742391Y280100D01*
X742599Y280392D01*
X742641Y280683D01*
X742558Y280975D01*
X742349Y281183D01*
G01X740141Y283575D02*
X742641D01*
X742141Y283075D01*
G01X740141D02*
Y284075D01*
G01Y286592D02*
X740683Y286675D01*
X741141Y286800D01*
X741558Y286967D01*
X742016Y287175D01*
X742641Y287508D01*
Y285842D01*
G01X758433Y278292D02*
X758558Y278042D01*
X758641Y277750D01*
Y277417D01*
X758516Y277042D01*
X758308Y276750D01*
X758058Y276542D01*
X757641Y276375D01*
X757266Y276333D01*
X756891Y276417D01*
X756641Y276542D01*
X756391Y276792D01*
X756224Y277083D01*
X756141Y277375D01*
Y277667D01*
X756224Y277958D01*
X756349Y278208D01*
X756516Y278417D01*
G01Y279558D02*
X756308Y279808D01*
X756183Y280100D01*
X756141Y280475D01*
X756224Y280850D01*
X756391Y281142D01*
X756683Y281350D01*
X757016Y281392D01*
X757349Y281308D01*
X757558Y281100D01*
X757724Y280808D01*
X757766Y280517D01*
X757724Y280225D01*
X757558Y279850D01*
X758641Y279975D01*
Y281100D01*
G01X756141Y284075D02*
X758641D01*
X756849Y282533D01*
Y284617D01*
G01X758641Y286675D02*
X758558Y286342D01*
X758349Y286092D01*
X758099Y285925D01*
X757766Y285800D01*
X757391Y285758D01*
X757016Y285800D01*
X756683Y285925D01*
X756433Y286092D01*
X756224Y286342D01*
X756141Y286675D01*
X756224Y287008D01*
X756433Y287258D01*
X756683Y287425D01*
X757016Y287550D01*
X757391Y287592D01*
X757766Y287550D01*
X758099Y287425D01*
X758349Y287258D01*
X758558Y287008D01*
X758641Y286675D01*
G01X754433Y278292D02*
X754558Y278042D01*
X754641Y277750D01*
Y277417D01*
X754516Y277042D01*
X754308Y276750D01*
X754058Y276542D01*
X753641Y276375D01*
X753266Y276333D01*
X752891Y276417D01*
X752641Y276542D01*
X752391Y276792D01*
X752224Y277083D01*
X752141Y277375D01*
Y277667D01*
X752224Y277958D01*
X752349Y278208D01*
X752516Y278417D01*
G01Y279558D02*
X752308Y279808D01*
X752183Y280100D01*
X752141Y280475D01*
X752224Y280850D01*
X752391Y281142D01*
X752683Y281350D01*
X753016Y281392D01*
X753349Y281308D01*
X753558Y281100D01*
X753724Y280808D01*
X753766Y280517D01*
X753724Y280225D01*
X753558Y279850D01*
X754641Y279975D01*
Y281100D01*
G01X752641Y282658D02*
X752349Y282908D01*
X752183Y283242D01*
X752141Y283617D01*
X752183Y283950D01*
X752391Y284283D01*
X752641Y284492D01*
X752891Y284533D01*
X753183Y284450D01*
X753391Y284158D01*
X753474Y283867D01*
Y283492D01*
G01Y283867D02*
X753599Y284117D01*
X753808Y284325D01*
X754058Y284408D01*
X754308Y284325D01*
X754516Y284117D01*
X754641Y283742D01*
X754599Y283367D01*
X754433Y282992D01*
G01X754224Y285883D02*
X754474Y286133D01*
X754599Y286425D01*
X754641Y286758D01*
X754558Y287175D01*
X754349Y287467D01*
X754099Y287550D01*
X753849Y287508D01*
X753641Y287342D01*
X753224Y286508D01*
X752933Y286133D01*
X752516Y285883D01*
X752141Y285800D01*
Y287550D01*
G01X806419Y754988D02*
X806544Y754738D01*
X806627Y754446D01*
Y754113D01*
X806502Y753738D01*
X806294Y753446D01*
X806044Y753238D01*
X805627Y753071D01*
X805252Y753029D01*
X804877Y753113D01*
X804627Y753238D01*
X804377Y753488D01*
X804210Y753779D01*
X804127Y754071D01*
Y754363D01*
X804210Y754654D01*
X804335Y754904D01*
X804502Y755113D01*
G01X804627Y756254D02*
X804335Y756504D01*
X804169Y756838D01*
X804127Y757213D01*
X804169Y757546D01*
X804377Y757879D01*
X804627Y758088D01*
X804877Y758129D01*
X805169Y758046D01*
X805377Y757754D01*
X805460Y757463D01*
Y757088D01*
G01Y757463D02*
X805585Y757713D01*
X805794Y757921D01*
X806044Y758004D01*
X806294Y757921D01*
X806502Y757713D01*
X806627Y757338D01*
X806585Y756963D01*
X806419Y756588D01*
G01X806210Y759479D02*
X806460Y759729D01*
X806585Y760021D01*
X806627Y760354D01*
X806544Y760771D01*
X806335Y761063D01*
X806085Y761146D01*
X805835Y761104D01*
X805627Y760938D01*
X805210Y760104D01*
X804919Y759729D01*
X804502Y759479D01*
X804127Y759396D01*
Y761146D01*
G01X806627Y763371D02*
X806544Y763038D01*
X806335Y762788D01*
X806085Y762621D01*
X805752Y762496D01*
X805377Y762454D01*
X805002Y762496D01*
X804669Y762621D01*
X804419Y762788D01*
X804210Y763038D01*
X804127Y763371D01*
X804210Y763704D01*
X804419Y763954D01*
X804669Y764121D01*
X805002Y764246D01*
X805377Y764288D01*
X805752Y764246D01*
X806085Y764121D01*
X806335Y763954D01*
X806544Y763704D01*
X806627Y763371D01*
G01X806210Y765679D02*
X806460Y765929D01*
X806585Y766221D01*
X806627Y766554D01*
X806544Y766971D01*
X806335Y767263D01*
X806085Y767346D01*
X805835Y767304D01*
X805627Y767138D01*
X805210Y766304D01*
X804919Y765929D01*
X804502Y765679D01*
X804127Y765596D01*
Y767346D01*
G01X833570Y-3775D02*
X836070D01*
Y-2734D01*
X835945Y-2400D01*
X835778Y-2192D01*
X835445Y-2109D01*
X835112Y-2192D01*
X834903Y-2442D01*
X834778Y-2734D01*
Y-3775D01*
G01Y-2734D02*
X833570Y-2109D01*
G01X834070Y-759D02*
X833778Y-509D01*
X833612Y-175D01*
X833570Y200D01*
X833612Y533D01*
X833820Y866D01*
X834070Y1075D01*
X834320Y1116D01*
X834612Y1033D01*
X834820Y741D01*
X834903Y450D01*
Y75D01*
G01Y450D02*
X835028Y700D01*
X835237Y908D01*
X835487Y991D01*
X835737Y908D01*
X835945Y700D01*
X836070Y325D01*
X836028Y-50D01*
X835862Y-425D01*
G01X833570Y3175D02*
X834112Y3258D01*
X834570Y3383D01*
X834987Y3550D01*
X835445Y3758D01*
X836070Y4091D01*
Y2425D01*
G01Y6358D02*
X835987Y6025D01*
X835778Y5775D01*
X835528Y5608D01*
X835195Y5483D01*
X834820Y5441D01*
X834445Y5483D01*
X834112Y5608D01*
X833862Y5775D01*
X833653Y6025D01*
X833570Y6358D01*
X833653Y6691D01*
X833862Y6941D01*
X834112Y7108D01*
X834445Y7233D01*
X834820Y7275D01*
X835195Y7233D01*
X835528Y7108D01*
X835778Y6941D01*
X835987Y6691D01*
X836070Y6358D01*
G01X833862Y8750D02*
X833653Y9041D01*
X833570Y9375D01*
X833653Y9708D01*
X833903Y10000D01*
X834278Y10208D01*
X834653Y10291D01*
X835112D01*
X835487Y10208D01*
X835820Y10000D01*
X835987Y9750D01*
X836070Y9458D01*
X835987Y9125D01*
X835820Y8875D01*
X835570Y8708D01*
X835237Y8625D01*
X834945Y8708D01*
X834653Y8916D01*
X834487Y9166D01*
X834445Y9458D01*
X834528Y9791D01*
X834737Y10041D01*
X835112Y10291D01*
G01X819530Y-3856D02*
X822030D01*
Y-2815D01*
X821905Y-2481D01*
X821738Y-2273D01*
X821405Y-2190D01*
X821072Y-2273D01*
X820863Y-2523D01*
X820738Y-2815D01*
Y-3856D01*
G01Y-2815D02*
X819530Y-2190D01*
G01X820030Y-840D02*
X819738Y-590D01*
X819572Y-256D01*
X819530Y119D01*
X819572Y452D01*
X819780Y785D01*
X820030Y994D01*
X820280Y1035D01*
X820572Y952D01*
X820780Y660D01*
X820863Y369D01*
Y-6D01*
G01Y369D02*
X820988Y619D01*
X821197Y827D01*
X821447Y910D01*
X821697Y827D01*
X821905Y619D01*
X822030Y244D01*
X821988Y-131D01*
X821822Y-506D01*
G01X819530Y3094D02*
X820072Y3177D01*
X820530Y3302D01*
X820947Y3469D01*
X821405Y3677D01*
X822030Y4010D01*
Y2344D01*
G01X819530Y6277D02*
X822030D01*
X821530Y5777D01*
G01X819530D02*
Y6777D01*
G01Y9377D02*
X822030D01*
X821530Y8877D01*
G01X819530D02*
Y9877D01*
G01X829570Y-3775D02*
X832070D01*
Y-2734D01*
X831945Y-2400D01*
X831778Y-2192D01*
X831445Y-2109D01*
X831112Y-2192D01*
X830903Y-2442D01*
X830778Y-2734D01*
Y-3775D01*
G01Y-2734D02*
X829570Y-2109D01*
G01X830070Y-759D02*
X829778Y-509D01*
X829612Y-175D01*
X829570Y200D01*
X829612Y533D01*
X829820Y866D01*
X830070Y1075D01*
X830320Y1116D01*
X830612Y1033D01*
X830820Y741D01*
X830903Y450D01*
Y75D01*
G01Y450D02*
X831028Y700D01*
X831237Y908D01*
X831487Y991D01*
X831737Y908D01*
X831945Y700D01*
X832070Y325D01*
X832028Y-50D01*
X831862Y-425D01*
G01X829570Y3175D02*
X830112Y3258D01*
X830570Y3383D01*
X830987Y3550D01*
X831445Y3758D01*
X832070Y4091D01*
Y2425D01*
G01X829570Y6358D02*
X832070D01*
X831570Y5858D01*
G01X829570D02*
Y6858D01*
G01X831653Y8666D02*
X831903Y8916D01*
X832028Y9208D01*
X832070Y9541D01*
X831987Y9958D01*
X831778Y10250D01*
X831528Y10333D01*
X831278Y10291D01*
X831070Y10125D01*
X830653Y9291D01*
X830362Y8916D01*
X829945Y8666D01*
X829570Y8583D01*
Y10333D01*
G01X825456Y-4471D02*
X827956D01*
Y-3430D01*
X827831Y-3096D01*
X827664Y-2888D01*
X827331Y-2805D01*
X826998Y-2888D01*
X826789Y-3138D01*
X826664Y-3430D01*
Y-4471D01*
G01Y-3430D02*
X825456Y-2805D01*
G01X825956Y-1455D02*
X825664Y-1205D01*
X825498Y-871D01*
X825456Y-496D01*
X825498Y-163D01*
X825706Y170D01*
X825956Y379D01*
X826206Y420D01*
X826498Y337D01*
X826706Y45D01*
X826789Y-246D01*
Y-621D01*
G01Y-246D02*
X826914Y4D01*
X827123Y212D01*
X827373Y295D01*
X827623Y212D01*
X827831Y4D01*
X827956Y-371D01*
X827914Y-746D01*
X827748Y-1121D01*
G01X825456Y2479D02*
X825998Y2562D01*
X826456Y2687D01*
X826873Y2854D01*
X827331Y3062D01*
X827956Y3395D01*
Y1729D01*
G01X825456Y5662D02*
X827956D01*
X827456Y5162D01*
G01X825456D02*
Y6162D01*
G01X825956Y7845D02*
X825664Y8095D01*
X825498Y8429D01*
X825456Y8804D01*
X825498Y9137D01*
X825706Y9470D01*
X825956Y9679D01*
X826206Y9720D01*
X826498Y9637D01*
X826706Y9345D01*
X826789Y9054D01*
Y8679D01*
G01Y9054D02*
X826914Y9304D01*
X827123Y9512D01*
X827373Y9595D01*
X827623Y9512D01*
X827831Y9304D01*
X827956Y8929D01*
X827914Y8554D01*
X827748Y8179D01*
G01X837570Y-3775D02*
X840070D01*
Y-2734D01*
X839945Y-2400D01*
X839778Y-2192D01*
X839445Y-2109D01*
X839112Y-2192D01*
X838903Y-2442D01*
X838778Y-2734D01*
Y-3775D01*
G01Y-2734D02*
X837570Y-2109D01*
G01X838070Y-759D02*
X837778Y-509D01*
X837612Y-175D01*
X837570Y200D01*
X837612Y533D01*
X837820Y866D01*
X838070Y1075D01*
X838320Y1116D01*
X838612Y1033D01*
X838820Y741D01*
X838903Y450D01*
Y75D01*
G01Y450D02*
X839028Y700D01*
X839237Y908D01*
X839487Y991D01*
X839737Y908D01*
X839945Y700D01*
X840070Y325D01*
X840028Y-50D01*
X839862Y-425D01*
G01X837570Y3175D02*
X838112Y3258D01*
X838570Y3383D01*
X838987Y3550D01*
X839445Y3758D01*
X840070Y4091D01*
Y2425D01*
G01X837570Y6358D02*
X840070D01*
X839570Y5858D01*
G01X837570D02*
Y6858D01*
G01X838612Y8666D02*
X838903Y8958D01*
X839070Y9208D01*
X839153Y9541D01*
X839070Y9833D01*
X838903Y10041D01*
X838653Y10208D01*
X838362Y10250D01*
X838112Y10208D01*
X837862Y10041D01*
X837653Y9791D01*
X837570Y9500D01*
X837653Y9166D01*
X837903Y8875D01*
X838278Y8708D01*
X838695Y8666D01*
X839237Y8750D01*
X839528Y8875D01*
X839820Y9083D01*
X840028Y9375D01*
X840070Y9666D01*
X839987Y9958D01*
X839778Y10166D01*
G01X832252Y19700D02*
X836252D01*
Y12300D01*
G01X818212Y19619D02*
X822212D01*
Y12219D01*
G01X828252Y19700D02*
X832252D01*
Y12300D01*
G01X824138Y19004D02*
X828138D01*
Y11604D01*
G01X836252Y19700D02*
X840252D01*
Y12300D01*
G01X837330Y141325D02*
X837580Y141450D01*
X837872Y141533D01*
X838205D01*
X838580Y141408D01*
X838872Y141200D01*
X839080Y140950D01*
X839247Y140533D01*
X839289Y140158D01*
X839205Y139783D01*
X839080Y139533D01*
X838830Y139283D01*
X838539Y139116D01*
X838247Y139033D01*
X837955D01*
X837664Y139116D01*
X837414Y139241D01*
X837205Y139408D01*
G01X836064D02*
X835814Y139200D01*
X835522Y139075D01*
X835147Y139033D01*
X834772Y139116D01*
X834480Y139283D01*
X834272Y139575D01*
X834230Y139908D01*
X834314Y140241D01*
X834522Y140450D01*
X834814Y140616D01*
X835105Y140658D01*
X835397Y140616D01*
X835772Y140450D01*
X835647Y141533D01*
X834522D01*
G01X832839Y140075D02*
X832547Y140366D01*
X832297Y140533D01*
X831964Y140616D01*
X831672Y140533D01*
X831464Y140366D01*
X831297Y140116D01*
X831255Y139825D01*
X831297Y139575D01*
X831464Y139325D01*
X831714Y139116D01*
X832005Y139033D01*
X832339Y139116D01*
X832630Y139366D01*
X832797Y139741D01*
X832839Y140158D01*
X832755Y140700D01*
X832630Y140991D01*
X832422Y141283D01*
X832130Y141491D01*
X831839Y141533D01*
X831547Y141450D01*
X831339Y141241D01*
G01X829655Y139325D02*
X829364Y139116D01*
X829030Y139033D01*
X828697Y139116D01*
X828405Y139366D01*
X828197Y139741D01*
X828114Y140116D01*
Y140575D01*
X828197Y140950D01*
X828405Y141283D01*
X828655Y141450D01*
X828947Y141533D01*
X829280Y141450D01*
X829530Y141283D01*
X829697Y141033D01*
X829780Y140700D01*
X829697Y140408D01*
X829489Y140116D01*
X829239Y139950D01*
X828947Y139908D01*
X828614Y139991D01*
X828364Y140200D01*
X828114Y140575D01*
G01X837330Y137351D02*
X837580Y137476D01*
X837872Y137559D01*
X838205D01*
X838580Y137434D01*
X838872Y137226D01*
X839080Y136976D01*
X839247Y136559D01*
X839289Y136184D01*
X839205Y135809D01*
X839080Y135559D01*
X838830Y135309D01*
X838539Y135142D01*
X838247Y135059D01*
X837955D01*
X837664Y135142D01*
X837414Y135267D01*
X837205Y135434D01*
G01X836064D02*
X835814Y135226D01*
X835522Y135101D01*
X835147Y135059D01*
X834772Y135142D01*
X834480Y135309D01*
X834272Y135601D01*
X834230Y135934D01*
X834314Y136267D01*
X834522Y136476D01*
X834814Y136642D01*
X835105Y136684D01*
X835397Y136642D01*
X835772Y136476D01*
X835647Y137559D01*
X834522D01*
G01X832839Y136101D02*
X832547Y136392D01*
X832297Y136559D01*
X831964Y136642D01*
X831672Y136559D01*
X831464Y136392D01*
X831297Y136142D01*
X831255Y135851D01*
X831297Y135601D01*
X831464Y135351D01*
X831714Y135142D01*
X832005Y135059D01*
X832339Y135142D01*
X832630Y135392D01*
X832797Y135767D01*
X832839Y136184D01*
X832755Y136726D01*
X832630Y137017D01*
X832422Y137309D01*
X832130Y137517D01*
X831839Y137559D01*
X831547Y137476D01*
X831339Y137267D01*
G01X828947Y135059D02*
X828655Y135101D01*
X828322Y135226D01*
X828114Y135434D01*
X828030Y135726D01*
X828114Y136017D01*
X828364Y136267D01*
X828739Y136392D01*
X829155D01*
X829405Y136476D01*
X829614Y136684D01*
X829697Y136976D01*
X829572Y137267D01*
X829280Y137476D01*
X828947Y137559D01*
X828614Y137476D01*
X828322Y137267D01*
X828197Y136976D01*
X828280Y136684D01*
X828489Y136476D01*
X828739Y136392D01*
X829155D01*
X829530Y136267D01*
X829780Y136017D01*
X829864Y135726D01*
X829780Y135434D01*
X829572Y135226D01*
X829239Y135101D01*
X828947Y135059D01*
G01X837330Y133437D02*
X837580Y133562D01*
X837872Y133645D01*
X838205D01*
X838580Y133520D01*
X838872Y133312D01*
X839080Y133062D01*
X839247Y132645D01*
X839289Y132270D01*
X839205Y131895D01*
X839080Y131645D01*
X838830Y131395D01*
X838539Y131228D01*
X838247Y131145D01*
X837955D01*
X837664Y131228D01*
X837414Y131353D01*
X837205Y131520D01*
G01X836064D02*
X835814Y131312D01*
X835522Y131187D01*
X835147Y131145D01*
X834772Y131228D01*
X834480Y131395D01*
X834272Y131687D01*
X834230Y132020D01*
X834314Y132353D01*
X834522Y132562D01*
X834814Y132728D01*
X835105Y132770D01*
X835397Y132728D01*
X835772Y132562D01*
X835647Y133645D01*
X834522D01*
G01X832839Y132187D02*
X832547Y132478D01*
X832297Y132645D01*
X831964Y132728D01*
X831672Y132645D01*
X831464Y132478D01*
X831297Y132228D01*
X831255Y131937D01*
X831297Y131687D01*
X831464Y131437D01*
X831714Y131228D01*
X832005Y131145D01*
X832339Y131228D01*
X832630Y131478D01*
X832797Y131853D01*
X832839Y132270D01*
X832755Y132812D01*
X832630Y133103D01*
X832422Y133395D01*
X832130Y133603D01*
X831839Y133645D01*
X831547Y133562D01*
X831339Y133353D01*
G01X829030Y131145D02*
X828947Y131687D01*
X828822Y132145D01*
X828655Y132562D01*
X828447Y133020D01*
X828114Y133645D01*
X829780D01*
G01X837330Y129514D02*
X837580Y129639D01*
X837872Y129722D01*
X838205D01*
X838580Y129597D01*
X838872Y129389D01*
X839080Y129139D01*
X839247Y128722D01*
X839289Y128347D01*
X839205Y127972D01*
X839080Y127722D01*
X838830Y127472D01*
X838539Y127305D01*
X838247Y127222D01*
X837955D01*
X837664Y127305D01*
X837414Y127430D01*
X837205Y127597D01*
G01X836064D02*
X835814Y127389D01*
X835522Y127264D01*
X835147Y127222D01*
X834772Y127305D01*
X834480Y127472D01*
X834272Y127764D01*
X834230Y128097D01*
X834314Y128430D01*
X834522Y128639D01*
X834814Y128805D01*
X835105Y128847D01*
X835397Y128805D01*
X835772Y128639D01*
X835647Y129722D01*
X834522D01*
G01X832839Y128264D02*
X832547Y128555D01*
X832297Y128722D01*
X831964Y128805D01*
X831672Y128722D01*
X831464Y128555D01*
X831297Y128305D01*
X831255Y128014D01*
X831297Y127764D01*
X831464Y127514D01*
X831714Y127305D01*
X832005Y127222D01*
X832339Y127305D01*
X832630Y127555D01*
X832797Y127930D01*
X832839Y128347D01*
X832755Y128889D01*
X832630Y129180D01*
X832422Y129472D01*
X832130Y129680D01*
X831839Y129722D01*
X831547Y129639D01*
X831339Y129430D01*
G01X829739Y128264D02*
X829447Y128555D01*
X829197Y128722D01*
X828864Y128805D01*
X828572Y128722D01*
X828364Y128555D01*
X828197Y128305D01*
X828155Y128014D01*
X828197Y127764D01*
X828364Y127514D01*
X828614Y127305D01*
X828905Y127222D01*
X829239Y127305D01*
X829530Y127555D01*
X829697Y127930D01*
X829739Y128347D01*
X829655Y128889D01*
X829530Y129180D01*
X829322Y129472D01*
X829030Y129680D01*
X828739Y129722D01*
X828447Y129639D01*
X828239Y129430D01*
G01X837330Y125540D02*
X837580Y125665D01*
X837872Y125748D01*
X838205D01*
X838580Y125623D01*
X838872Y125415D01*
X839080Y125165D01*
X839247Y124748D01*
X839289Y124373D01*
X839205Y123998D01*
X839080Y123748D01*
X838830Y123498D01*
X838539Y123331D01*
X838247Y123248D01*
X837955D01*
X837664Y123331D01*
X837414Y123456D01*
X837205Y123623D01*
G01X836064D02*
X835814Y123415D01*
X835522Y123290D01*
X835147Y123248D01*
X834772Y123331D01*
X834480Y123498D01*
X834272Y123790D01*
X834230Y124123D01*
X834314Y124456D01*
X834522Y124665D01*
X834814Y124831D01*
X835105Y124873D01*
X835397Y124831D01*
X835772Y124665D01*
X835647Y125748D01*
X834522D01*
G01X832839Y124290D02*
X832547Y124581D01*
X832297Y124748D01*
X831964Y124831D01*
X831672Y124748D01*
X831464Y124581D01*
X831297Y124331D01*
X831255Y124040D01*
X831297Y123790D01*
X831464Y123540D01*
X831714Y123331D01*
X832005Y123248D01*
X832339Y123331D01*
X832630Y123581D01*
X832797Y123956D01*
X832839Y124373D01*
X832755Y124915D01*
X832630Y125206D01*
X832422Y125498D01*
X832130Y125706D01*
X831839Y125748D01*
X831547Y125665D01*
X831339Y125456D01*
G01X829864Y123623D02*
X829614Y123415D01*
X829322Y123290D01*
X828947Y123248D01*
X828572Y123331D01*
X828280Y123498D01*
X828072Y123790D01*
X828030Y124123D01*
X828114Y124456D01*
X828322Y124665D01*
X828614Y124831D01*
X828905Y124873D01*
X829197Y124831D01*
X829572Y124665D01*
X829447Y125748D01*
X828322D01*
G01X837330Y149199D02*
X837580Y149324D01*
X837872Y149407D01*
X838205D01*
X838580Y149282D01*
X838872Y149074D01*
X839080Y148824D01*
X839247Y148407D01*
X839289Y148032D01*
X839205Y147657D01*
X839080Y147407D01*
X838830Y147157D01*
X838539Y146990D01*
X838247Y146907D01*
X837955D01*
X837664Y146990D01*
X837414Y147115D01*
X837205Y147282D01*
G01X836064D02*
X835814Y147074D01*
X835522Y146949D01*
X835147Y146907D01*
X834772Y146990D01*
X834480Y147157D01*
X834272Y147449D01*
X834230Y147782D01*
X834314Y148115D01*
X834522Y148324D01*
X834814Y148490D01*
X835105Y148532D01*
X835397Y148490D01*
X835772Y148324D01*
X835647Y149407D01*
X834522D01*
G01X832130Y146907D02*
X832047Y147449D01*
X831922Y147907D01*
X831755Y148324D01*
X831547Y148782D01*
X831214Y149407D01*
X832880D01*
G01X828947Y146907D02*
Y149407D01*
X829447Y148907D01*
G01Y146907D02*
X828447D01*
G01X837330Y145237D02*
X837580Y145362D01*
X837872Y145445D01*
X838205D01*
X838580Y145320D01*
X838872Y145112D01*
X839080Y144862D01*
X839247Y144445D01*
X839289Y144070D01*
X839205Y143695D01*
X839080Y143445D01*
X838830Y143195D01*
X838539Y143028D01*
X838247Y142945D01*
X837955D01*
X837664Y143028D01*
X837414Y143153D01*
X837205Y143320D01*
G01X836064D02*
X835814Y143112D01*
X835522Y142987D01*
X835147Y142945D01*
X834772Y143028D01*
X834480Y143195D01*
X834272Y143487D01*
X834230Y143820D01*
X834314Y144153D01*
X834522Y144362D01*
X834814Y144528D01*
X835105Y144570D01*
X835397Y144528D01*
X835772Y144362D01*
X835647Y145445D01*
X834522D01*
G01X832130Y142945D02*
X832047Y143487D01*
X831922Y143945D01*
X831755Y144362D01*
X831547Y144820D01*
X831214Y145445D01*
X832880D01*
G01X828947D02*
X829280Y145362D01*
X829530Y145153D01*
X829697Y144903D01*
X829822Y144570D01*
X829864Y144195D01*
X829822Y143820D01*
X829697Y143487D01*
X829530Y143237D01*
X829280Y143028D01*
X828947Y142945D01*
X828614Y143028D01*
X828364Y143237D01*
X828197Y143487D01*
X828072Y143820D01*
X828030Y144195D01*
X828072Y144570D01*
X828197Y144903D01*
X828364Y145153D01*
X828614Y145362D01*
X828947Y145445D01*
G01X837330Y157073D02*
X837580Y157198D01*
X837872Y157281D01*
X838205D01*
X838580Y157156D01*
X838872Y156948D01*
X839080Y156698D01*
X839247Y156281D01*
X839289Y155906D01*
X839205Y155531D01*
X839080Y155281D01*
X838830Y155031D01*
X838539Y154864D01*
X838247Y154781D01*
X837955D01*
X837664Y154864D01*
X837414Y154989D01*
X837205Y155156D01*
G01X836064D02*
X835814Y154948D01*
X835522Y154823D01*
X835147Y154781D01*
X834772Y154864D01*
X834480Y155031D01*
X834272Y155323D01*
X834230Y155656D01*
X834314Y155989D01*
X834522Y156198D01*
X834814Y156364D01*
X835105Y156406D01*
X835397Y156364D01*
X835772Y156198D01*
X835647Y157281D01*
X834522D01*
G01X832964Y155156D02*
X832714Y154948D01*
X832422Y154823D01*
X832047Y154781D01*
X831672Y154864D01*
X831380Y155031D01*
X831172Y155323D01*
X831130Y155656D01*
X831214Y155989D01*
X831422Y156198D01*
X831714Y156364D01*
X832005Y156406D01*
X832297Y156364D01*
X832672Y156198D01*
X832547Y157281D01*
X831422D01*
G01X829030Y154781D02*
X828947Y155323D01*
X828822Y155781D01*
X828655Y156198D01*
X828447Y156656D01*
X828114Y157281D01*
X829780D01*
G01X837330Y153136D02*
X837580Y153261D01*
X837872Y153344D01*
X838205D01*
X838580Y153219D01*
X838872Y153011D01*
X839080Y152761D01*
X839247Y152344D01*
X839289Y151969D01*
X839205Y151594D01*
X839080Y151344D01*
X838830Y151094D01*
X838539Y150927D01*
X838247Y150844D01*
X837955D01*
X837664Y150927D01*
X837414Y151052D01*
X837205Y151219D01*
G01X836064D02*
X835814Y151011D01*
X835522Y150886D01*
X835147Y150844D01*
X834772Y150927D01*
X834480Y151094D01*
X834272Y151386D01*
X834230Y151719D01*
X834314Y152052D01*
X834522Y152261D01*
X834814Y152427D01*
X835105Y152469D01*
X835397Y152427D01*
X835772Y152261D01*
X835647Y153344D01*
X834522D01*
G01X832964Y151219D02*
X832714Y151011D01*
X832422Y150886D01*
X832047Y150844D01*
X831672Y150927D01*
X831380Y151094D01*
X831172Y151386D01*
X831130Y151719D01*
X831214Y152052D01*
X831422Y152261D01*
X831714Y152427D01*
X832005Y152469D01*
X832297Y152427D01*
X832672Y152261D01*
X832547Y153344D01*
X831422D01*
G01X829739Y151886D02*
X829447Y152177D01*
X829197Y152344D01*
X828864Y152427D01*
X828572Y152344D01*
X828364Y152177D01*
X828197Y151927D01*
X828155Y151636D01*
X828197Y151386D01*
X828364Y151136D01*
X828614Y150927D01*
X828905Y150844D01*
X829239Y150927D01*
X829530Y151177D01*
X829697Y151552D01*
X829739Y151969D01*
X829655Y152511D01*
X829530Y152802D01*
X829322Y153094D01*
X829030Y153302D01*
X828739Y153344D01*
X828447Y153261D01*
X828239Y153052D01*
G01X837033Y184653D02*
X837283Y184778D01*
X837575Y184861D01*
X837908D01*
X838283Y184736D01*
X838575Y184528D01*
X838783Y184278D01*
X838950Y183861D01*
X838992Y183486D01*
X838908Y183111D01*
X838783Y182861D01*
X838533Y182611D01*
X838242Y182444D01*
X837950Y182361D01*
X837658D01*
X837367Y182444D01*
X837117Y182569D01*
X836908Y182736D01*
G01X834933Y182361D02*
X834850Y182903D01*
X834725Y183361D01*
X834558Y183778D01*
X834350Y184236D01*
X834017Y184861D01*
X835683D01*
G01X832667Y182861D02*
X832417Y182569D01*
X832083Y182403D01*
X831708Y182361D01*
X831375Y182403D01*
X831042Y182611D01*
X830833Y182861D01*
X830792Y183111D01*
X830875Y183403D01*
X831167Y183611D01*
X831458Y183694D01*
X831833D01*
G01X831458D02*
X831208Y183819D01*
X831000Y184028D01*
X830917Y184278D01*
X831000Y184528D01*
X831208Y184736D01*
X831583Y184861D01*
X831958Y184819D01*
X832333Y184653D01*
G01X828650Y184861D02*
X828983Y184778D01*
X829233Y184569D01*
X829400Y184319D01*
X829525Y183986D01*
X829567Y183611D01*
X829525Y183236D01*
X829400Y182903D01*
X829233Y182653D01*
X828983Y182444D01*
X828650Y182361D01*
X828317Y182444D01*
X828067Y182653D01*
X827900Y182903D01*
X827775Y183236D01*
X827733Y183611D01*
X827775Y183986D01*
X827900Y184319D01*
X828067Y184569D01*
X828317Y184778D01*
X828650Y184861D01*
G01X837233Y189292D02*
X837483Y189417D01*
X837775Y189500D01*
X838108D01*
X838483Y189375D01*
X838775Y189167D01*
X838983Y188917D01*
X839150Y188500D01*
X839192Y188125D01*
X839108Y187750D01*
X838983Y187500D01*
X838733Y187250D01*
X838442Y187083D01*
X838150Y187000D01*
X837858D01*
X837567Y187083D01*
X837317Y187208D01*
X837108Y187375D01*
G01X835133Y187000D02*
X835050Y187542D01*
X834925Y188000D01*
X834758Y188417D01*
X834550Y188875D01*
X834217Y189500D01*
X835883D01*
G01X832742Y189083D02*
X832492Y189333D01*
X832200Y189458D01*
X831867Y189500D01*
X831450Y189417D01*
X831158Y189208D01*
X831075Y188958D01*
X831117Y188708D01*
X831283Y188500D01*
X832117Y188083D01*
X832492Y187792D01*
X832742Y187375D01*
X832825Y187000D01*
X831075D01*
G01X829558Y187292D02*
X829267Y187083D01*
X828933Y187000D01*
X828600Y187083D01*
X828308Y187333D01*
X828100Y187708D01*
X828017Y188083D01*
Y188542D01*
X828100Y188917D01*
X828308Y189250D01*
X828558Y189417D01*
X828850Y189500D01*
X829183Y189417D01*
X829433Y189250D01*
X829600Y189000D01*
X829683Y188667D01*
X829600Y188375D01*
X829392Y188083D01*
X829142Y187917D01*
X828850Y187875D01*
X828517Y187958D01*
X828267Y188167D01*
X828017Y188542D01*
G01X829885Y781448D02*
X828093D01*
X827718Y781615D01*
X827468Y781948D01*
X827385Y782365D01*
X827468Y782782D01*
X827718Y783115D01*
X828093Y783282D01*
X829885D01*
G01X827385Y785382D02*
X827927Y785465D01*
X828385Y785590D01*
X828802Y785757D01*
X829260Y785965D01*
X829885Y786298D01*
Y784632D01*
G01X827385Y788482D02*
X827927Y788565D01*
X828385Y788690D01*
X828802Y788857D01*
X829260Y789065D01*
X829885Y789398D01*
Y787732D01*
G01X831385Y781532D02*
X833885D01*
Y782573D01*
X833760Y782907D01*
X833593Y783115D01*
X833260Y783198D01*
X832927Y783115D01*
X832718Y782865D01*
X832593Y782573D01*
Y781532D01*
G01Y782573D02*
X831385Y783198D01*
G01Y785465D02*
X833885D01*
X833385Y784965D01*
G01X831385D02*
Y785965D01*
G01Y789065D02*
X833885D01*
X832093Y787523D01*
Y789607D01*
G01X831760Y790748D02*
X831552Y790998D01*
X831427Y791290D01*
X831385Y791665D01*
X831468Y792040D01*
X831635Y792332D01*
X831927Y792540D01*
X832260Y792582D01*
X832593Y792498D01*
X832802Y792290D01*
X832968Y791998D01*
X833010Y791707D01*
X832968Y791415D01*
X832802Y791040D01*
X833885Y791165D01*
Y792290D01*
G01X823385Y781532D02*
X825885D01*
Y782573D01*
X825760Y782907D01*
X825593Y783115D01*
X825260Y783198D01*
X824927Y783115D01*
X824718Y782865D01*
X824593Y782573D01*
Y781532D01*
G01Y782573D02*
X823385Y783198D01*
G01X825468Y784673D02*
X825718Y784923D01*
X825843Y785215D01*
X825885Y785548D01*
X825802Y785965D01*
X825593Y786257D01*
X825343Y786340D01*
X825093Y786298D01*
X824885Y786132D01*
X824468Y785298D01*
X824177Y784923D01*
X823760Y784673D01*
X823385Y784590D01*
Y786340D01*
G01Y788482D02*
X823927Y788565D01*
X824385Y788690D01*
X824802Y788857D01*
X825260Y789065D01*
X825885Y789398D01*
Y787732D01*
G01X823385Y791665D02*
X825885D01*
X825385Y791165D01*
G01X823385D02*
Y792165D01*
G01X839000Y780200D02*
X843000D01*
Y772800D01*
G01X838195Y753026D02*
X840695D01*
Y754067D01*
X840570Y754401D01*
X840403Y754609D01*
X840070Y754692D01*
X839737Y754609D01*
X839528Y754359D01*
X839403Y754067D01*
Y753026D01*
G01Y754067D02*
X838195Y754692D01*
G01X838695Y756042D02*
X838403Y756292D01*
X838237Y756626D01*
X838195Y757001D01*
X838237Y757334D01*
X838445Y757667D01*
X838695Y757876D01*
X838945Y757917D01*
X839237Y757834D01*
X839445Y757542D01*
X839528Y757251D01*
Y756876D01*
G01Y757251D02*
X839653Y757501D01*
X839862Y757709D01*
X840112Y757792D01*
X840362Y757709D01*
X840570Y757501D01*
X840695Y757126D01*
X840653Y756751D01*
X840487Y756376D01*
G01X840278Y759267D02*
X840528Y759517D01*
X840653Y759809D01*
X840695Y760142D01*
X840612Y760559D01*
X840403Y760851D01*
X840153Y760934D01*
X839903Y760892D01*
X839695Y760726D01*
X839278Y759892D01*
X838987Y759517D01*
X838570Y759267D01*
X838195Y759184D01*
Y760934D01*
G01X840278Y762367D02*
X840528Y762617D01*
X840653Y762909D01*
X840695Y763242D01*
X840612Y763659D01*
X840403Y763951D01*
X840153Y764034D01*
X839903Y763992D01*
X839695Y763826D01*
X839278Y762992D01*
X838987Y762617D01*
X838570Y762367D01*
X838195Y762284D01*
Y764034D01*
G01Y766176D02*
X838737Y766259D01*
X839195Y766384D01*
X839612Y766551D01*
X840070Y766759D01*
X840695Y767092D01*
Y765426D01*
G01X819385Y781532D02*
X821885D01*
Y782573D01*
X821760Y782907D01*
X821593Y783115D01*
X821260Y783198D01*
X820927Y783115D01*
X820718Y782865D01*
X820593Y782573D01*
Y781532D01*
G01Y782573D02*
X819385Y783198D01*
G01X819885Y784548D02*
X819593Y784798D01*
X819427Y785132D01*
X819385Y785507D01*
X819427Y785840D01*
X819635Y786173D01*
X819885Y786382D01*
X820135Y786423D01*
X820427Y786340D01*
X820635Y786048D01*
X820718Y785757D01*
Y785382D01*
G01Y785757D02*
X820843Y786007D01*
X821052Y786215D01*
X821302Y786298D01*
X821552Y786215D01*
X821760Y786007D01*
X821885Y785632D01*
X821843Y785257D01*
X821677Y784882D01*
G01X821468Y787773D02*
X821718Y788023D01*
X821843Y788315D01*
X821885Y788648D01*
X821802Y789065D01*
X821593Y789357D01*
X821343Y789440D01*
X821093Y789398D01*
X820885Y789232D01*
X820468Y788398D01*
X820177Y788023D01*
X819760Y787773D01*
X819385Y787690D01*
Y789440D01*
G01Y792165D02*
X821885D01*
X820093Y790623D01*
Y792707D01*
G01X819385Y794765D02*
X821885D01*
X821385Y794265D01*
G01X819385D02*
Y795265D01*
G01X839000Y772800D02*
X835000D01*
Y780200D01*
G01X808240Y753150D02*
X810740D01*
Y754191D01*
X810615Y754525D01*
X810448Y754733D01*
X810115Y754816D01*
X809782Y754733D01*
X809573Y754483D01*
X809448Y754191D01*
Y753150D01*
G01Y754191D02*
X808240Y754816D01*
G01X808740Y756166D02*
X808448Y756416D01*
X808282Y756750D01*
X808240Y757125D01*
X808282Y757458D01*
X808490Y757791D01*
X808740Y758000D01*
X808990Y758041D01*
X809282Y757958D01*
X809490Y757666D01*
X809573Y757375D01*
Y757000D01*
G01Y757375D02*
X809698Y757625D01*
X809907Y757833D01*
X810157Y757916D01*
X810407Y757833D01*
X810615Y757625D01*
X810740Y757250D01*
X810698Y756875D01*
X810532Y756500D01*
G01X810323Y759391D02*
X810573Y759641D01*
X810698Y759933D01*
X810740Y760266D01*
X810657Y760683D01*
X810448Y760975D01*
X810198Y761058D01*
X809948Y761016D01*
X809740Y760850D01*
X809323Y760016D01*
X809032Y759641D01*
X808615Y759391D01*
X808240Y759308D01*
Y761058D01*
G01Y763783D02*
X810740D01*
X808948Y762241D01*
Y764325D01*
G01X810323Y765591D02*
X810573Y765841D01*
X810698Y766133D01*
X810740Y766466D01*
X810657Y766883D01*
X810448Y767175D01*
X810198Y767258D01*
X809948Y767216D01*
X809740Y767050D01*
X809323Y766216D01*
X809032Y765841D01*
X808615Y765591D01*
X808240Y765508D01*
Y767258D01*
G01X830120Y766232D02*
Y768732D01*
X829079D01*
X828745Y768607D01*
X828537Y768440D01*
X828454Y768107D01*
X828537Y767774D01*
X828787Y767565D01*
X829079Y767440D01*
X830120D01*
G01X829079D02*
X828454Y766232D01*
G01X827104Y766732D02*
X826854Y766440D01*
X826520Y766274D01*
X826145Y766232D01*
X825812Y766274D01*
X825479Y766482D01*
X825270Y766732D01*
X825229Y766982D01*
X825312Y767274D01*
X825604Y767482D01*
X825895Y767565D01*
X826270D01*
G01X825895D02*
X825645Y767690D01*
X825437Y767899D01*
X825354Y768149D01*
X825437Y768399D01*
X825645Y768607D01*
X826020Y768732D01*
X826395Y768690D01*
X826770Y768524D01*
G01X823879Y768315D02*
X823629Y768565D01*
X823337Y768690D01*
X823004Y768732D01*
X822587Y768649D01*
X822295Y768440D01*
X822212Y768190D01*
X822254Y767940D01*
X822420Y767732D01*
X823254Y767315D01*
X823629Y767024D01*
X823879Y766607D01*
X823962Y766232D01*
X822212D01*
G01X819987D02*
Y768732D01*
X820487Y768232D01*
G01Y766232D02*
X819487D01*
G01X817679Y768315D02*
X817429Y768565D01*
X817137Y768690D01*
X816804Y768732D01*
X816387Y768649D01*
X816095Y768440D01*
X816012Y768190D01*
X816054Y767940D01*
X816220Y767732D01*
X817054Y767315D01*
X817429Y767024D01*
X817679Y766607D01*
X817762Y766232D01*
X816012D01*
G01X836506Y754820D02*
X836631Y754570D01*
X836714Y754278D01*
Y753945D01*
X836589Y753570D01*
X836381Y753278D01*
X836131Y753070D01*
X835714Y752903D01*
X835339Y752861D01*
X834964Y752945D01*
X834714Y753070D01*
X834464Y753320D01*
X834297Y753611D01*
X834214Y753903D01*
Y754195D01*
X834297Y754486D01*
X834422Y754736D01*
X834589Y754945D01*
G01X834714Y756086D02*
X834422Y756336D01*
X834256Y756670D01*
X834214Y757045D01*
X834256Y757378D01*
X834464Y757711D01*
X834714Y757920D01*
X834964Y757961D01*
X835256Y757878D01*
X835464Y757586D01*
X835547Y757295D01*
Y756920D01*
G01Y757295D02*
X835672Y757545D01*
X835881Y757753D01*
X836131Y757836D01*
X836381Y757753D01*
X836589Y757545D01*
X836714Y757170D01*
X836672Y756795D01*
X836506Y756420D01*
G01X836297Y759311D02*
X836547Y759561D01*
X836672Y759853D01*
X836714Y760186D01*
X836631Y760603D01*
X836422Y760895D01*
X836172Y760978D01*
X835922Y760936D01*
X835714Y760770D01*
X835297Y759936D01*
X835006Y759561D01*
X834589Y759311D01*
X834214Y759228D01*
Y760978D01*
G01X836714Y763203D02*
X836631Y762870D01*
X836422Y762620D01*
X836172Y762453D01*
X835839Y762328D01*
X835464Y762286D01*
X835089Y762328D01*
X834756Y762453D01*
X834506Y762620D01*
X834297Y762870D01*
X834214Y763203D01*
X834297Y763536D01*
X834506Y763786D01*
X834756Y763953D01*
X835089Y764078D01*
X835464Y764120D01*
X835839Y764078D01*
X836172Y763953D01*
X836422Y763786D01*
X836631Y763536D01*
X836714Y763203D01*
G01X834714Y765386D02*
X834422Y765636D01*
X834256Y765970D01*
X834214Y766345D01*
X834256Y766678D01*
X834464Y767011D01*
X834714Y767220D01*
X834964Y767261D01*
X835256Y767178D01*
X835464Y766886D01*
X835547Y766595D01*
Y766220D01*
G01Y766595D02*
X835672Y766845D01*
X835881Y767053D01*
X836131Y767136D01*
X836381Y767053D01*
X836589Y766845D01*
X836714Y766470D01*
X836672Y766095D01*
X836506Y765720D01*
G01X818058Y755565D02*
X818183Y755315D01*
X818266Y755023D01*
Y754690D01*
X818141Y754315D01*
X817933Y754023D01*
X817683Y753815D01*
X817266Y753648D01*
X816891Y753606D01*
X816516Y753690D01*
X816266Y753815D01*
X816016Y754065D01*
X815849Y754356D01*
X815766Y754648D01*
Y754940D01*
X815849Y755231D01*
X815974Y755481D01*
X816141Y755690D01*
G01X815766Y758248D02*
X818266D01*
X816474Y756706D01*
Y758790D01*
G01X815766Y760848D02*
X818266D01*
X817766Y760348D01*
G01X815766D02*
Y761348D01*
G01X816808Y763156D02*
X817099Y763448D01*
X817266Y763698D01*
X817349Y764031D01*
X817266Y764323D01*
X817099Y764531D01*
X816849Y764698D01*
X816558Y764740D01*
X816308Y764698D01*
X816058Y764531D01*
X815849Y764281D01*
X815766Y763990D01*
X815849Y763656D01*
X816099Y763365D01*
X816474Y763198D01*
X816891Y763156D01*
X817433Y763240D01*
X817724Y763365D01*
X818016Y763573D01*
X818224Y763865D01*
X818266Y764156D01*
X818183Y764448D01*
X817974Y764656D01*
G01X829910Y795642D02*
X832410D01*
Y796683D01*
X832285Y797017D01*
X832118Y797225D01*
X831785Y797308D01*
X831452Y797225D01*
X831243Y796975D01*
X831118Y796683D01*
Y795642D01*
G01Y796683D02*
X829910Y797308D01*
G01X830410Y798658D02*
X830118Y798908D01*
X829952Y799242D01*
X829910Y799617D01*
X829952Y799950D01*
X830160Y800283D01*
X830410Y800492D01*
X830660Y800533D01*
X830952Y800450D01*
X831160Y800158D01*
X831243Y799867D01*
Y799492D01*
G01Y799867D02*
X831368Y800117D01*
X831577Y800325D01*
X831827Y800408D01*
X832077Y800325D01*
X832285Y800117D01*
X832410Y799742D01*
X832368Y799367D01*
X832202Y798992D01*
G01X831993Y801883D02*
X832243Y802133D01*
X832368Y802425D01*
X832410Y802758D01*
X832327Y803175D01*
X832118Y803467D01*
X831868Y803550D01*
X831618Y803508D01*
X831410Y803342D01*
X830993Y802508D01*
X830702Y802133D01*
X830285Y801883D01*
X829910Y801800D01*
Y803550D01*
G01Y806275D02*
X832410D01*
X830618Y804733D01*
Y806817D01*
G01X832410Y808875D02*
X832327Y808542D01*
X832118Y808292D01*
X831868Y808125D01*
X831535Y808000D01*
X831160Y807958D01*
X830785Y808000D01*
X830452Y808125D01*
X830202Y808292D01*
X829993Y808542D01*
X829910Y808875D01*
X829993Y809208D01*
X830202Y809458D01*
X830452Y809625D01*
X830785Y809750D01*
X831160Y809792D01*
X831535Y809750D01*
X831868Y809625D01*
X832118Y809458D01*
X832327Y809208D01*
X832410Y808875D01*
G01X837910Y795642D02*
X840410D01*
Y796683D01*
X840285Y797017D01*
X840118Y797225D01*
X839785Y797308D01*
X839452Y797225D01*
X839243Y796975D01*
X839118Y796683D01*
Y795642D01*
G01Y796683D02*
X837910Y797308D01*
G01X838410Y798658D02*
X838118Y798908D01*
X837952Y799242D01*
X837910Y799617D01*
X837952Y799950D01*
X838160Y800283D01*
X838410Y800492D01*
X838660Y800533D01*
X838952Y800450D01*
X839160Y800158D01*
X839243Y799867D01*
Y799492D01*
G01Y799867D02*
X839368Y800117D01*
X839577Y800325D01*
X839827Y800408D01*
X840077Y800325D01*
X840285Y800117D01*
X840410Y799742D01*
X840368Y799367D01*
X840202Y798992D01*
G01X839993Y801883D02*
X840243Y802133D01*
X840368Y802425D01*
X840410Y802758D01*
X840327Y803175D01*
X840118Y803467D01*
X839868Y803550D01*
X839618Y803508D01*
X839410Y803342D01*
X838993Y802508D01*
X838702Y802133D01*
X838285Y801883D01*
X837910Y801800D01*
Y803550D01*
G01Y805775D02*
X840410D01*
X839910Y805275D01*
G01X837910D02*
Y806275D01*
G01Y808875D02*
X840410D01*
X839910Y808375D01*
G01X837910D02*
Y809375D01*
G01X836202Y797392D02*
X836327Y797142D01*
X836410Y796850D01*
Y796517D01*
X836285Y796142D01*
X836077Y795850D01*
X835827Y795642D01*
X835410Y795475D01*
X835035Y795433D01*
X834660Y795517D01*
X834410Y795642D01*
X834160Y795892D01*
X833993Y796183D01*
X833910Y796475D01*
Y796767D01*
X833993Y797058D01*
X834118Y797308D01*
X834285Y797517D01*
G01X833910Y799575D02*
X833952Y799867D01*
X834077Y800200D01*
X834285Y800408D01*
X834577Y800492D01*
X834868Y800408D01*
X835118Y800158D01*
X835243Y799783D01*
Y799367D01*
X835327Y799117D01*
X835535Y798908D01*
X835827Y798825D01*
X836118Y798950D01*
X836327Y799242D01*
X836410Y799575D01*
X836327Y799908D01*
X836118Y800200D01*
X835827Y800325D01*
X835535Y800242D01*
X835327Y800033D01*
X835243Y799783D01*
Y799367D01*
X835118Y798992D01*
X834868Y798742D01*
X834577Y798658D01*
X834285Y798742D01*
X834077Y798950D01*
X833952Y799283D01*
X833910Y799575D01*
G01X836410Y802675D02*
X836327Y802342D01*
X836118Y802092D01*
X835868Y801925D01*
X835535Y801800D01*
X835160Y801758D01*
X834785Y801800D01*
X834452Y801925D01*
X834202Y802092D01*
X833993Y802342D01*
X833910Y802675D01*
X833993Y803008D01*
X834202Y803258D01*
X834452Y803425D01*
X834785Y803550D01*
X835160Y803592D01*
X835535Y803550D01*
X835868Y803425D01*
X836118Y803258D01*
X836327Y803008D01*
X836410Y802675D01*
G01X834202Y805067D02*
X833993Y805358D01*
X833910Y805692D01*
X833993Y806025D01*
X834243Y806317D01*
X834618Y806525D01*
X834993Y806608D01*
X835452D01*
X835827Y806525D01*
X836160Y806317D01*
X836327Y806067D01*
X836410Y805775D01*
X836327Y805442D01*
X836160Y805192D01*
X835910Y805025D01*
X835577Y804942D01*
X835285Y805025D01*
X834993Y805233D01*
X834827Y805483D01*
X834785Y805775D01*
X834868Y806108D01*
X835077Y806358D01*
X835452Y806608D01*
G01X835993Y808083D02*
X836243Y808333D01*
X836368Y808625D01*
X836410Y808958D01*
X836327Y809375D01*
X836118Y809667D01*
X835868Y809750D01*
X835618Y809708D01*
X835410Y809542D01*
X834993Y808708D01*
X834702Y808333D01*
X834285Y808083D01*
X833910Y808000D01*
Y809750D01*
G01X845570Y-3775D02*
X848070D01*
Y-2734D01*
X847945Y-2400D01*
X847778Y-2192D01*
X847445Y-2109D01*
X847112Y-2192D01*
X846903Y-2442D01*
X846778Y-2734D01*
Y-3775D01*
G01Y-2734D02*
X845570Y-2109D01*
G01X846070Y-759D02*
X845778Y-509D01*
X845612Y-175D01*
X845570Y200D01*
X845612Y533D01*
X845820Y866D01*
X846070Y1075D01*
X846320Y1116D01*
X846612Y1033D01*
X846820Y741D01*
X846903Y450D01*
Y75D01*
G01Y450D02*
X847028Y700D01*
X847237Y908D01*
X847487Y991D01*
X847737Y908D01*
X847945Y700D01*
X848070Y325D01*
X848028Y-50D01*
X847862Y-425D01*
G01X845570Y3175D02*
X846112Y3258D01*
X846570Y3383D01*
X846987Y3550D01*
X847445Y3758D01*
X848070Y4091D01*
Y2425D01*
G01X845570Y6358D02*
X848070D01*
X847570Y5858D01*
G01X845570D02*
Y6858D01*
G01X848070Y9458D02*
X847987Y9125D01*
X847778Y8875D01*
X847528Y8708D01*
X847195Y8583D01*
X846820Y8541D01*
X846445Y8583D01*
X846112Y8708D01*
X845862Y8875D01*
X845653Y9125D01*
X845570Y9458D01*
X845653Y9791D01*
X845862Y10041D01*
X846112Y10208D01*
X846445Y10333D01*
X846820Y10375D01*
X847195Y10333D01*
X847528Y10208D01*
X847778Y10041D01*
X847987Y9791D01*
X848070Y9458D01*
G01X841570Y-3775D02*
X844070D01*
Y-2734D01*
X843945Y-2400D01*
X843778Y-2192D01*
X843445Y-2109D01*
X843112Y-2192D01*
X842903Y-2442D01*
X842778Y-2734D01*
Y-3775D01*
G01Y-2734D02*
X841570Y-2109D01*
G01X842070Y-759D02*
X841778Y-509D01*
X841612Y-175D01*
X841570Y200D01*
X841612Y533D01*
X841820Y866D01*
X842070Y1075D01*
X842320Y1116D01*
X842612Y1033D01*
X842820Y741D01*
X842903Y450D01*
Y75D01*
G01Y450D02*
X843028Y700D01*
X843237Y908D01*
X843487Y991D01*
X843737Y908D01*
X843945Y700D01*
X844070Y325D01*
X844028Y-50D01*
X843862Y-425D01*
G01X841570Y3175D02*
X842112Y3258D01*
X842570Y3383D01*
X842987Y3550D01*
X843445Y3758D01*
X844070Y4091D01*
Y2425D01*
G01X841570Y6358D02*
X844070D01*
X843570Y5858D01*
G01X841570D02*
Y6858D01*
G01X841945Y8541D02*
X841737Y8791D01*
X841612Y9083D01*
X841570Y9458D01*
X841653Y9833D01*
X841820Y10125D01*
X842112Y10333D01*
X842445Y10375D01*
X842778Y10291D01*
X842987Y10083D01*
X843153Y9791D01*
X843195Y9500D01*
X843153Y9208D01*
X842987Y8833D01*
X844070Y8958D01*
Y10083D01*
G01X866799Y5702D02*
X867132Y5744D01*
X867424Y5910D01*
X867674Y6160D01*
X867841Y6452D01*
X867924Y6785D01*
Y7119D01*
X867841Y7452D01*
X867674Y7744D01*
X867424Y7994D01*
X867132Y8160D01*
X866799Y8202D01*
X866466Y8160D01*
X866174Y7994D01*
X865924Y7744D01*
X865757Y7452D01*
X865674Y7119D01*
Y6785D01*
X865757Y6452D01*
X865924Y6160D01*
X866174Y5910D01*
X866466Y5744D01*
X866799Y5702D01*
G01X866466Y6369D02*
X865966Y5702D01*
G01X864616Y6202D02*
X864366Y5910D01*
X864032Y5744D01*
X863657Y5702D01*
X863324Y5744D01*
X862991Y5952D01*
X862782Y6202D01*
X862741Y6452D01*
X862824Y6744D01*
X863116Y6952D01*
X863407Y7035D01*
X863782D01*
G01X863407D02*
X863157Y7160D01*
X862949Y7369D01*
X862866Y7619D01*
X862949Y7869D01*
X863157Y8077D01*
X863532Y8202D01*
X863907Y8160D01*
X864282Y7994D01*
G01X861391Y7785D02*
X861141Y8035D01*
X860849Y8160D01*
X860516Y8202D01*
X860099Y8119D01*
X859807Y7910D01*
X859724Y7660D01*
X859766Y7410D01*
X859932Y7202D01*
X860766Y6785D01*
X861141Y6494D01*
X861391Y6077D01*
X861474Y5702D01*
X859724D01*
G01X857499Y8202D02*
X857832Y8119D01*
X858082Y7910D01*
X858249Y7660D01*
X858374Y7327D01*
X858416Y6952D01*
X858374Y6577D01*
X858249Y6244D01*
X858082Y5994D01*
X857832Y5785D01*
X857499Y5702D01*
X857166Y5785D01*
X856916Y5994D01*
X856749Y6244D01*
X856624Y6577D01*
X856582Y6952D01*
X856624Y7327D01*
X856749Y7660D01*
X856916Y7910D01*
X857166Y8119D01*
X857499Y8202D01*
G01X855191Y7785D02*
X854941Y8035D01*
X854649Y8160D01*
X854316Y8202D01*
X853899Y8119D01*
X853607Y7910D01*
X853524Y7660D01*
X853566Y7410D01*
X853732Y7202D01*
X854566Y6785D01*
X854941Y6494D01*
X855191Y6077D01*
X855274Y5702D01*
X853524D01*
G01X863867Y36783D02*
X862075D01*
X861700Y36950D01*
X861450Y37283D01*
X861367Y37700D01*
X861450Y38117D01*
X861700Y38450D01*
X862075Y38617D01*
X863867D01*
G01X861367Y40800D02*
X861409Y41092D01*
X861534Y41425D01*
X861742Y41633D01*
X862034Y41717D01*
X862325Y41633D01*
X862575Y41383D01*
X862700Y41008D01*
Y40592D01*
X862784Y40342D01*
X862992Y40133D01*
X863284Y40050D01*
X863575Y40175D01*
X863784Y40467D01*
X863867Y40800D01*
X863784Y41133D01*
X863575Y41425D01*
X863284Y41550D01*
X862992Y41467D01*
X862784Y41258D01*
X862700Y41008D01*
Y40592D01*
X862575Y40217D01*
X862325Y39967D01*
X862034Y39883D01*
X861742Y39967D01*
X861534Y40175D01*
X861409Y40508D01*
X861367Y40800D01*
G01Y43900D02*
X863867D01*
X863367Y43400D01*
G01X861367D02*
Y44400D01*
G01X865500Y47300D02*
Y33900D01*
G01D02*
X875500D01*
G01X844252Y19700D02*
X848252D01*
Y12300D01*
G01X871100Y32700D02*
X875100D01*
Y25300D01*
G01X840252Y19700D02*
X844252D01*
Y12300D01*
G01X853400Y22700D02*
X867400D01*
G01X853400Y9700D02*
Y22700D01*
G01X867400Y9700D02*
X853400D01*
G01X867400Y22700D02*
Y9700D01*
G01X875500Y47300D02*
X865500D01*
G01X875200Y73967D02*
Y71467D01*
G01X876158Y73967D02*
X874242D01*
G01X872933Y71467D02*
Y73967D01*
X871933D01*
X871600Y73842D01*
X871350Y73550D01*
X871267Y73217D01*
X871350Y72884D01*
X871558Y72634D01*
X871933Y72509D01*
X872933D01*
G01X869792Y73550D02*
X869542Y73800D01*
X869250Y73925D01*
X868917Y73967D01*
X868500Y73884D01*
X868208Y73675D01*
X868125Y73425D01*
X868167Y73175D01*
X868333Y72967D01*
X869167Y72550D01*
X869542Y72259D01*
X869792Y71842D01*
X869875Y71467D01*
X868125D01*
G01X865900D02*
Y73967D01*
X866400Y73467D01*
G01Y71467D02*
X865400D01*
G01X863717Y71967D02*
X863467Y71675D01*
X863133Y71509D01*
X862758Y71467D01*
X862425Y71509D01*
X862092Y71717D01*
X861883Y71967D01*
X861842Y72217D01*
X861925Y72509D01*
X862217Y72717D01*
X862508Y72800D01*
X862883D01*
G01X862508D02*
X862258Y72925D01*
X862050Y73134D01*
X861967Y73384D01*
X862050Y73634D01*
X862258Y73842D01*
X862633Y73967D01*
X863008Y73925D01*
X863383Y73759D01*
G01X877778Y60825D02*
X878028Y60950D01*
X878320Y61033D01*
X878653D01*
X879028Y60908D01*
X879320Y60700D01*
X879528Y60450D01*
X879695Y60033D01*
X879737Y59658D01*
X879653Y59283D01*
X879528Y59033D01*
X879278Y58783D01*
X878987Y58616D01*
X878695Y58533D01*
X878403D01*
X878112Y58616D01*
X877862Y58741D01*
X877653Y58908D01*
G01X876512Y59033D02*
X876262Y58741D01*
X875928Y58575D01*
X875553Y58533D01*
X875220Y58575D01*
X874887Y58783D01*
X874678Y59033D01*
X874637Y59283D01*
X874720Y59575D01*
X875012Y59783D01*
X875303Y59866D01*
X875678D01*
G01X875303D02*
X875053Y59991D01*
X874845Y60200D01*
X874762Y60450D01*
X874845Y60700D01*
X875053Y60908D01*
X875428Y61033D01*
X875803Y60991D01*
X876178Y60825D01*
G01X872578Y58533D02*
X872495Y59075D01*
X872370Y59533D01*
X872203Y59950D01*
X871995Y60408D01*
X871662Y61033D01*
X873328D01*
G01X870312Y59033D02*
X870062Y58741D01*
X869728Y58575D01*
X869353Y58533D01*
X869020Y58575D01*
X868687Y58783D01*
X868478Y59033D01*
X868437Y59283D01*
X868520Y59575D01*
X868812Y59783D01*
X869103Y59866D01*
X869478D01*
G01X869103D02*
X868853Y59991D01*
X868645Y60200D01*
X868562Y60450D01*
X868645Y60700D01*
X868853Y60908D01*
X869228Y61033D01*
X869603Y60991D01*
X869978Y60825D01*
G01X851037Y91121D02*
X853537D01*
Y92162D01*
X853412Y92496D01*
X853245Y92704D01*
X852912Y92787D01*
X852579Y92704D01*
X852370Y92454D01*
X852245Y92162D01*
Y91121D01*
G01Y92162D02*
X851037Y92787D01*
G01X852079Y94262D02*
X852370Y94554D01*
X852537Y94804D01*
X852620Y95137D01*
X852537Y95429D01*
X852370Y95637D01*
X852120Y95804D01*
X851829Y95846D01*
X851579Y95804D01*
X851329Y95637D01*
X851120Y95387D01*
X851037Y95096D01*
X851120Y94762D01*
X851370Y94471D01*
X851745Y94304D01*
X852162Y94262D01*
X852704Y94346D01*
X852995Y94471D01*
X853287Y94679D01*
X853495Y94971D01*
X853537Y95262D01*
X853454Y95554D01*
X853245Y95762D01*
G01X851537Y97237D02*
X851245Y97487D01*
X851079Y97821D01*
X851037Y98196D01*
X851079Y98529D01*
X851287Y98862D01*
X851537Y99071D01*
X851787Y99112D01*
X852079Y99029D01*
X852287Y98737D01*
X852370Y98446D01*
Y98071D01*
G01Y98446D02*
X852495Y98696D01*
X852704Y98904D01*
X852954Y98987D01*
X853204Y98904D01*
X853412Y98696D01*
X853537Y98321D01*
X853495Y97946D01*
X853329Y97571D01*
G01X854400Y82100D02*
X850400D01*
Y89500D01*
G01X873000Y84200D02*
X877000D01*
Y76800D01*
G01Y87800D02*
X873000D01*
Y95200D01*
G01Y76800D02*
X869000D01*
Y84200D01*
G01X846737Y91221D02*
X849237D01*
Y92262D01*
X849112Y92596D01*
X848945Y92804D01*
X848612Y92887D01*
X848279Y92804D01*
X848070Y92554D01*
X847945Y92262D01*
Y91221D01*
G01Y92262D02*
X846737Y92887D01*
G01X848820Y94362D02*
X849070Y94612D01*
X849195Y94904D01*
X849237Y95237D01*
X849154Y95654D01*
X848945Y95946D01*
X848695Y96029D01*
X848445Y95987D01*
X848237Y95821D01*
X847820Y94987D01*
X847529Y94612D01*
X847112Y94362D01*
X846737Y94279D01*
Y96029D01*
G01X847029Y97546D02*
X846820Y97837D01*
X846737Y98171D01*
X846820Y98504D01*
X847070Y98796D01*
X847445Y99004D01*
X847820Y99087D01*
X848279D01*
X848654Y99004D01*
X848987Y98796D01*
X849154Y98546D01*
X849237Y98254D01*
X849154Y97921D01*
X848987Y97671D01*
X848737Y97504D01*
X848404Y97421D01*
X848112Y97504D01*
X847820Y97712D01*
X847654Y97962D01*
X847612Y98254D01*
X847695Y98587D01*
X847904Y98837D01*
X848279Y99087D01*
G01X850100Y82200D02*
X846100D01*
Y89600D01*
G01X871618Y142147D02*
Y139647D01*
G01X872576Y142147D02*
X870660D01*
G01X869351Y139647D02*
Y142147D01*
X868351D01*
X868018Y142022D01*
X867768Y141730D01*
X867685Y141397D01*
X867768Y141064D01*
X867976Y140814D01*
X868351Y140689D01*
X869351D01*
G01X866210Y141730D02*
X865960Y141980D01*
X865668Y142105D01*
X865335Y142147D01*
X864918Y142064D01*
X864626Y141855D01*
X864543Y141605D01*
X864585Y141355D01*
X864751Y141147D01*
X865585Y140730D01*
X865960Y140439D01*
X866210Y140022D01*
X866293Y139647D01*
X864543D01*
G01X862318D02*
Y142147D01*
X862818Y141647D01*
G01Y139647D02*
X861818D01*
G01X860135Y140022D02*
X859885Y139814D01*
X859593Y139689D01*
X859218Y139647D01*
X858843Y139730D01*
X858551Y139897D01*
X858343Y140189D01*
X858301Y140522D01*
X858385Y140855D01*
X858593Y141064D01*
X858885Y141230D01*
X859176Y141272D01*
X859468Y141230D01*
X859843Y141064D01*
X859718Y142147D01*
X858593D01*
G01X871686Y134132D02*
Y131632D01*
G01X872644Y134132D02*
X870728D01*
G01X869419Y131632D02*
Y134132D01*
X868419D01*
X868086Y134007D01*
X867836Y133715D01*
X867753Y133382D01*
X867836Y133049D01*
X868044Y132799D01*
X868419Y132674D01*
X869419D01*
G01X866278Y133715D02*
X866028Y133965D01*
X865736Y134090D01*
X865403Y134132D01*
X864986Y134049D01*
X864694Y133840D01*
X864611Y133590D01*
X864653Y133340D01*
X864819Y133132D01*
X865653Y132715D01*
X866028Y132424D01*
X866278Y132007D01*
X866361Y131632D01*
X864611D01*
G01X862386Y134132D02*
X862719Y134049D01*
X862969Y133840D01*
X863136Y133590D01*
X863261Y133257D01*
X863303Y132882D01*
X863261Y132507D01*
X863136Y132174D01*
X862969Y131924D01*
X862719Y131715D01*
X862386Y131632D01*
X862053Y131715D01*
X861803Y131924D01*
X861636Y132174D01*
X861511Y132507D01*
X861469Y132882D01*
X861511Y133257D01*
X861636Y133590D01*
X861803Y133840D01*
X862053Y134049D01*
X862386Y134132D01*
G01X860203Y132007D02*
X859953Y131799D01*
X859661Y131674D01*
X859286Y131632D01*
X858911Y131715D01*
X858619Y131882D01*
X858411Y132174D01*
X858369Y132507D01*
X858453Y132840D01*
X858661Y133049D01*
X858953Y133215D01*
X859244Y133257D01*
X859536Y133215D01*
X859911Y133049D01*
X859786Y134132D01*
X858661D01*
G01X869105Y127339D02*
Y124839D01*
G01X870063Y127339D02*
X868147D01*
G01X866838Y124839D02*
Y127339D01*
X865838D01*
X865505Y127214D01*
X865255Y126922D01*
X865172Y126589D01*
X865255Y126256D01*
X865463Y126006D01*
X865838Y125881D01*
X866838D01*
G01X862905Y124839D02*
Y127339D01*
X863405Y126839D01*
G01Y124839D02*
X862405D01*
G01X860513Y125131D02*
X860222Y124922D01*
X859888Y124839D01*
X859555Y124922D01*
X859263Y125172D01*
X859055Y125547D01*
X858972Y125922D01*
Y126381D01*
X859055Y126756D01*
X859263Y127089D01*
X859513Y127256D01*
X859805Y127339D01*
X860138Y127256D01*
X860388Y127089D01*
X860555Y126839D01*
X860638Y126506D01*
X860555Y126214D01*
X860347Y125922D01*
X860097Y125756D01*
X859805Y125714D01*
X859472Y125797D01*
X859222Y126006D01*
X858972Y126381D01*
G01X856705Y124839D02*
X856413Y124881D01*
X856080Y125006D01*
X855872Y125214D01*
X855788Y125506D01*
X855872Y125797D01*
X856122Y126047D01*
X856497Y126172D01*
X856913D01*
X857163Y126256D01*
X857372Y126464D01*
X857455Y126756D01*
X857330Y127047D01*
X857038Y127256D01*
X856705Y127339D01*
X856372Y127256D01*
X856080Y127047D01*
X855955Y126756D01*
X856038Y126464D01*
X856247Y126256D01*
X856497Y126172D01*
X856913D01*
X857288Y126047D01*
X857538Y125797D01*
X857622Y125506D01*
X857538Y125214D01*
X857330Y125006D01*
X856997Y124881D01*
X856705Y124839D01*
G01X855179Y141808D02*
Y139308D01*
G01X856137Y141808D02*
X854221D01*
G01X852912Y139308D02*
Y141808D01*
X851912D01*
X851579Y141683D01*
X851329Y141391D01*
X851246Y141058D01*
X851329Y140725D01*
X851537Y140475D01*
X851912Y140350D01*
X852912D01*
G01X848979Y139308D02*
Y141808D01*
X849479Y141308D01*
G01Y139308D02*
X848479D01*
G01X846671Y141391D02*
X846421Y141641D01*
X846129Y141766D01*
X845796Y141808D01*
X845379Y141725D01*
X845087Y141516D01*
X845004Y141266D01*
X845046Y141016D01*
X845212Y140808D01*
X846046Y140391D01*
X846421Y140100D01*
X846671Y139683D01*
X846754Y139308D01*
X845004D01*
G01X842279D02*
Y141808D01*
X843821Y140016D01*
X841737D01*
G01X854907Y134064D02*
Y131564D01*
G01X855865Y134064D02*
X853949D01*
G01X852640Y131564D02*
Y134064D01*
X851640D01*
X851307Y133939D01*
X851057Y133647D01*
X850974Y133314D01*
X851057Y132981D01*
X851265Y132731D01*
X851640Y132606D01*
X852640D01*
G01X849499Y133647D02*
X849249Y133897D01*
X848957Y134022D01*
X848624Y134064D01*
X848207Y133981D01*
X847915Y133772D01*
X847832Y133522D01*
X847874Y133272D01*
X848040Y133064D01*
X848874Y132647D01*
X849249Y132356D01*
X849499Y131939D01*
X849582Y131564D01*
X847832D01*
G01X845690D02*
X845607Y132106D01*
X845482Y132564D01*
X845315Y132981D01*
X845107Y133439D01*
X844774Y134064D01*
X846440D01*
G01X842007Y131564D02*
Y134064D01*
X843549Y132272D01*
X841465D01*
G01X852305Y158243D02*
X852555Y158368D01*
X852847Y158451D01*
X853180D01*
X853555Y158326D01*
X853847Y158118D01*
X854055Y157868D01*
X854222Y157451D01*
X854264Y157076D01*
X854180Y156701D01*
X854055Y156451D01*
X853805Y156201D01*
X853514Y156034D01*
X853222Y155951D01*
X852930D01*
X852639Y156034D01*
X852389Y156159D01*
X852180Y156326D01*
G01X851039D02*
X850789Y156118D01*
X850497Y155993D01*
X850122Y155951D01*
X849747Y156034D01*
X849455Y156201D01*
X849247Y156493D01*
X849205Y156826D01*
X849289Y157159D01*
X849497Y157368D01*
X849789Y157534D01*
X850080Y157576D01*
X850372Y157534D01*
X850747Y157368D01*
X850622Y158451D01*
X849497D01*
G01X847105Y155951D02*
X847022Y156493D01*
X846897Y156951D01*
X846730Y157368D01*
X846522Y157826D01*
X846189Y158451D01*
X847855D01*
G01X844714Y156993D02*
X844422Y157284D01*
X844172Y157451D01*
X843839Y157534D01*
X843547Y157451D01*
X843339Y157284D01*
X843172Y157034D01*
X843130Y156743D01*
X843172Y156493D01*
X843339Y156243D01*
X843589Y156034D01*
X843880Y155951D01*
X844214Y156034D01*
X844505Y156284D01*
X844672Y156659D01*
X844714Y157076D01*
X844630Y157618D01*
X844505Y157909D01*
X844297Y158201D01*
X844005Y158409D01*
X843714Y158451D01*
X843422Y158368D01*
X843214Y158159D01*
G01X873063Y166837D02*
X873313Y166962D01*
X873605Y167045D01*
X873938D01*
X874313Y166920D01*
X874605Y166712D01*
X874813Y166462D01*
X874980Y166045D01*
X875022Y165670D01*
X874938Y165295D01*
X874813Y165045D01*
X874563Y164795D01*
X874272Y164628D01*
X873980Y164545D01*
X873688D01*
X873397Y164628D01*
X873147Y164753D01*
X872938Y164920D01*
G01X871797D02*
X871547Y164712D01*
X871255Y164587D01*
X870880Y164545D01*
X870505Y164628D01*
X870213Y164795D01*
X870005Y165087D01*
X869963Y165420D01*
X870047Y165753D01*
X870255Y165962D01*
X870547Y166128D01*
X870838Y166170D01*
X871130Y166128D01*
X871505Y165962D01*
X871380Y167045D01*
X870255D01*
G01X867863Y164545D02*
X867780Y165087D01*
X867655Y165545D01*
X867488Y165962D01*
X867280Y166420D01*
X866947Y167045D01*
X868613D01*
G01X864180Y164545D02*
Y167045D01*
X865722Y165253D01*
X863638D01*
G01X873063Y170787D02*
X873313Y170912D01*
X873605Y170995D01*
X873938D01*
X874313Y170870D01*
X874605Y170662D01*
X874813Y170412D01*
X874980Y169995D01*
X875022Y169620D01*
X874938Y169245D01*
X874813Y168995D01*
X874563Y168745D01*
X874272Y168578D01*
X873980Y168495D01*
X873688D01*
X873397Y168578D01*
X873147Y168703D01*
X872938Y168870D01*
G01X871797D02*
X871547Y168662D01*
X871255Y168537D01*
X870880Y168495D01*
X870505Y168578D01*
X870213Y168745D01*
X870005Y169037D01*
X869963Y169370D01*
X870047Y169703D01*
X870255Y169912D01*
X870547Y170078D01*
X870838Y170120D01*
X871130Y170078D01*
X871505Y169912D01*
X871380Y170995D01*
X870255D01*
G01X867863Y168495D02*
X867780Y169037D01*
X867655Y169495D01*
X867488Y169912D01*
X867280Y170370D01*
X866947Y170995D01*
X868613D01*
G01X865597Y168995D02*
X865347Y168703D01*
X865013Y168537D01*
X864638Y168495D01*
X864305Y168537D01*
X863972Y168745D01*
X863763Y168995D01*
X863722Y169245D01*
X863805Y169537D01*
X864097Y169745D01*
X864388Y169828D01*
X864763D01*
G01X864388D02*
X864138Y169953D01*
X863930Y170162D01*
X863847Y170412D01*
X863930Y170662D01*
X864138Y170870D01*
X864513Y170995D01*
X864888Y170953D01*
X865263Y170787D01*
G01X873063Y174737D02*
X873313Y174862D01*
X873605Y174945D01*
X873938D01*
X874313Y174820D01*
X874605Y174612D01*
X874813Y174362D01*
X874980Y173945D01*
X875022Y173570D01*
X874938Y173195D01*
X874813Y172945D01*
X874563Y172695D01*
X874272Y172528D01*
X873980Y172445D01*
X873688D01*
X873397Y172528D01*
X873147Y172653D01*
X872938Y172820D01*
G01X870380Y172445D02*
Y174945D01*
X871922Y173153D01*
X869838D01*
G01X867780Y172445D02*
X867488Y172487D01*
X867155Y172612D01*
X866947Y172820D01*
X866863Y173112D01*
X866947Y173403D01*
X867197Y173653D01*
X867572Y173778D01*
X867988D01*
X868238Y173862D01*
X868447Y174070D01*
X868530Y174362D01*
X868405Y174653D01*
X868113Y174862D01*
X867780Y174945D01*
X867447Y174862D01*
X867155Y174653D01*
X867030Y174362D01*
X867113Y174070D01*
X867322Y173862D01*
X867572Y173778D01*
X867988D01*
X868363Y173653D01*
X868613Y173403D01*
X868697Y173112D01*
X868613Y172820D01*
X868405Y172612D01*
X868072Y172487D01*
X867780Y172445D01*
G01X865388Y172737D02*
X865097Y172528D01*
X864763Y172445D01*
X864430Y172528D01*
X864138Y172778D01*
X863930Y173153D01*
X863847Y173528D01*
Y173987D01*
X863930Y174362D01*
X864138Y174695D01*
X864388Y174862D01*
X864680Y174945D01*
X865013Y174862D01*
X865263Y174695D01*
X865430Y174445D01*
X865513Y174112D01*
X865430Y173820D01*
X865222Y173528D01*
X864972Y173362D01*
X864680Y173320D01*
X864347Y173403D01*
X864097Y173612D01*
X863847Y173987D01*
G01X855315Y149280D02*
Y146780D01*
G01X856273Y149280D02*
X854357D01*
G01X853048Y146780D02*
Y149280D01*
X852048D01*
X851715Y149155D01*
X851465Y148863D01*
X851382Y148530D01*
X851465Y148197D01*
X851673Y147947D01*
X852048Y147822D01*
X853048D01*
G01X849907Y148863D02*
X849657Y149113D01*
X849365Y149238D01*
X849032Y149280D01*
X848615Y149197D01*
X848323Y148988D01*
X848240Y148738D01*
X848282Y148488D01*
X848448Y148280D01*
X849282Y147863D01*
X849657Y147572D01*
X849907Y147155D01*
X849990Y146780D01*
X848240D01*
G01X846098D02*
X846015Y147322D01*
X845890Y147780D01*
X845723Y148197D01*
X845515Y148655D01*
X845182Y149280D01*
X846848D01*
G01X842915Y146780D02*
X842623Y146822D01*
X842290Y146947D01*
X842082Y147155D01*
X841998Y147447D01*
X842082Y147738D01*
X842332Y147988D01*
X842707Y148113D01*
X843123D01*
X843373Y148197D01*
X843582Y148405D01*
X843665Y148697D01*
X843540Y148988D01*
X843248Y149197D01*
X842915Y149280D01*
X842582Y149197D01*
X842290Y148988D01*
X842165Y148697D01*
X842248Y148405D01*
X842457Y148197D01*
X842707Y148113D01*
X843123D01*
X843498Y147988D01*
X843748Y147738D01*
X843832Y147447D01*
X843748Y147155D01*
X843540Y146947D01*
X843207Y146822D01*
X842915Y146780D01*
G01X872094Y154102D02*
Y151602D01*
G01X873052Y154102D02*
X871136D01*
G01X869827Y151602D02*
Y154102D01*
X868827D01*
X868494Y153977D01*
X868244Y153685D01*
X868161Y153352D01*
X868244Y153019D01*
X868452Y152769D01*
X868827Y152644D01*
X869827D01*
G01X866686Y153685D02*
X866436Y153935D01*
X866144Y154060D01*
X865811Y154102D01*
X865394Y154019D01*
X865102Y153810D01*
X865019Y153560D01*
X865061Y153310D01*
X865227Y153102D01*
X866061Y152685D01*
X866436Y152394D01*
X866686Y151977D01*
X866769Y151602D01*
X865019D01*
G01X862794D02*
Y154102D01*
X863294Y153602D01*
G01Y151602D02*
X862294D01*
G01X859194D02*
Y154102D01*
X860736Y152310D01*
X858652D01*
G01X872094Y149212D02*
Y146712D01*
G01X873052Y149212D02*
X871136D01*
G01X869827Y146712D02*
Y149212D01*
X868827D01*
X868494Y149087D01*
X868244Y148795D01*
X868161Y148462D01*
X868244Y148129D01*
X868452Y147879D01*
X868827Y147754D01*
X869827D01*
G01X866686Y148795D02*
X866436Y149045D01*
X866144Y149170D01*
X865811Y149212D01*
X865394Y149129D01*
X865102Y148920D01*
X865019Y148670D01*
X865061Y148420D01*
X865227Y148212D01*
X866061Y147795D01*
X866436Y147504D01*
X866686Y147087D01*
X866769Y146712D01*
X865019D01*
G01X862794Y149212D02*
X863127Y149129D01*
X863377Y148920D01*
X863544Y148670D01*
X863669Y148337D01*
X863711Y147962D01*
X863669Y147587D01*
X863544Y147254D01*
X863377Y147004D01*
X863127Y146795D01*
X862794Y146712D01*
X862461Y146795D01*
X862211Y147004D01*
X862044Y147254D01*
X861919Y147587D01*
X861877Y147962D01*
X861919Y148337D01*
X862044Y148670D01*
X862211Y148920D01*
X862461Y149129D01*
X862794Y149212D01*
G01X859694Y146712D02*
Y149212D01*
X860194Y148712D01*
G01Y146712D02*
X859194D01*
G01X855451Y153696D02*
Y151196D01*
G01X856409Y153696D02*
X854493D01*
G01X853184Y151196D02*
Y153696D01*
X852184D01*
X851851Y153571D01*
X851601Y153279D01*
X851518Y152946D01*
X851601Y152613D01*
X851809Y152363D01*
X852184Y152238D01*
X853184D01*
G01X850043Y153279D02*
X849793Y153529D01*
X849501Y153654D01*
X849168Y153696D01*
X848751Y153613D01*
X848459Y153404D01*
X848376Y153154D01*
X848418Y152904D01*
X848584Y152696D01*
X849418Y152279D01*
X849793Y151988D01*
X850043Y151571D01*
X850126Y151196D01*
X848376D01*
G01X846943Y152238D02*
X846651Y152529D01*
X846401Y152696D01*
X846068Y152779D01*
X845776Y152696D01*
X845568Y152529D01*
X845401Y152279D01*
X845359Y151988D01*
X845401Y151738D01*
X845568Y151488D01*
X845818Y151279D01*
X846109Y151196D01*
X846443Y151279D01*
X846734Y151529D01*
X846901Y151904D01*
X846943Y152321D01*
X846859Y152863D01*
X846734Y153154D01*
X846526Y153446D01*
X846234Y153654D01*
X845943Y153696D01*
X845651Y153613D01*
X845443Y153404D01*
G01X843051Y151196D02*
X842759Y151238D01*
X842426Y151363D01*
X842218Y151571D01*
X842134Y151863D01*
X842218Y152154D01*
X842468Y152404D01*
X842843Y152529D01*
X843259D01*
X843509Y152613D01*
X843718Y152821D01*
X843801Y153113D01*
X843676Y153404D01*
X843384Y153613D01*
X843051Y153696D01*
X842718Y153613D01*
X842426Y153404D01*
X842301Y153113D01*
X842384Y152821D01*
X842593Y152613D01*
X842843Y152529D01*
X843259D01*
X843634Y152404D01*
X843884Y152154D01*
X843968Y151863D01*
X843884Y151571D01*
X843676Y151363D01*
X843343Y151238D01*
X843051Y151196D01*
G01X873233Y181192D02*
X873483Y181317D01*
X873775Y181400D01*
X874108D01*
X874483Y181275D01*
X874775Y181067D01*
X874983Y180817D01*
X875150Y180400D01*
X875192Y180025D01*
X875108Y179650D01*
X874983Y179400D01*
X874733Y179150D01*
X874442Y178983D01*
X874150Y178900D01*
X873858D01*
X873567Y178983D01*
X873317Y179108D01*
X873108Y179275D01*
G01X870550Y178900D02*
Y181400D01*
X872092Y179608D01*
X870008D01*
G01X868658Y179192D02*
X868367Y178983D01*
X868033Y178900D01*
X867700Y178983D01*
X867408Y179233D01*
X867200Y179608D01*
X867117Y179983D01*
Y180442D01*
X867200Y180817D01*
X867408Y181150D01*
X867658Y181317D01*
X867950Y181400D01*
X868283Y181317D01*
X868533Y181150D01*
X868700Y180900D01*
X868783Y180567D01*
X868700Y180275D01*
X868492Y179983D01*
X868242Y179817D01*
X867950Y179775D01*
X867617Y179858D01*
X867367Y180067D01*
X867117Y180442D01*
G01X864850Y181400D02*
X865183Y181317D01*
X865433Y181108D01*
X865600Y180858D01*
X865725Y180525D01*
X865767Y180150D01*
X865725Y179775D01*
X865600Y179442D01*
X865433Y179192D01*
X865183Y178983D01*
X864850Y178900D01*
X864517Y178983D01*
X864267Y179192D01*
X864100Y179442D01*
X863975Y179775D01*
X863933Y180150D01*
X863975Y180525D01*
X864100Y180858D01*
X864267Y181108D01*
X864517Y181317D01*
X864850Y181400D01*
G01X855567Y731415D02*
X858067D01*
Y732456D01*
X857942Y732790D01*
X857775Y732998D01*
X857442Y733081D01*
X857109Y732998D01*
X856900Y732748D01*
X856775Y732456D01*
Y731415D01*
G01Y732456D02*
X855567Y733081D01*
G01X855942Y734431D02*
X855734Y734681D01*
X855609Y734973D01*
X855567Y735348D01*
X855650Y735723D01*
X855817Y736015D01*
X856109Y736223D01*
X856442Y736265D01*
X856775Y736181D01*
X856984Y735973D01*
X857150Y735681D01*
X857192Y735390D01*
X857150Y735098D01*
X856984Y734723D01*
X858067Y734848D01*
Y735973D01*
G01X855942Y737531D02*
X855734Y737781D01*
X855609Y738073D01*
X855567Y738448D01*
X855650Y738823D01*
X855817Y739115D01*
X856109Y739323D01*
X856442Y739365D01*
X856775Y739281D01*
X856984Y739073D01*
X857150Y738781D01*
X857192Y738490D01*
X857150Y738198D01*
X856984Y737823D01*
X858067Y737948D01*
Y739073D01*
G01X855942Y740631D02*
X855734Y740881D01*
X855609Y741173D01*
X855567Y741548D01*
X855650Y741923D01*
X855817Y742215D01*
X856109Y742423D01*
X856442Y742465D01*
X856775Y742381D01*
X856984Y742173D01*
X857150Y741881D01*
X857192Y741590D01*
X857150Y741298D01*
X856984Y740923D01*
X858067Y741048D01*
Y742173D01*
G01X858906Y746698D02*
X854906D01*
Y754098D01*
G01X859567Y731415D02*
X862067D01*
Y732456D01*
X861942Y732790D01*
X861775Y732998D01*
X861442Y733081D01*
X861109Y732998D01*
X860900Y732748D01*
X860775Y732456D01*
Y731415D01*
G01Y732456D02*
X859567Y733081D01*
G01X859942Y734431D02*
X859734Y734681D01*
X859609Y734973D01*
X859567Y735348D01*
X859650Y735723D01*
X859817Y736015D01*
X860109Y736223D01*
X860442Y736265D01*
X860775Y736181D01*
X860984Y735973D01*
X861150Y735681D01*
X861192Y735390D01*
X861150Y735098D01*
X860984Y734723D01*
X862067Y734848D01*
Y735973D01*
G01X859942Y737531D02*
X859734Y737781D01*
X859609Y738073D01*
X859567Y738448D01*
X859650Y738823D01*
X859817Y739115D01*
X860109Y739323D01*
X860442Y739365D01*
X860775Y739281D01*
X860984Y739073D01*
X861150Y738781D01*
X861192Y738490D01*
X861150Y738198D01*
X860984Y737823D01*
X862067Y737948D01*
Y739073D01*
G01X860067Y740631D02*
X859775Y740881D01*
X859609Y741215D01*
X859567Y741590D01*
X859609Y741923D01*
X859817Y742256D01*
X860067Y742465D01*
X860317Y742506D01*
X860609Y742423D01*
X860817Y742131D01*
X860900Y741840D01*
Y741465D01*
G01Y741840D02*
X861025Y742090D01*
X861234Y742298D01*
X861484Y742381D01*
X861734Y742298D01*
X861942Y742090D01*
X862067Y741715D01*
X862025Y741340D01*
X861859Y740965D01*
G01X862906Y746698D02*
X858906D01*
Y754098D01*
G01X863567Y729865D02*
X866067D01*
Y730906D01*
X865942Y731240D01*
X865775Y731448D01*
X865442Y731531D01*
X865109Y731448D01*
X864900Y731198D01*
X864775Y730906D01*
Y729865D01*
G01Y730906D02*
X863567Y731531D01*
G01Y734298D02*
X866067D01*
X864275Y732756D01*
Y734840D01*
G01X863567Y736898D02*
X866067D01*
X865567Y736398D01*
G01X863567D02*
Y737398D01*
G01Y740498D02*
X866067D01*
X864275Y738956D01*
Y741040D01*
G01X864609Y742306D02*
X864900Y742598D01*
X865067Y742848D01*
X865150Y743181D01*
X865067Y743473D01*
X864900Y743681D01*
X864650Y743848D01*
X864359Y743890D01*
X864109Y743848D01*
X863859Y743681D01*
X863650Y743431D01*
X863567Y743140D01*
X863650Y742806D01*
X863900Y742515D01*
X864275Y742348D01*
X864692Y742306D01*
X865234Y742390D01*
X865525Y742515D01*
X865817Y742723D01*
X866025Y743015D01*
X866067Y743306D01*
X865984Y743598D01*
X865775Y743806D01*
G01X862906Y754098D02*
X866906D01*
Y746698D01*
G01X867567Y729865D02*
X870067D01*
Y730906D01*
X869942Y731240D01*
X869775Y731448D01*
X869442Y731531D01*
X869109Y731448D01*
X868900Y731198D01*
X868775Y730906D01*
Y729865D01*
G01Y730906D02*
X867567Y731531D01*
G01Y734298D02*
X870067D01*
X868275Y732756D01*
Y734840D01*
G01X867567Y736898D02*
X870067D01*
X869567Y736398D01*
G01X867567D02*
Y737398D01*
G01X868067Y739081D02*
X867775Y739331D01*
X867609Y739665D01*
X867567Y740040D01*
X867609Y740373D01*
X867817Y740706D01*
X868067Y740915D01*
X868317Y740956D01*
X868609Y740873D01*
X868817Y740581D01*
X868900Y740290D01*
Y739915D01*
G01Y740290D02*
X869025Y740540D01*
X869234Y740748D01*
X869484Y740831D01*
X869734Y740748D01*
X869942Y740540D01*
X870067Y740165D01*
X870025Y739790D01*
X869859Y739415D01*
G01X867942Y742181D02*
X867734Y742431D01*
X867609Y742723D01*
X867567Y743098D01*
X867650Y743473D01*
X867817Y743765D01*
X868109Y743973D01*
X868442Y744015D01*
X868775Y743931D01*
X868984Y743723D01*
X869150Y743431D01*
X869192Y743140D01*
X869150Y742848D01*
X868984Y742473D01*
X870067Y742598D01*
Y743723D01*
G01X866906Y754098D02*
X870906D01*
Y746698D01*
G01X870500Y768800D02*
Y782200D01*
G01X860500Y768800D02*
X870500D01*
G01X860500Y782200D02*
Y768800D01*
G01X870500Y782200D02*
X860500D01*
G01X854222Y769269D02*
Y782669D01*
G01X844222Y769269D02*
X854222D01*
G01X844222Y782669D02*
Y769269D01*
G01X854222Y782669D02*
X844222D01*
G01X855500Y783700D02*
X859500D01*
Y776300D01*
G01X850400Y767600D02*
X854400D01*
Y760200D01*
G01X864700Y763800D02*
Y767800D01*
X872100D01*
G01X845910Y795642D02*
X848410D01*
Y796683D01*
X848285Y797017D01*
X848118Y797225D01*
X847785Y797308D01*
X847452Y797225D01*
X847243Y796975D01*
X847118Y796683D01*
Y795642D01*
G01Y796683D02*
X845910Y797308D01*
G01Y799575D02*
X848410D01*
X847910Y799075D01*
G01X845910D02*
Y800075D01*
G01X846285Y801758D02*
X846077Y802008D01*
X845952Y802300D01*
X845910Y802675D01*
X845993Y803050D01*
X846160Y803342D01*
X846452Y803550D01*
X846785Y803592D01*
X847118Y803508D01*
X847327Y803300D01*
X847493Y803008D01*
X847535Y802717D01*
X847493Y802425D01*
X847327Y802050D01*
X848410Y802175D01*
Y803300D01*
G01X845910Y805692D02*
X846452Y805775D01*
X846910Y805900D01*
X847327Y806067D01*
X847785Y806275D01*
X848410Y806608D01*
Y804942D01*
G01X868400Y791100D02*
X872400D01*
Y783700D01*
G01X841910Y795642D02*
X844410D01*
Y796683D01*
X844285Y797017D01*
X844118Y797225D01*
X843785Y797308D01*
X843452Y797225D01*
X843243Y796975D01*
X843118Y796683D01*
Y795642D01*
G01Y796683D02*
X841910Y797308D01*
G01X842410Y798658D02*
X842118Y798908D01*
X841952Y799242D01*
X841910Y799617D01*
X841952Y799950D01*
X842160Y800283D01*
X842410Y800492D01*
X842660Y800533D01*
X842952Y800450D01*
X843160Y800158D01*
X843243Y799867D01*
Y799492D01*
G01Y799867D02*
X843368Y800117D01*
X843577Y800325D01*
X843827Y800408D01*
X844077Y800325D01*
X844285Y800117D01*
X844410Y799742D01*
X844368Y799367D01*
X844202Y798992D01*
G01X843993Y801883D02*
X844243Y802133D01*
X844368Y802425D01*
X844410Y802758D01*
X844327Y803175D01*
X844118Y803467D01*
X843868Y803550D01*
X843618Y803508D01*
X843410Y803342D01*
X842993Y802508D01*
X842702Y802133D01*
X842285Y801883D01*
X841910Y801800D01*
Y803550D01*
G01Y805775D02*
X844410D01*
X843910Y805275D01*
G01X841910D02*
Y806275D01*
G01X844410Y808875D02*
X844327Y808542D01*
X844118Y808292D01*
X843868Y808125D01*
X843535Y808000D01*
X843160Y807958D01*
X842785Y808000D01*
X842452Y808125D01*
X842202Y808292D01*
X841993Y808542D01*
X841910Y808875D01*
X841993Y809208D01*
X842202Y809458D01*
X842452Y809625D01*
X842785Y809750D01*
X843160Y809792D01*
X843535Y809750D01*
X843868Y809625D01*
X844118Y809458D01*
X844327Y809208D01*
X844410Y808875D01*
G01X868260Y790880D02*
Y786880D01*
X860860D01*
G01X849910Y795642D02*
X852410D01*
Y796683D01*
X852285Y797017D01*
X852118Y797225D01*
X851785Y797308D01*
X851452Y797225D01*
X851243Y796975D01*
X851118Y796683D01*
Y795642D01*
G01Y796683D02*
X849910Y797308D01*
G01X850410Y798658D02*
X850118Y798908D01*
X849952Y799242D01*
X849910Y799617D01*
X849952Y799950D01*
X850160Y800283D01*
X850410Y800492D01*
X850660Y800533D01*
X850952Y800450D01*
X851160Y800158D01*
X851243Y799867D01*
Y799492D01*
G01Y799867D02*
X851368Y800117D01*
X851577Y800325D01*
X851827Y800408D01*
X852077Y800325D01*
X852285Y800117D01*
X852410Y799742D01*
X852368Y799367D01*
X852202Y798992D01*
G01X851993Y801883D02*
X852243Y802133D01*
X852368Y802425D01*
X852410Y802758D01*
X852327Y803175D01*
X852118Y803467D01*
X851868Y803550D01*
X851618Y803508D01*
X851410Y803342D01*
X850993Y802508D01*
X850702Y802133D01*
X850285Y801883D01*
X849910Y801800D01*
Y803550D01*
G01X851993Y804983D02*
X852243Y805233D01*
X852368Y805525D01*
X852410Y805858D01*
X852327Y806275D01*
X852118Y806567D01*
X851868Y806650D01*
X851618Y806608D01*
X851410Y806442D01*
X850993Y805608D01*
X850702Y805233D01*
X850285Y804983D01*
X849910Y804900D01*
Y806650D01*
G01X850952Y808083D02*
X851243Y808375D01*
X851410Y808625D01*
X851493Y808958D01*
X851410Y809250D01*
X851243Y809458D01*
X850993Y809625D01*
X850702Y809667D01*
X850452Y809625D01*
X850202Y809458D01*
X849993Y809208D01*
X849910Y808917D01*
X849993Y808583D01*
X850243Y808292D01*
X850618Y808125D01*
X851035Y808083D01*
X851577Y808167D01*
X851868Y808292D01*
X852160Y808500D01*
X852368Y808792D01*
X852410Y809083D01*
X852327Y809375D01*
X852118Y809583D01*
G01X842810Y791290D02*
X846810D01*
Y783890D01*
G01X853240Y788220D02*
Y792220D01*
X860640D01*
G01X858049Y806546D02*
X860549D01*
Y807587D01*
X860424Y807921D01*
X860257Y808129D01*
X859924Y808212D01*
X859591Y808129D01*
X859382Y807879D01*
X859257Y807587D01*
Y806546D01*
G01Y807587D02*
X858049Y808212D01*
G01X858424Y809562D02*
X858216Y809812D01*
X858091Y810104D01*
X858049Y810479D01*
X858132Y810854D01*
X858299Y811146D01*
X858591Y811354D01*
X858924Y811396D01*
X859257Y811312D01*
X859466Y811104D01*
X859632Y810812D01*
X859674Y810521D01*
X859632Y810229D01*
X859466Y809854D01*
X860549Y809979D01*
Y811104D01*
G01X858424Y812662D02*
X858216Y812912D01*
X858091Y813204D01*
X858049Y813579D01*
X858132Y813954D01*
X858299Y814246D01*
X858591Y814454D01*
X858924Y814496D01*
X859257Y814412D01*
X859466Y814204D01*
X859632Y813912D01*
X859674Y813621D01*
X859632Y813329D01*
X859466Y812954D01*
X860549Y813079D01*
Y814204D01*
G01X858049Y816679D02*
X860549D01*
X860049Y816179D01*
G01X858049D02*
Y817179D01*
G01X863378Y803131D02*
X867378D01*
Y795731D01*
G01X866505Y806073D02*
X869005D01*
Y807114D01*
X868880Y807448D01*
X868713Y807656D01*
X868380Y807739D01*
X868047Y807656D01*
X867838Y807406D01*
X867713Y807114D01*
Y806073D01*
G01Y807114D02*
X866505Y807739D01*
G01Y810506D02*
X869005D01*
X867213Y808964D01*
Y811048D01*
G01X866505Y813106D02*
X869005D01*
X868505Y812606D01*
G01X866505D02*
Y813606D01*
G01Y816706D02*
X869005D01*
X867213Y815164D01*
Y817248D01*
G01X866797Y818598D02*
X866588Y818889D01*
X866505Y819223D01*
X866588Y819556D01*
X866838Y819848D01*
X867213Y820056D01*
X867588Y820139D01*
X868047D01*
X868422Y820056D01*
X868755Y819848D01*
X868922Y819598D01*
X869005Y819306D01*
X868922Y818973D01*
X868755Y818723D01*
X868505Y818556D01*
X868172Y818473D01*
X867880Y818556D01*
X867588Y818764D01*
X867422Y819014D01*
X867380Y819306D01*
X867463Y819639D01*
X867672Y819889D01*
X868047Y820139D01*
G01X871906Y795698D02*
X867906D01*
Y803098D01*
G01X876800Y41500D02*
Y39500D01*
G01X890200D02*
Y41500D01*
G01X876800Y39500D02*
X890200D01*
G01X875500Y33900D02*
Y47300D01*
G01X897045Y31288D02*
X899545D01*
Y32329D01*
X899420Y32663D01*
X899253Y32871D01*
X898920Y32954D01*
X898587Y32871D01*
X898378Y32621D01*
X898253Y32329D01*
Y31288D01*
G01Y32329D02*
X897045Y32954D01*
G01Y35138D02*
X897587Y35221D01*
X898045Y35346D01*
X898462Y35513D01*
X898920Y35721D01*
X899545Y36054D01*
Y34388D01*
G01X897045Y38321D02*
X899545D01*
X899045Y37821D01*
G01X897045D02*
Y38821D01*
G01X897545Y40504D02*
X897253Y40754D01*
X897087Y41088D01*
X897045Y41463D01*
X897087Y41796D01*
X897295Y42129D01*
X897545Y42338D01*
X897795Y42379D01*
X898087Y42296D01*
X898295Y42004D01*
X898378Y41713D01*
Y41338D01*
G01Y41713D02*
X898503Y41963D01*
X898712Y42171D01*
X898962Y42254D01*
X899212Y42171D01*
X899420Y41963D01*
X899545Y41588D01*
X899503Y41213D01*
X899337Y40838D01*
G01X895100Y32700D02*
X891100D01*
Y40100D01*
G01X880667Y8417D02*
X883167D01*
Y9458D01*
X883042Y9792D01*
X882875Y10000D01*
X882542Y10083D01*
X882209Y10000D01*
X882000Y9750D01*
X881875Y9458D01*
Y8417D01*
G01Y9458D02*
X880667Y10083D01*
G01X881709Y11558D02*
X882000Y11850D01*
X882167Y12100D01*
X882250Y12433D01*
X882167Y12725D01*
X882000Y12933D01*
X881750Y13100D01*
X881459Y13142D01*
X881209Y13100D01*
X880959Y12933D01*
X880750Y12683D01*
X880667Y12392D01*
X880750Y12058D01*
X881000Y11767D01*
X881375Y11600D01*
X881792Y11558D01*
X882334Y11642D01*
X882625Y11767D01*
X882917Y11975D01*
X883125Y12267D01*
X883167Y12558D01*
X883084Y12850D01*
X882875Y13058D01*
G01X880667Y15367D02*
X881209Y15450D01*
X881667Y15575D01*
X882084Y15742D01*
X882542Y15950D01*
X883167Y16283D01*
Y14617D01*
G01X880667Y19050D02*
X883167D01*
X881375Y17508D01*
Y19592D01*
G01X875300Y32700D02*
X879300D01*
Y25300D01*
G01X876270Y8265D02*
X878770D01*
Y9306D01*
X878645Y9640D01*
X878478Y9848D01*
X878145Y9931D01*
X877812Y9848D01*
X877603Y9598D01*
X877478Y9306D01*
Y8265D01*
G01Y9306D02*
X876270Y9931D01*
G01X876770Y11281D02*
X876478Y11531D01*
X876312Y11865D01*
X876270Y12240D01*
X876312Y12573D01*
X876520Y12906D01*
X876770Y13115D01*
X877020Y13156D01*
X877312Y13073D01*
X877520Y12781D01*
X877603Y12490D01*
Y12115D01*
G01Y12490D02*
X877728Y12740D01*
X877937Y12948D01*
X878187Y13031D01*
X878437Y12948D01*
X878645Y12740D01*
X878770Y12365D01*
X878728Y11990D01*
X878562Y11615D01*
G01X876270Y15215D02*
X876812Y15298D01*
X877270Y15423D01*
X877687Y15590D01*
X878145Y15798D01*
X878770Y16131D01*
Y14465D01*
G01X876270Y18398D02*
X878770D01*
X878270Y17898D01*
G01X876270D02*
Y18898D01*
G01Y21998D02*
X878770D01*
X876978Y20456D01*
Y22540D01*
G01X902483Y44675D02*
Y47175D01*
X901483D01*
X901150Y47050D01*
X900900Y46758D01*
X900817Y46425D01*
X900900Y46092D01*
X901108Y45842D01*
X901483Y45717D01*
X902483D01*
G01X898550Y44675D02*
X898883Y44717D01*
X899175Y44883D01*
X899425Y45133D01*
X899592Y45425D01*
X899675Y45758D01*
Y46092D01*
X899592Y46425D01*
X899425Y46717D01*
X899175Y46967D01*
X898883Y47133D01*
X898550Y47175D01*
X898217Y47133D01*
X897925Y46967D01*
X897675Y46717D01*
X897508Y46425D01*
X897425Y46092D01*
Y45758D01*
X897508Y45425D01*
X897675Y45133D01*
X897925Y44883D01*
X898217Y44717D01*
X898550Y44675D01*
G01X898217Y45342D02*
X897717Y44675D01*
G01X896242Y46758D02*
X895992Y47008D01*
X895700Y47133D01*
X895367Y47175D01*
X894950Y47092D01*
X894658Y46883D01*
X894575Y46633D01*
X894617Y46383D01*
X894783Y46175D01*
X895617Y45758D01*
X895992Y45467D01*
X896242Y45050D01*
X896325Y44675D01*
X894575D01*
G01X893142Y46758D02*
X892892Y47008D01*
X892600Y47133D01*
X892267Y47175D01*
X891850Y47092D01*
X891558Y46883D01*
X891475Y46633D01*
X891517Y46383D01*
X891683Y46175D01*
X892517Y45758D01*
X892892Y45467D01*
X893142Y45050D01*
X893225Y44675D01*
X891475D01*
G01X890200Y41500D02*
X876800D01*
G01X904500Y84200D02*
X908500D01*
Y76800D01*
G01X900000Y84200D02*
X904000D01*
Y76800D01*
G01X895500Y84200D02*
X899500D01*
Y76800D01*
G01X891000Y84200D02*
X895000D01*
Y76800D01*
G01X886500Y84200D02*
X890500D01*
Y76800D01*
G01X882000Y84200D02*
X886000D01*
Y76800D01*
G01X877500Y84200D02*
X881500D01*
Y76800D01*
G01Y87800D02*
X877500D01*
Y95200D01*
G01X886000Y87800D02*
X882000D01*
Y95200D01*
G01X890500Y87800D02*
X886500D01*
Y95200D01*
G01X895000Y87800D02*
X891000D01*
Y95200D01*
G01X899500Y87800D02*
X895500D01*
Y95200D01*
G01X904000Y87800D02*
X900000D01*
Y95200D01*
G01X908500Y87800D02*
X904500D01*
Y95200D01*
G01X907281Y106935D02*
Y109435D01*
X906240D01*
X905906Y109310D01*
X905698Y109143D01*
X905615Y108810D01*
X905698Y108477D01*
X905948Y108268D01*
X906240Y108143D01*
X907281D01*
G01X906240D02*
X905615Y106935D01*
G01X904140Y109018D02*
X903890Y109268D01*
X903598Y109393D01*
X903265Y109435D01*
X902848Y109352D01*
X902556Y109143D01*
X902473Y108893D01*
X902515Y108643D01*
X902681Y108435D01*
X903515Y108018D01*
X903890Y107727D01*
X904140Y107310D01*
X904223Y106935D01*
X902473D01*
G01X900331D02*
X900248Y107477D01*
X900123Y107935D01*
X899956Y108352D01*
X899748Y108810D01*
X899415Y109435D01*
X901081D01*
G01X909733Y131292D02*
X909983Y131417D01*
X910275Y131500D01*
X910608D01*
X910983Y131375D01*
X911275Y131167D01*
X911483Y130917D01*
X911650Y130500D01*
X911692Y130125D01*
X911608Y129750D01*
X911483Y129500D01*
X911233Y129250D01*
X910942Y129083D01*
X910650Y129000D01*
X910358D01*
X910067Y129083D01*
X909817Y129208D01*
X909608Y129375D01*
G01X907050Y129000D02*
Y131500D01*
X908592Y129708D01*
X906508D01*
G01X904450Y129000D02*
X904158Y129042D01*
X903825Y129167D01*
X903617Y129375D01*
X903533Y129667D01*
X903617Y129958D01*
X903867Y130208D01*
X904242Y130333D01*
X904658D01*
X904908Y130417D01*
X905117Y130625D01*
X905200Y130917D01*
X905075Y131208D01*
X904783Y131417D01*
X904450Y131500D01*
X904117Y131417D01*
X903825Y131208D01*
X903700Y130917D01*
X903783Y130625D01*
X903992Y130417D01*
X904242Y130333D01*
X904658D01*
X905033Y130208D01*
X905283Y129958D01*
X905367Y129667D01*
X905283Y129375D01*
X905075Y129167D01*
X904742Y129042D01*
X904450Y129000D01*
G01X901350Y131500D02*
X901683Y131417D01*
X901933Y131208D01*
X902100Y130958D01*
X902225Y130625D01*
X902267Y130250D01*
X902225Y129875D01*
X902100Y129542D01*
X901933Y129292D01*
X901683Y129083D01*
X901350Y129000D01*
X901017Y129083D01*
X900767Y129292D01*
X900600Y129542D01*
X900475Y129875D01*
X900433Y130250D01*
X900475Y130625D01*
X900600Y130958D01*
X900767Y131208D01*
X901017Y131417D01*
X901350Y131500D01*
G01X904822Y117257D02*
X904947Y117007D01*
X905030Y116715D01*
Y116382D01*
X904905Y116007D01*
X904697Y115715D01*
X904447Y115507D01*
X904030Y115340D01*
X903655Y115298D01*
X903280Y115382D01*
X903030Y115507D01*
X902780Y115757D01*
X902613Y116048D01*
X902530Y116340D01*
Y116632D01*
X902613Y116923D01*
X902738Y117173D01*
X902905Y117382D01*
G01X902530Y119940D02*
X905030D01*
X903238Y118398D01*
Y120482D01*
G01X902530Y122457D02*
X903072Y122540D01*
X903530Y122665D01*
X903947Y122832D01*
X904405Y123040D01*
X905030Y123373D01*
Y121707D01*
G01X902822Y124932D02*
X902613Y125223D01*
X902530Y125557D01*
X902613Y125890D01*
X902863Y126182D01*
X903238Y126390D01*
X903613Y126473D01*
X904072D01*
X904447Y126390D01*
X904780Y126182D01*
X904947Y125932D01*
X905030Y125640D01*
X904947Y125307D01*
X904780Y125057D01*
X904530Y124890D01*
X904197Y124807D01*
X903905Y124890D01*
X903613Y125098D01*
X903447Y125348D01*
X903405Y125640D01*
X903488Y125973D01*
X903697Y126223D01*
X904072Y126473D01*
G01X891700Y141500D02*
Y139000D01*
G01X892658Y141500D02*
X890742D01*
G01X889433Y139000D02*
Y141500D01*
X888433D01*
X888100Y141375D01*
X887850Y141083D01*
X887767Y140750D01*
X887850Y140417D01*
X888058Y140167D01*
X888433Y140042D01*
X889433D01*
G01X886292Y141083D02*
X886042Y141333D01*
X885750Y141458D01*
X885417Y141500D01*
X885000Y141417D01*
X884708Y141208D01*
X884625Y140958D01*
X884667Y140708D01*
X884833Y140500D01*
X885667Y140083D01*
X886042Y139792D01*
X886292Y139375D01*
X886375Y139000D01*
X884625D01*
G01X882400Y141500D02*
X882733Y141417D01*
X882983Y141208D01*
X883150Y140958D01*
X883275Y140625D01*
X883317Y140250D01*
X883275Y139875D01*
X883150Y139542D01*
X882983Y139292D01*
X882733Y139083D01*
X882400Y139000D01*
X882067Y139083D01*
X881817Y139292D01*
X881650Y139542D01*
X881525Y139875D01*
X881483Y140250D01*
X881525Y140625D01*
X881650Y140958D01*
X881817Y141208D01*
X882067Y141417D01*
X882400Y141500D01*
G01X880092Y141083D02*
X879842Y141333D01*
X879550Y141458D01*
X879217Y141500D01*
X878800Y141417D01*
X878508Y141208D01*
X878425Y140958D01*
X878467Y140708D01*
X878633Y140500D01*
X879467Y140083D01*
X879842Y139792D01*
X880092Y139375D01*
X880175Y139000D01*
X878425D01*
G01X891700Y133500D02*
Y131000D01*
G01X892658Y133500D02*
X890742D01*
G01X889433Y131000D02*
Y133500D01*
X888433D01*
X888100Y133375D01*
X887850Y133083D01*
X887767Y132750D01*
X887850Y132417D01*
X888058Y132167D01*
X888433Y132042D01*
X889433D01*
G01X885500Y131000D02*
Y133500D01*
X886000Y133000D01*
G01Y131000D02*
X885000D01*
G01X883108Y131292D02*
X882817Y131083D01*
X882483Y131000D01*
X882150Y131083D01*
X881858Y131333D01*
X881650Y131708D01*
X881567Y132083D01*
Y132542D01*
X881650Y132917D01*
X881858Y133250D01*
X882108Y133417D01*
X882400Y133500D01*
X882733Y133417D01*
X882983Y133250D01*
X883150Y133000D01*
X883233Y132667D01*
X883150Y132375D01*
X882942Y132083D01*
X882692Y131917D01*
X882400Y131875D01*
X882067Y131958D01*
X881817Y132167D01*
X881567Y132542D01*
G01X880008Y131292D02*
X879717Y131083D01*
X879383Y131000D01*
X879050Y131083D01*
X878758Y131333D01*
X878550Y131708D01*
X878467Y132083D01*
Y132542D01*
X878550Y132917D01*
X878758Y133250D01*
X879008Y133417D01*
X879300Y133500D01*
X879633Y133417D01*
X879883Y133250D01*
X880050Y133000D01*
X880133Y132667D01*
X880050Y132375D01*
X879842Y132083D01*
X879592Y131917D01*
X879300Y131875D01*
X878967Y131958D01*
X878717Y132167D01*
X878467Y132542D01*
G01X891700Y137500D02*
Y135000D01*
G01X892658Y137500D02*
X890742D01*
G01X889433Y135000D02*
Y137500D01*
X888433D01*
X888100Y137375D01*
X887850Y137083D01*
X887767Y136750D01*
X887850Y136417D01*
X888058Y136167D01*
X888433Y136042D01*
X889433D01*
G01X885500Y135000D02*
Y137500D01*
X886000Y137000D01*
G01Y135000D02*
X885000D01*
G01X883192Y137083D02*
X882942Y137333D01*
X882650Y137458D01*
X882317Y137500D01*
X881900Y137417D01*
X881608Y137208D01*
X881525Y136958D01*
X881567Y136708D01*
X881733Y136500D01*
X882567Y136083D01*
X882942Y135792D01*
X883192Y135375D01*
X883275Y135000D01*
X881525D01*
G01X880092Y137083D02*
X879842Y137333D01*
X879550Y137458D01*
X879217Y137500D01*
X878800Y137417D01*
X878508Y137208D01*
X878425Y136958D01*
X878467Y136708D01*
X878633Y136500D01*
X879467Y136083D01*
X879842Y135792D01*
X880092Y135375D01*
X880175Y135000D01*
X878425D01*
G01X890570Y112326D02*
Y109826D01*
G01X891528Y112326D02*
X889612D01*
G01X888303Y109826D02*
Y112326D01*
X887303D01*
X886970Y112201D01*
X886720Y111909D01*
X886637Y111576D01*
X886720Y111243D01*
X886928Y110993D01*
X887303Y110868D01*
X888303D01*
G01X885287Y110326D02*
X885037Y110034D01*
X884703Y109868D01*
X884328Y109826D01*
X883995Y109868D01*
X883662Y110076D01*
X883453Y110326D01*
X883412Y110576D01*
X883495Y110868D01*
X883787Y111076D01*
X884078Y111159D01*
X884453D01*
G01X884078D02*
X883828Y111284D01*
X883620Y111493D01*
X883537Y111743D01*
X883620Y111993D01*
X883828Y112201D01*
X884203Y112326D01*
X884578Y112284D01*
X884953Y112118D01*
G01X881270Y112326D02*
X881603Y112243D01*
X881853Y112034D01*
X882020Y111784D01*
X882145Y111451D01*
X882187Y111076D01*
X882145Y110701D01*
X882020Y110368D01*
X881853Y110118D01*
X881603Y109909D01*
X881270Y109826D01*
X880937Y109909D01*
X880687Y110118D01*
X880520Y110368D01*
X880395Y110701D01*
X880353Y111076D01*
X880395Y111451D01*
X880520Y111784D01*
X880687Y112034D01*
X880937Y112243D01*
X881270Y112326D01*
G01X878878Y110118D02*
X878587Y109909D01*
X878253Y109826D01*
X877920Y109909D01*
X877628Y110159D01*
X877420Y110534D01*
X877337Y110909D01*
Y111368D01*
X877420Y111743D01*
X877628Y112076D01*
X877878Y112243D01*
X878170Y112326D01*
X878503Y112243D01*
X878753Y112076D01*
X878920Y111826D01*
X879003Y111493D01*
X878920Y111201D01*
X878712Y110909D01*
X878462Y110743D01*
X878170Y110701D01*
X877837Y110784D01*
X877587Y110993D01*
X877337Y111368D01*
G01X900200Y110500D02*
Y114500D01*
X907600D01*
G01X900670Y166699D02*
X900920Y166824D01*
X901212Y166907D01*
X901545D01*
X901920Y166782D01*
X902212Y166574D01*
X902420Y166324D01*
X902587Y165907D01*
X902629Y165532D01*
X902545Y165157D01*
X902420Y164907D01*
X902170Y164657D01*
X901879Y164490D01*
X901587Y164407D01*
X901295D01*
X901004Y164490D01*
X900754Y164615D01*
X900545Y164782D01*
G01X899404D02*
X899154Y164574D01*
X898862Y164449D01*
X898487Y164407D01*
X898112Y164490D01*
X897820Y164657D01*
X897612Y164949D01*
X897570Y165282D01*
X897654Y165615D01*
X897862Y165824D01*
X898154Y165990D01*
X898445Y166032D01*
X898737Y165990D01*
X899112Y165824D01*
X898987Y166907D01*
X897862D01*
G01X895470Y164407D02*
X895387Y164949D01*
X895262Y165407D01*
X895095Y165824D01*
X894887Y166282D01*
X894554Y166907D01*
X896220D01*
G01X893204Y164782D02*
X892954Y164574D01*
X892662Y164449D01*
X892287Y164407D01*
X891912Y164490D01*
X891620Y164657D01*
X891412Y164949D01*
X891370Y165282D01*
X891454Y165615D01*
X891662Y165824D01*
X891954Y165990D01*
X892245Y166032D01*
X892537Y165990D01*
X892912Y165824D01*
X892787Y166907D01*
X891662D01*
G01X914188Y175157D02*
X914438Y175282D01*
X914730Y175365D01*
X915063D01*
X915438Y175240D01*
X915730Y175032D01*
X915938Y174782D01*
X916105Y174365D01*
X916147Y173990D01*
X916063Y173615D01*
X915938Y173365D01*
X915688Y173115D01*
X915397Y172948D01*
X915105Y172865D01*
X914813D01*
X914522Y172948D01*
X914272Y173073D01*
X914063Y173240D01*
G01X911505Y172865D02*
Y175365D01*
X913047Y173573D01*
X910963D01*
G01X909822Y173365D02*
X909572Y173073D01*
X909238Y172907D01*
X908863Y172865D01*
X908530Y172907D01*
X908197Y173115D01*
X907988Y173365D01*
X907947Y173615D01*
X908030Y173907D01*
X908322Y174115D01*
X908613Y174198D01*
X908988D01*
G01X908613D02*
X908363Y174323D01*
X908155Y174532D01*
X908072Y174782D01*
X908155Y175032D01*
X908363Y175240D01*
X908738Y175365D01*
X909113Y175323D01*
X909488Y175157D01*
G01X906722Y173365D02*
X906472Y173073D01*
X906138Y172907D01*
X905763Y172865D01*
X905430Y172907D01*
X905097Y173115D01*
X904888Y173365D01*
X904847Y173615D01*
X904930Y173907D01*
X905222Y174115D01*
X905513Y174198D01*
X905888D01*
G01X905513D02*
X905263Y174323D01*
X905055Y174532D01*
X904972Y174782D01*
X905055Y175032D01*
X905263Y175240D01*
X905638Y175365D01*
X906013Y175323D01*
X906388Y175157D01*
G01X891200Y158000D02*
Y155500D01*
G01X892158Y158000D02*
X890242D01*
G01X888933Y155500D02*
Y158000D01*
X887933D01*
X887600Y157875D01*
X887350Y157583D01*
X887267Y157250D01*
X887350Y156917D01*
X887558Y156667D01*
X887933Y156542D01*
X888933D01*
G01X885792Y157583D02*
X885542Y157833D01*
X885250Y157958D01*
X884917Y158000D01*
X884500Y157917D01*
X884208Y157708D01*
X884125Y157458D01*
X884167Y157208D01*
X884333Y157000D01*
X885167Y156583D01*
X885542Y156292D01*
X885792Y155875D01*
X885875Y155500D01*
X884125D01*
G01X881900Y158000D02*
X882233Y157917D01*
X882483Y157708D01*
X882650Y157458D01*
X882775Y157125D01*
X882817Y156750D01*
X882775Y156375D01*
X882650Y156042D01*
X882483Y155792D01*
X882233Y155583D01*
X881900Y155500D01*
X881567Y155583D01*
X881317Y155792D01*
X881150Y156042D01*
X881025Y156375D01*
X880983Y156750D01*
X881025Y157125D01*
X881150Y157458D01*
X881317Y157708D01*
X881567Y157917D01*
X881900Y158000D01*
G01X878300Y155500D02*
Y158000D01*
X879842Y156208D01*
X877758D01*
G01X891700Y145500D02*
Y143000D01*
G01X892658Y145500D02*
X890742D01*
G01X889433Y143000D02*
Y145500D01*
X888433D01*
X888100Y145375D01*
X887850Y145083D01*
X887767Y144750D01*
X887850Y144417D01*
X888058Y144167D01*
X888433Y144042D01*
X889433D01*
G01X886292Y145083D02*
X886042Y145333D01*
X885750Y145458D01*
X885417Y145500D01*
X885000Y145417D01*
X884708Y145208D01*
X884625Y144958D01*
X884667Y144708D01*
X884833Y144500D01*
X885667Y144083D01*
X886042Y143792D01*
X886292Y143375D01*
X886375Y143000D01*
X884625D01*
G01X882400Y145500D02*
X882733Y145417D01*
X882983Y145208D01*
X883150Y144958D01*
X883275Y144625D01*
X883317Y144250D01*
X883275Y143875D01*
X883150Y143542D01*
X882983Y143292D01*
X882733Y143083D01*
X882400Y143000D01*
X882067Y143083D01*
X881817Y143292D01*
X881650Y143542D01*
X881525Y143875D01*
X881483Y144250D01*
X881525Y144625D01*
X881650Y144958D01*
X881817Y145208D01*
X882067Y145417D01*
X882400Y145500D01*
G01X880217Y143500D02*
X879967Y143208D01*
X879633Y143042D01*
X879258Y143000D01*
X878925Y143042D01*
X878592Y143250D01*
X878383Y143500D01*
X878342Y143750D01*
X878425Y144042D01*
X878717Y144250D01*
X879008Y144333D01*
X879383D01*
G01X879008D02*
X878758Y144458D01*
X878550Y144667D01*
X878467Y144917D01*
X878550Y145167D01*
X878758Y145375D01*
X879133Y145500D01*
X879508Y145458D01*
X879883Y145292D01*
G01X891700Y153500D02*
Y151000D01*
G01X892658Y153500D02*
X890742D01*
G01X889433Y151000D02*
Y153500D01*
X888433D01*
X888100Y153375D01*
X887850Y153083D01*
X887767Y152750D01*
X887850Y152417D01*
X888058Y152167D01*
X888433Y152042D01*
X889433D01*
G01X886292Y153083D02*
X886042Y153333D01*
X885750Y153458D01*
X885417Y153500D01*
X885000Y153417D01*
X884708Y153208D01*
X884625Y152958D01*
X884667Y152708D01*
X884833Y152500D01*
X885667Y152083D01*
X886042Y151792D01*
X886292Y151375D01*
X886375Y151000D01*
X884625D01*
G01X882400Y153500D02*
X882733Y153417D01*
X882983Y153208D01*
X883150Y152958D01*
X883275Y152625D01*
X883317Y152250D01*
X883275Y151875D01*
X883150Y151542D01*
X882983Y151292D01*
X882733Y151083D01*
X882400Y151000D01*
X882067Y151083D01*
X881817Y151292D01*
X881650Y151542D01*
X881525Y151875D01*
X881483Y152250D01*
X881525Y152625D01*
X881650Y152958D01*
X881817Y153208D01*
X882067Y153417D01*
X882400Y153500D01*
G01X879300D02*
X879633Y153417D01*
X879883Y153208D01*
X880050Y152958D01*
X880175Y152625D01*
X880217Y152250D01*
X880175Y151875D01*
X880050Y151542D01*
X879883Y151292D01*
X879633Y151083D01*
X879300Y151000D01*
X878967Y151083D01*
X878717Y151292D01*
X878550Y151542D01*
X878425Y151875D01*
X878383Y152250D01*
X878425Y152625D01*
X878550Y152958D01*
X878717Y153208D01*
X878967Y153417D01*
X879300Y153500D01*
G01X891700Y149500D02*
Y147000D01*
G01X892658Y149500D02*
X890742D01*
G01X889433Y147000D02*
Y149500D01*
X888433D01*
X888100Y149375D01*
X887850Y149083D01*
X887767Y148750D01*
X887850Y148417D01*
X888058Y148167D01*
X888433Y148042D01*
X889433D01*
G01X885500Y147000D02*
Y149500D01*
X886000Y149000D01*
G01Y147000D02*
X885000D01*
G01X883317Y147500D02*
X883067Y147208D01*
X882733Y147042D01*
X882358Y147000D01*
X882025Y147042D01*
X881692Y147250D01*
X881483Y147500D01*
X881442Y147750D01*
X881525Y148042D01*
X881817Y148250D01*
X882108Y148333D01*
X882483D01*
G01X882108D02*
X881858Y148458D01*
X881650Y148667D01*
X881567Y148917D01*
X881650Y149167D01*
X881858Y149375D01*
X882233Y149500D01*
X882608Y149458D01*
X882983Y149292D01*
G01X880217Y147375D02*
X879967Y147167D01*
X879675Y147042D01*
X879300Y147000D01*
X878925Y147083D01*
X878633Y147250D01*
X878425Y147542D01*
X878383Y147875D01*
X878467Y148208D01*
X878675Y148417D01*
X878967Y148583D01*
X879258Y148625D01*
X879550Y148583D01*
X879925Y148417D01*
X879800Y149500D01*
X878675D01*
G01X893333Y194271D02*
X893583Y194396D01*
X893875Y194479D01*
X894208D01*
X894583Y194354D01*
X894875Y194146D01*
X895083Y193896D01*
X895250Y193479D01*
X895292Y193104D01*
X895208Y192729D01*
X895083Y192479D01*
X894833Y192229D01*
X894542Y192062D01*
X894250Y191979D01*
X893958D01*
X893667Y192062D01*
X893417Y192187D01*
X893208Y192354D01*
G01X892067D02*
X891817Y192146D01*
X891525Y192021D01*
X891150Y191979D01*
X890775Y192062D01*
X890483Y192229D01*
X890275Y192521D01*
X890233Y192854D01*
X890317Y193187D01*
X890525Y193396D01*
X890817Y193562D01*
X891108Y193604D01*
X891400Y193562D01*
X891775Y193396D01*
X891650Y194479D01*
X890525D01*
G01X888133Y191979D02*
X888050Y192521D01*
X887925Y192979D01*
X887758Y193396D01*
X887550Y193854D01*
X887217Y194479D01*
X888883D01*
G01X885033Y191979D02*
X884950Y192521D01*
X884825Y192979D01*
X884658Y193396D01*
X884450Y193854D01*
X884117Y194479D01*
X885783D01*
G01X893333Y206121D02*
X893583Y206246D01*
X893875Y206329D01*
X894208D01*
X894583Y206204D01*
X894875Y205996D01*
X895083Y205746D01*
X895250Y205329D01*
X895292Y204954D01*
X895208Y204579D01*
X895083Y204329D01*
X894833Y204079D01*
X894542Y203912D01*
X894250Y203829D01*
X893958D01*
X893667Y203912D01*
X893417Y204037D01*
X893208Y204204D01*
G01X892067D02*
X891817Y203996D01*
X891525Y203871D01*
X891150Y203829D01*
X890775Y203912D01*
X890483Y204079D01*
X890275Y204371D01*
X890233Y204704D01*
X890317Y205037D01*
X890525Y205246D01*
X890817Y205412D01*
X891108Y205454D01*
X891400Y205412D01*
X891775Y205246D01*
X891650Y206329D01*
X890525D01*
G01X888842Y204871D02*
X888550Y205162D01*
X888300Y205329D01*
X887967Y205412D01*
X887675Y205329D01*
X887467Y205162D01*
X887300Y204912D01*
X887258Y204621D01*
X887300Y204371D01*
X887467Y204121D01*
X887717Y203912D01*
X888008Y203829D01*
X888342Y203912D01*
X888633Y204162D01*
X888800Y204537D01*
X888842Y204954D01*
X888758Y205496D01*
X888633Y205787D01*
X888425Y206079D01*
X888133Y206287D01*
X887842Y206329D01*
X887550Y206246D01*
X887342Y206037D01*
G01X885867Y204329D02*
X885617Y204037D01*
X885283Y203871D01*
X884908Y203829D01*
X884575Y203871D01*
X884242Y204079D01*
X884033Y204329D01*
X883992Y204579D01*
X884075Y204871D01*
X884367Y205079D01*
X884658Y205162D01*
X885033D01*
G01X884658D02*
X884408Y205287D01*
X884200Y205496D01*
X884117Y205746D01*
X884200Y205996D01*
X884408Y206204D01*
X884783Y206329D01*
X885158Y206287D01*
X885533Y206121D01*
G01X893333Y198221D02*
X893583Y198346D01*
X893875Y198429D01*
X894208D01*
X894583Y198304D01*
X894875Y198096D01*
X895083Y197846D01*
X895250Y197429D01*
X895292Y197054D01*
X895208Y196679D01*
X895083Y196429D01*
X894833Y196179D01*
X894542Y196012D01*
X894250Y195929D01*
X893958D01*
X893667Y196012D01*
X893417Y196137D01*
X893208Y196304D01*
G01X892067D02*
X891817Y196096D01*
X891525Y195971D01*
X891150Y195929D01*
X890775Y196012D01*
X890483Y196179D01*
X890275Y196471D01*
X890233Y196804D01*
X890317Y197137D01*
X890525Y197346D01*
X890817Y197512D01*
X891108Y197554D01*
X891400Y197512D01*
X891775Y197346D01*
X891650Y198429D01*
X890525D01*
G01X888842Y196971D02*
X888550Y197262D01*
X888300Y197429D01*
X887967Y197512D01*
X887675Y197429D01*
X887467Y197262D01*
X887300Y197012D01*
X887258Y196721D01*
X887300Y196471D01*
X887467Y196221D01*
X887717Y196012D01*
X888008Y195929D01*
X888342Y196012D01*
X888633Y196262D01*
X888800Y196637D01*
X888842Y197054D01*
X888758Y197596D01*
X888633Y197887D01*
X888425Y198179D01*
X888133Y198387D01*
X887842Y198429D01*
X887550Y198346D01*
X887342Y198137D01*
G01X885742Y198012D02*
X885492Y198262D01*
X885200Y198387D01*
X884867Y198429D01*
X884450Y198346D01*
X884158Y198137D01*
X884075Y197887D01*
X884117Y197637D01*
X884283Y197429D01*
X885117Y197012D01*
X885492Y196721D01*
X885742Y196304D01*
X885825Y195929D01*
X884075D01*
G01X893333Y202171D02*
X893583Y202296D01*
X893875Y202379D01*
X894208D01*
X894583Y202254D01*
X894875Y202046D01*
X895083Y201796D01*
X895250Y201379D01*
X895292Y201004D01*
X895208Y200629D01*
X895083Y200379D01*
X894833Y200129D01*
X894542Y199962D01*
X894250Y199879D01*
X893958D01*
X893667Y199962D01*
X893417Y200087D01*
X893208Y200254D01*
G01X892067D02*
X891817Y200046D01*
X891525Y199921D01*
X891150Y199879D01*
X890775Y199962D01*
X890483Y200129D01*
X890275Y200421D01*
X890233Y200754D01*
X890317Y201087D01*
X890525Y201296D01*
X890817Y201462D01*
X891108Y201504D01*
X891400Y201462D01*
X891775Y201296D01*
X891650Y202379D01*
X890525D01*
G01X888842Y200921D02*
X888550Y201212D01*
X888300Y201379D01*
X887967Y201462D01*
X887675Y201379D01*
X887467Y201212D01*
X887300Y200962D01*
X887258Y200671D01*
X887300Y200421D01*
X887467Y200171D01*
X887717Y199962D01*
X888008Y199879D01*
X888342Y199962D01*
X888633Y200212D01*
X888800Y200587D01*
X888842Y201004D01*
X888758Y201546D01*
X888633Y201837D01*
X888425Y202129D01*
X888133Y202337D01*
X887842Y202379D01*
X887550Y202296D01*
X887342Y202087D01*
G01X884950Y199879D02*
Y202379D01*
X885450Y201879D01*
G01Y199879D02*
X884450D01*
G01X893333Y210021D02*
X893583Y210146D01*
X893875Y210229D01*
X894208D01*
X894583Y210104D01*
X894875Y209896D01*
X895083Y209646D01*
X895250Y209229D01*
X895292Y208854D01*
X895208Y208479D01*
X895083Y208229D01*
X894833Y207979D01*
X894542Y207812D01*
X894250Y207729D01*
X893958D01*
X893667Y207812D01*
X893417Y207937D01*
X893208Y208104D01*
G01X892067D02*
X891817Y207896D01*
X891525Y207771D01*
X891150Y207729D01*
X890775Y207812D01*
X890483Y207979D01*
X890275Y208271D01*
X890233Y208604D01*
X890317Y208937D01*
X890525Y209146D01*
X890817Y209312D01*
X891108Y209354D01*
X891400Y209312D01*
X891775Y209146D01*
X891650Y210229D01*
X890525D01*
G01X888967Y208229D02*
X888717Y207937D01*
X888383Y207771D01*
X888008Y207729D01*
X887675Y207771D01*
X887342Y207979D01*
X887133Y208229D01*
X887092Y208479D01*
X887175Y208771D01*
X887467Y208979D01*
X887758Y209062D01*
X888133D01*
G01X887758D02*
X887508Y209187D01*
X887300Y209396D01*
X887217Y209646D01*
X887300Y209896D01*
X887508Y210104D01*
X887883Y210229D01*
X888258Y210187D01*
X888633Y210021D01*
G01X884950Y207729D02*
X884658Y207771D01*
X884325Y207896D01*
X884117Y208104D01*
X884033Y208396D01*
X884117Y208687D01*
X884367Y208937D01*
X884742Y209062D01*
X885158D01*
X885408Y209146D01*
X885617Y209354D01*
X885700Y209646D01*
X885575Y209937D01*
X885283Y210146D01*
X884950Y210229D01*
X884617Y210146D01*
X884325Y209937D01*
X884200Y209646D01*
X884283Y209354D01*
X884492Y209146D01*
X884742Y209062D01*
X885158D01*
X885533Y208937D01*
X885783Y208687D01*
X885867Y208396D01*
X885783Y208104D01*
X885575Y207896D01*
X885242Y207771D01*
X884950Y207729D01*
G01X915733Y190292D02*
X915983Y190417D01*
X916275Y190500D01*
X916608D01*
X916983Y190375D01*
X917275Y190167D01*
X917483Y189917D01*
X917650Y189500D01*
X917692Y189125D01*
X917608Y188750D01*
X917483Y188500D01*
X917233Y188250D01*
X916942Y188083D01*
X916650Y188000D01*
X916358D01*
X916067Y188083D01*
X915817Y188208D01*
X915608Y188375D01*
G01X913050Y188000D02*
Y190500D01*
X914592Y188708D01*
X912508D01*
G01X911158Y188292D02*
X910867Y188083D01*
X910533Y188000D01*
X910200Y188083D01*
X909908Y188333D01*
X909700Y188708D01*
X909617Y189083D01*
Y189542D01*
X909700Y189917D01*
X909908Y190250D01*
X910158Y190417D01*
X910450Y190500D01*
X910783Y190417D01*
X911033Y190250D01*
X911200Y190000D01*
X911283Y189667D01*
X911200Y189375D01*
X910992Y189083D01*
X910742Y188917D01*
X910450Y188875D01*
X910117Y188958D01*
X909867Y189167D01*
X909617Y189542D01*
G01X908058Y188292D02*
X907767Y188083D01*
X907433Y188000D01*
X907100Y188083D01*
X906808Y188333D01*
X906600Y188708D01*
X906517Y189083D01*
Y189542D01*
X906600Y189917D01*
X906808Y190250D01*
X907058Y190417D01*
X907350Y190500D01*
X907683Y190417D01*
X907933Y190250D01*
X908100Y190000D01*
X908183Y189667D01*
X908100Y189375D01*
X907892Y189083D01*
X907642Y188917D01*
X907350Y188875D01*
X907017Y188958D01*
X906767Y189167D01*
X906517Y189542D01*
G01X893333Y190371D02*
X893583Y190496D01*
X893875Y190579D01*
X894208D01*
X894583Y190454D01*
X894875Y190246D01*
X895083Y189996D01*
X895250Y189579D01*
X895292Y189204D01*
X895208Y188829D01*
X895083Y188579D01*
X894833Y188329D01*
X894542Y188162D01*
X894250Y188079D01*
X893958D01*
X893667Y188162D01*
X893417Y188287D01*
X893208Y188454D01*
G01X890650Y188079D02*
Y190579D01*
X892192Y188787D01*
X890108D01*
G01X888758Y188371D02*
X888467Y188162D01*
X888133Y188079D01*
X887800Y188162D01*
X887508Y188412D01*
X887300Y188787D01*
X887217Y189162D01*
Y189621D01*
X887300Y189996D01*
X887508Y190329D01*
X887758Y190496D01*
X888050Y190579D01*
X888383Y190496D01*
X888633Y190329D01*
X888800Y190079D01*
X888883Y189746D01*
X888800Y189454D01*
X888592Y189162D01*
X888342Y188996D01*
X888050Y188954D01*
X887717Y189037D01*
X887467Y189246D01*
X887217Y189621D01*
G01X885867Y188579D02*
X885617Y188287D01*
X885283Y188121D01*
X884908Y188079D01*
X884575Y188121D01*
X884242Y188329D01*
X884033Y188579D01*
X883992Y188829D01*
X884075Y189121D01*
X884367Y189329D01*
X884658Y189412D01*
X885033D01*
G01X884658D02*
X884408Y189537D01*
X884200Y189746D01*
X884117Y189996D01*
X884200Y190246D01*
X884408Y190454D01*
X884783Y190579D01*
X885158Y190537D01*
X885533Y190371D01*
G01X891179Y186755D02*
X891429Y186880D01*
X891721Y186963D01*
X892054D01*
X892429Y186838D01*
X892721Y186630D01*
X892929Y186380D01*
X893096Y185963D01*
X893138Y185588D01*
X893054Y185213D01*
X892929Y184963D01*
X892679Y184713D01*
X892388Y184546D01*
X892096Y184463D01*
X891804D01*
X891513Y184546D01*
X891263Y184671D01*
X891054Y184838D01*
G01X888496Y184463D02*
Y186963D01*
X890038Y185171D01*
X887954D01*
G01X886604Y184755D02*
X886313Y184546D01*
X885979Y184463D01*
X885646Y184546D01*
X885354Y184796D01*
X885146Y185171D01*
X885063Y185546D01*
Y186005D01*
X885146Y186380D01*
X885354Y186713D01*
X885604Y186880D01*
X885896Y186963D01*
X886229Y186880D01*
X886479Y186713D01*
X886646Y186463D01*
X886729Y186130D01*
X886646Y185838D01*
X886438Y185546D01*
X886188Y185380D01*
X885896Y185338D01*
X885563Y185421D01*
X885313Y185630D01*
X885063Y186005D01*
G01X883588Y186546D02*
X883338Y186796D01*
X883046Y186921D01*
X882713Y186963D01*
X882296Y186880D01*
X882004Y186671D01*
X881921Y186421D01*
X881963Y186171D01*
X882129Y185963D01*
X882963Y185546D01*
X883338Y185255D01*
X883588Y184838D01*
X883671Y184463D01*
X881921D01*
G01X913233Y194792D02*
X913483Y194917D01*
X913775Y195000D01*
X914108D01*
X914483Y194875D01*
X914775Y194667D01*
X914983Y194417D01*
X915150Y194000D01*
X915192Y193625D01*
X915108Y193250D01*
X914983Y193000D01*
X914733Y192750D01*
X914442Y192583D01*
X914150Y192500D01*
X913858D01*
X913567Y192583D01*
X913317Y192708D01*
X913108Y192875D01*
G01X910550Y192500D02*
Y195000D01*
X912092Y193208D01*
X910008D01*
G01X908658Y192792D02*
X908367Y192583D01*
X908033Y192500D01*
X907700Y192583D01*
X907408Y192833D01*
X907200Y193208D01*
X907117Y193583D01*
Y194042D01*
X907200Y194417D01*
X907408Y194750D01*
X907658Y194917D01*
X907950Y195000D01*
X908283Y194917D01*
X908533Y194750D01*
X908700Y194500D01*
X908783Y194167D01*
X908700Y193875D01*
X908492Y193583D01*
X908242Y193417D01*
X907950Y193375D01*
X907617Y193458D01*
X907367Y193667D01*
X907117Y194042D01*
G01X904850Y192500D02*
Y195000D01*
X905350Y194500D01*
G01Y192500D02*
X904350D01*
G01X910183Y209292D02*
X910433Y209417D01*
X910725Y209500D01*
X911058D01*
X911433Y209375D01*
X911725Y209167D01*
X911933Y208917D01*
X912100Y208500D01*
X912142Y208125D01*
X912058Y207750D01*
X911933Y207500D01*
X911683Y207250D01*
X911392Y207083D01*
X911100Y207000D01*
X910808D01*
X910517Y207083D01*
X910267Y207208D01*
X910058Y207375D01*
G01X908917Y207500D02*
X908667Y207208D01*
X908333Y207042D01*
X907958Y207000D01*
X907625Y207042D01*
X907292Y207250D01*
X907083Y207500D01*
X907042Y207750D01*
X907125Y208042D01*
X907417Y208250D01*
X907708Y208333D01*
X908083D01*
G01X907708D02*
X907458Y208458D01*
X907250Y208667D01*
X907167Y208917D01*
X907250Y209167D01*
X907458Y209375D01*
X907833Y209500D01*
X908208Y209458D01*
X908583Y209292D01*
G01X905817Y207500D02*
X905567Y207208D01*
X905233Y207042D01*
X904858Y207000D01*
X904525Y207042D01*
X904192Y207250D01*
X903983Y207500D01*
X903942Y207750D01*
X904025Y208042D01*
X904317Y208250D01*
X904608Y208333D01*
X904983D01*
G01X904608D02*
X904358Y208458D01*
X904150Y208667D01*
X904067Y208917D01*
X904150Y209167D01*
X904358Y209375D01*
X904733Y209500D01*
X905108Y209458D01*
X905483Y209292D01*
G01X907683Y242967D02*
X907808Y242717D01*
X907891Y242425D01*
Y242092D01*
X907766Y241717D01*
X907558Y241425D01*
X907308Y241217D01*
X906891Y241050D01*
X906516Y241008D01*
X906141Y241092D01*
X905891Y241217D01*
X905641Y241467D01*
X905474Y241758D01*
X905391Y242050D01*
Y242342D01*
X905474Y242633D01*
X905599Y242883D01*
X905766Y243092D01*
G01X906433Y244358D02*
X906724Y244650D01*
X906891Y244900D01*
X906974Y245233D01*
X906891Y245525D01*
X906724Y245733D01*
X906474Y245900D01*
X906183Y245942D01*
X905933Y245900D01*
X905683Y245733D01*
X905474Y245483D01*
X905391Y245192D01*
X905474Y244858D01*
X905724Y244567D01*
X906099Y244400D01*
X906516Y244358D01*
X907058Y244442D01*
X907349Y244567D01*
X907641Y244775D01*
X907849Y245067D01*
X907891Y245358D01*
X907808Y245650D01*
X907599Y245858D01*
G01X907891Y248250D02*
X907808Y247917D01*
X907599Y247667D01*
X907349Y247500D01*
X907016Y247375D01*
X906641Y247333D01*
X906266Y247375D01*
X905933Y247500D01*
X905683Y247667D01*
X905474Y247917D01*
X905391Y248250D01*
X905474Y248583D01*
X905683Y248833D01*
X905933Y249000D01*
X906266Y249125D01*
X906641Y249167D01*
X907016Y249125D01*
X907349Y249000D01*
X907599Y248833D01*
X907808Y248583D01*
X907891Y248250D01*
G01X905391Y251850D02*
X907891D01*
X906099Y250308D01*
Y252392D01*
G01X893233Y241292D02*
X893483Y241417D01*
X893775Y241500D01*
X894108D01*
X894483Y241375D01*
X894775Y241167D01*
X894983Y240917D01*
X895150Y240500D01*
X895192Y240125D01*
X895108Y239750D01*
X894983Y239500D01*
X894733Y239250D01*
X894442Y239083D01*
X894150Y239000D01*
X893858D01*
X893567Y239083D01*
X893317Y239208D01*
X893108Y239375D01*
G01X891967D02*
X891717Y239167D01*
X891425Y239042D01*
X891050Y239000D01*
X890675Y239083D01*
X890383Y239250D01*
X890175Y239542D01*
X890133Y239875D01*
X890217Y240208D01*
X890425Y240417D01*
X890717Y240583D01*
X891008Y240625D01*
X891300Y240583D01*
X891675Y240417D01*
X891550Y241500D01*
X890425D01*
G01X887450Y239000D02*
Y241500D01*
X888992Y239708D01*
X886908D01*
G01X884350Y239000D02*
Y241500D01*
X885892Y239708D01*
X883808D01*
G01X899846Y242967D02*
X899971Y242717D01*
X900054Y242425D01*
Y242092D01*
X899929Y241717D01*
X899721Y241425D01*
X899471Y241217D01*
X899054Y241050D01*
X898679Y241008D01*
X898304Y241092D01*
X898054Y241217D01*
X897804Y241467D01*
X897637Y241758D01*
X897554Y242050D01*
Y242342D01*
X897637Y242633D01*
X897762Y242883D01*
X897929Y243092D01*
G01Y244233D02*
X897721Y244483D01*
X897596Y244775D01*
X897554Y245150D01*
X897637Y245525D01*
X897804Y245817D01*
X898096Y246025D01*
X898429Y246067D01*
X898762Y245983D01*
X898971Y245775D01*
X899137Y245483D01*
X899179Y245192D01*
X899137Y244900D01*
X898971Y244525D01*
X900054Y244650D01*
Y245775D01*
G01X897554Y248750D02*
X900054D01*
X898262Y247208D01*
Y249292D01*
G01X898054Y250433D02*
X897762Y250683D01*
X897596Y251017D01*
X897554Y251392D01*
X897596Y251725D01*
X897804Y252058D01*
X898054Y252267D01*
X898304Y252308D01*
X898596Y252225D01*
X898804Y251933D01*
X898887Y251642D01*
Y251267D01*
G01Y251642D02*
X899012Y251892D01*
X899221Y252100D01*
X899471Y252183D01*
X899721Y252100D01*
X899929Y251892D01*
X900054Y251517D01*
X900012Y251142D01*
X899846Y250767D01*
G01X903753Y242967D02*
X903878Y242717D01*
X903961Y242425D01*
Y242092D01*
X903836Y241717D01*
X903628Y241425D01*
X903378Y241217D01*
X902961Y241050D01*
X902586Y241008D01*
X902211Y241092D01*
X901961Y241217D01*
X901711Y241467D01*
X901544Y241758D01*
X901461Y242050D01*
Y242342D01*
X901544Y242633D01*
X901669Y242883D01*
X901836Y243092D01*
G01Y244233D02*
X901628Y244483D01*
X901503Y244775D01*
X901461Y245150D01*
X901544Y245525D01*
X901711Y245817D01*
X902003Y246025D01*
X902336Y246067D01*
X902669Y245983D01*
X902878Y245775D01*
X903044Y245483D01*
X903086Y245192D01*
X903044Y244900D01*
X902878Y244525D01*
X903961Y244650D01*
Y245775D01*
G01X901461Y248750D02*
X903961D01*
X902169Y247208D01*
Y249292D01*
G01X903544Y250558D02*
X903794Y250808D01*
X903919Y251100D01*
X903961Y251433D01*
X903878Y251850D01*
X903669Y252142D01*
X903419Y252225D01*
X903169Y252183D01*
X902961Y252017D01*
X902544Y251183D01*
X902253Y250808D01*
X901836Y250558D01*
X901461Y250475D01*
Y252225D01*
G01X893333Y233653D02*
X893583Y233778D01*
X893875Y233861D01*
X894208D01*
X894583Y233736D01*
X894875Y233528D01*
X895083Y233278D01*
X895250Y232861D01*
X895292Y232486D01*
X895208Y232111D01*
X895083Y231861D01*
X894833Y231611D01*
X894542Y231444D01*
X894250Y231361D01*
X893958D01*
X893667Y231444D01*
X893417Y231569D01*
X893208Y231736D01*
G01X892067D02*
X891817Y231528D01*
X891525Y231403D01*
X891150Y231361D01*
X890775Y231444D01*
X890483Y231611D01*
X890275Y231903D01*
X890233Y232236D01*
X890317Y232569D01*
X890525Y232778D01*
X890817Y232944D01*
X891108Y232986D01*
X891400Y232944D01*
X891775Y232778D01*
X891650Y233861D01*
X890525D01*
G01X888967Y231861D02*
X888717Y231569D01*
X888383Y231403D01*
X888008Y231361D01*
X887675Y231403D01*
X887342Y231611D01*
X887133Y231861D01*
X887092Y232111D01*
X887175Y232403D01*
X887467Y232611D01*
X887758Y232694D01*
X888133D01*
G01X887758D02*
X887508Y232819D01*
X887300Y233028D01*
X887217Y233278D01*
X887300Y233528D01*
X887508Y233736D01*
X887883Y233861D01*
X888258Y233819D01*
X888633Y233653D01*
G01X885658Y231653D02*
X885367Y231444D01*
X885033Y231361D01*
X884700Y231444D01*
X884408Y231694D01*
X884200Y232069D01*
X884117Y232444D01*
Y232903D01*
X884200Y233278D01*
X884408Y233611D01*
X884658Y233778D01*
X884950Y233861D01*
X885283Y233778D01*
X885533Y233611D01*
X885700Y233361D01*
X885783Y233028D01*
X885700Y232736D01*
X885492Y232444D01*
X885242Y232278D01*
X884950Y232236D01*
X884617Y232319D01*
X884367Y232528D01*
X884117Y232903D01*
G01X893333Y213971D02*
X893583Y214096D01*
X893875Y214179D01*
X894208D01*
X894583Y214054D01*
X894875Y213846D01*
X895083Y213596D01*
X895250Y213179D01*
X895292Y212804D01*
X895208Y212429D01*
X895083Y212179D01*
X894833Y211929D01*
X894542Y211762D01*
X894250Y211679D01*
X893958D01*
X893667Y211762D01*
X893417Y211887D01*
X893208Y212054D01*
G01X892067D02*
X891817Y211846D01*
X891525Y211721D01*
X891150Y211679D01*
X890775Y211762D01*
X890483Y211929D01*
X890275Y212221D01*
X890233Y212554D01*
X890317Y212887D01*
X890525Y213096D01*
X890817Y213262D01*
X891108Y213304D01*
X891400Y213262D01*
X891775Y213096D01*
X891650Y214179D01*
X890525D01*
G01X888967Y212179D02*
X888717Y211887D01*
X888383Y211721D01*
X888008Y211679D01*
X887675Y211721D01*
X887342Y211929D01*
X887133Y212179D01*
X887092Y212429D01*
X887175Y212721D01*
X887467Y212929D01*
X887758Y213012D01*
X888133D01*
G01X887758D02*
X887508Y213137D01*
X887300Y213346D01*
X887217Y213596D01*
X887300Y213846D01*
X887508Y214054D01*
X887883Y214179D01*
X888258Y214137D01*
X888633Y213971D01*
G01X885033Y211679D02*
X884950Y212221D01*
X884825Y212679D01*
X884658Y213096D01*
X884450Y213554D01*
X884117Y214179D01*
X885783D01*
G01X893333Y217921D02*
X893583Y218046D01*
X893875Y218129D01*
X894208D01*
X894583Y218004D01*
X894875Y217796D01*
X895083Y217546D01*
X895250Y217129D01*
X895292Y216754D01*
X895208Y216379D01*
X895083Y216129D01*
X894833Y215879D01*
X894542Y215712D01*
X894250Y215629D01*
X893958D01*
X893667Y215712D01*
X893417Y215837D01*
X893208Y216004D01*
G01X892067D02*
X891817Y215796D01*
X891525Y215671D01*
X891150Y215629D01*
X890775Y215712D01*
X890483Y215879D01*
X890275Y216171D01*
X890233Y216504D01*
X890317Y216837D01*
X890525Y217046D01*
X890817Y217212D01*
X891108Y217254D01*
X891400Y217212D01*
X891775Y217046D01*
X891650Y218129D01*
X890525D01*
G01X888967Y216129D02*
X888717Y215837D01*
X888383Y215671D01*
X888008Y215629D01*
X887675Y215671D01*
X887342Y215879D01*
X887133Y216129D01*
X887092Y216379D01*
X887175Y216671D01*
X887467Y216879D01*
X887758Y216962D01*
X888133D01*
G01X887758D02*
X887508Y217087D01*
X887300Y217296D01*
X887217Y217546D01*
X887300Y217796D01*
X887508Y218004D01*
X887883Y218129D01*
X888258Y218087D01*
X888633Y217921D01*
G01X885742Y216671D02*
X885450Y216962D01*
X885200Y217129D01*
X884867Y217212D01*
X884575Y217129D01*
X884367Y216962D01*
X884200Y216712D01*
X884158Y216421D01*
X884200Y216171D01*
X884367Y215921D01*
X884617Y215712D01*
X884908Y215629D01*
X885242Y215712D01*
X885533Y215962D01*
X885700Y216337D01*
X885742Y216754D01*
X885658Y217296D01*
X885533Y217587D01*
X885325Y217879D01*
X885033Y218087D01*
X884742Y218129D01*
X884450Y218046D01*
X884242Y217837D01*
G01X893333Y221821D02*
X893583Y221946D01*
X893875Y222029D01*
X894208D01*
X894583Y221904D01*
X894875Y221696D01*
X895083Y221446D01*
X895250Y221029D01*
X895292Y220654D01*
X895208Y220279D01*
X895083Y220029D01*
X894833Y219779D01*
X894542Y219612D01*
X894250Y219529D01*
X893958D01*
X893667Y219612D01*
X893417Y219737D01*
X893208Y219904D01*
G01X892067D02*
X891817Y219696D01*
X891525Y219571D01*
X891150Y219529D01*
X890775Y219612D01*
X890483Y219779D01*
X890275Y220071D01*
X890233Y220404D01*
X890317Y220737D01*
X890525Y220946D01*
X890817Y221112D01*
X891108Y221154D01*
X891400Y221112D01*
X891775Y220946D01*
X891650Y222029D01*
X890525D01*
G01X888967Y220029D02*
X888717Y219737D01*
X888383Y219571D01*
X888008Y219529D01*
X887675Y219571D01*
X887342Y219779D01*
X887133Y220029D01*
X887092Y220279D01*
X887175Y220571D01*
X887467Y220779D01*
X887758Y220862D01*
X888133D01*
G01X887758D02*
X887508Y220987D01*
X887300Y221196D01*
X887217Y221446D01*
X887300Y221696D01*
X887508Y221904D01*
X887883Y222029D01*
X888258Y221987D01*
X888633Y221821D01*
G01X885867Y219904D02*
X885617Y219696D01*
X885325Y219571D01*
X884950Y219529D01*
X884575Y219612D01*
X884283Y219779D01*
X884075Y220071D01*
X884033Y220404D01*
X884117Y220737D01*
X884325Y220946D01*
X884617Y221112D01*
X884908Y221154D01*
X885200Y221112D01*
X885575Y220946D01*
X885450Y222029D01*
X884325D01*
G01X893333Y225771D02*
X893583Y225896D01*
X893875Y225979D01*
X894208D01*
X894583Y225854D01*
X894875Y225646D01*
X895083Y225396D01*
X895250Y224979D01*
X895292Y224604D01*
X895208Y224229D01*
X895083Y223979D01*
X894833Y223729D01*
X894542Y223562D01*
X894250Y223479D01*
X893958D01*
X893667Y223562D01*
X893417Y223687D01*
X893208Y223854D01*
G01X892067D02*
X891817Y223646D01*
X891525Y223521D01*
X891150Y223479D01*
X890775Y223562D01*
X890483Y223729D01*
X890275Y224021D01*
X890233Y224354D01*
X890317Y224687D01*
X890525Y224896D01*
X890817Y225062D01*
X891108Y225104D01*
X891400Y225062D01*
X891775Y224896D01*
X891650Y225979D01*
X890525D01*
G01X888967Y223979D02*
X888717Y223687D01*
X888383Y223521D01*
X888008Y223479D01*
X887675Y223521D01*
X887342Y223729D01*
X887133Y223979D01*
X887092Y224229D01*
X887175Y224521D01*
X887467Y224729D01*
X887758Y224812D01*
X888133D01*
G01X887758D02*
X887508Y224937D01*
X887300Y225146D01*
X887217Y225396D01*
X887300Y225646D01*
X887508Y225854D01*
X887883Y225979D01*
X888258Y225937D01*
X888633Y225771D01*
G01X884450Y223479D02*
Y225979D01*
X885992Y224187D01*
X883908D01*
G01X893333Y229721D02*
X893583Y229846D01*
X893875Y229929D01*
X894208D01*
X894583Y229804D01*
X894875Y229596D01*
X895083Y229346D01*
X895250Y228929D01*
X895292Y228554D01*
X895208Y228179D01*
X895083Y227929D01*
X894833Y227679D01*
X894542Y227512D01*
X894250Y227429D01*
X893958D01*
X893667Y227512D01*
X893417Y227637D01*
X893208Y227804D01*
G01X892067D02*
X891817Y227596D01*
X891525Y227471D01*
X891150Y227429D01*
X890775Y227512D01*
X890483Y227679D01*
X890275Y227971D01*
X890233Y228304D01*
X890317Y228637D01*
X890525Y228846D01*
X890817Y229012D01*
X891108Y229054D01*
X891400Y229012D01*
X891775Y228846D01*
X891650Y229929D01*
X890525D01*
G01X888967Y227929D02*
X888717Y227637D01*
X888383Y227471D01*
X888008Y227429D01*
X887675Y227471D01*
X887342Y227679D01*
X887133Y227929D01*
X887092Y228179D01*
X887175Y228471D01*
X887467Y228679D01*
X887758Y228762D01*
X888133D01*
G01X887758D02*
X887508Y228887D01*
X887300Y229096D01*
X887217Y229346D01*
X887300Y229596D01*
X887508Y229804D01*
X887883Y229929D01*
X888258Y229887D01*
X888633Y229721D01*
G01X885867Y227929D02*
X885617Y227637D01*
X885283Y227471D01*
X884908Y227429D01*
X884575Y227471D01*
X884242Y227679D01*
X884033Y227929D01*
X883992Y228179D01*
X884075Y228471D01*
X884367Y228679D01*
X884658Y228762D01*
X885033D01*
G01X884658D02*
X884408Y228887D01*
X884200Y229096D01*
X884117Y229346D01*
X884200Y229596D01*
X884408Y229804D01*
X884783Y229929D01*
X885158Y229887D01*
X885533Y229721D01*
G01X915733Y225792D02*
X915983Y225917D01*
X916275Y226000D01*
X916608D01*
X916983Y225875D01*
X917275Y225667D01*
X917483Y225417D01*
X917650Y225000D01*
X917692Y224625D01*
X917608Y224250D01*
X917483Y224000D01*
X917233Y223750D01*
X916942Y223583D01*
X916650Y223500D01*
X916358D01*
X916067Y223583D01*
X915817Y223708D01*
X915608Y223875D01*
G01X914467D02*
X914217Y223667D01*
X913925Y223542D01*
X913550Y223500D01*
X913175Y223583D01*
X912883Y223750D01*
X912675Y224042D01*
X912633Y224375D01*
X912717Y224708D01*
X912925Y224917D01*
X913217Y225083D01*
X913508Y225125D01*
X913800Y225083D01*
X914175Y224917D01*
X914050Y226000D01*
X912925D01*
G01X910450Y223500D02*
Y226000D01*
X910950Y225500D01*
G01Y223500D02*
X909950D01*
G01X908267Y223875D02*
X908017Y223667D01*
X907725Y223542D01*
X907350Y223500D01*
X906975Y223583D01*
X906683Y223750D01*
X906475Y224042D01*
X906433Y224375D01*
X906517Y224708D01*
X906725Y224917D01*
X907017Y225083D01*
X907308Y225125D01*
X907600Y225083D01*
X907975Y224917D01*
X907850Y226000D01*
X906725D01*
G01X910183Y213792D02*
X910433Y213917D01*
X910725Y214000D01*
X911058D01*
X911433Y213875D01*
X911725Y213667D01*
X911933Y213417D01*
X912100Y213000D01*
X912142Y212625D01*
X912058Y212250D01*
X911933Y212000D01*
X911683Y211750D01*
X911392Y211583D01*
X911100Y211500D01*
X910808D01*
X910517Y211583D01*
X910267Y211708D01*
X910058Y211875D01*
G01X908792Y213583D02*
X908542Y213833D01*
X908250Y213958D01*
X907917Y214000D01*
X907500Y213917D01*
X907208Y213708D01*
X907125Y213458D01*
X907167Y213208D01*
X907333Y213000D01*
X908167Y212583D01*
X908542Y212292D01*
X908792Y211875D01*
X908875Y211500D01*
X907125D01*
G01X905608Y211792D02*
X905317Y211583D01*
X904983Y211500D01*
X904650Y211583D01*
X904358Y211833D01*
X904150Y212208D01*
X904067Y212583D01*
Y213042D01*
X904150Y213417D01*
X904358Y213750D01*
X904608Y213917D01*
X904900Y214000D01*
X905233Y213917D01*
X905483Y213750D01*
X905650Y213500D01*
X905733Y213167D01*
X905650Y212875D01*
X905442Y212583D01*
X905192Y212417D01*
X904900Y212375D01*
X904567Y212458D01*
X904317Y212667D01*
X904067Y213042D01*
G01X915233Y267453D02*
X915483Y267578D01*
X915775Y267661D01*
X916108D01*
X916483Y267536D01*
X916775Y267328D01*
X916983Y267078D01*
X917150Y266661D01*
X917192Y266286D01*
X917108Y265911D01*
X916983Y265661D01*
X916733Y265411D01*
X916442Y265244D01*
X916150Y265161D01*
X915858D01*
X915567Y265244D01*
X915317Y265369D01*
X915108Y265536D01*
G01X913967D02*
X913717Y265328D01*
X913425Y265203D01*
X913050Y265161D01*
X912675Y265244D01*
X912383Y265411D01*
X912175Y265703D01*
X912133Y266036D01*
X912217Y266369D01*
X912425Y266578D01*
X912717Y266744D01*
X913008Y266786D01*
X913300Y266744D01*
X913675Y266578D01*
X913550Y267661D01*
X912425D01*
G01X909950Y265161D02*
Y267661D01*
X910450Y267161D01*
G01Y265161D02*
X909450D01*
G01X907642Y266203D02*
X907350Y266494D01*
X907100Y266661D01*
X906767Y266744D01*
X906475Y266661D01*
X906267Y266494D01*
X906100Y266244D01*
X906058Y265953D01*
X906100Y265703D01*
X906267Y265453D01*
X906517Y265244D01*
X906808Y265161D01*
X907142Y265244D01*
X907433Y265494D01*
X907600Y265869D01*
X907642Y266286D01*
X907558Y266828D01*
X907433Y267119D01*
X907225Y267411D01*
X906933Y267619D01*
X906642Y267661D01*
X906350Y267578D01*
X906142Y267369D01*
G01X915233Y275453D02*
X915483Y275578D01*
X915775Y275661D01*
X916108D01*
X916483Y275536D01*
X916775Y275328D01*
X916983Y275078D01*
X917150Y274661D01*
X917192Y274286D01*
X917108Y273911D01*
X916983Y273661D01*
X916733Y273411D01*
X916442Y273244D01*
X916150Y273161D01*
X915858D01*
X915567Y273244D01*
X915317Y273369D01*
X915108Y273536D01*
G01X912550Y273161D02*
Y275661D01*
X914092Y273869D01*
X912008D01*
G01X910658Y273453D02*
X910367Y273244D01*
X910033Y273161D01*
X909700Y273244D01*
X909408Y273494D01*
X909200Y273869D01*
X909117Y274244D01*
Y274703D01*
X909200Y275078D01*
X909408Y275411D01*
X909658Y275578D01*
X909950Y275661D01*
X910283Y275578D01*
X910533Y275411D01*
X910700Y275161D01*
X910783Y274828D01*
X910700Y274536D01*
X910492Y274244D01*
X910242Y274078D01*
X909950Y274036D01*
X909617Y274119D01*
X909367Y274328D01*
X909117Y274703D01*
G01X906350Y273161D02*
Y275661D01*
X907892Y273869D01*
X905808D01*
G01X914095Y286587D02*
X914345Y286712D01*
X914637Y286795D01*
X914970D01*
X915345Y286670D01*
X915637Y286462D01*
X915845Y286212D01*
X916012Y285795D01*
X916054Y285420D01*
X915970Y285045D01*
X915845Y284795D01*
X915595Y284545D01*
X915304Y284378D01*
X915012Y284295D01*
X914720D01*
X914429Y284378D01*
X914179Y284503D01*
X913970Y284670D01*
G01X911412Y284295D02*
Y286795D01*
X912954Y285003D01*
X910870D01*
G01X909520Y284587D02*
X909229Y284378D01*
X908895Y284295D01*
X908562Y284378D01*
X908270Y284628D01*
X908062Y285003D01*
X907979Y285378D01*
Y285837D01*
X908062Y286212D01*
X908270Y286545D01*
X908520Y286712D01*
X908812Y286795D01*
X909145Y286712D01*
X909395Y286545D01*
X909562Y286295D01*
X909645Y285962D01*
X909562Y285670D01*
X909354Y285378D01*
X909104Y285212D01*
X908812Y285170D01*
X908479Y285253D01*
X908229Y285462D01*
X907979Y285837D01*
G01X906504Y285337D02*
X906212Y285628D01*
X905962Y285795D01*
X905629Y285878D01*
X905337Y285795D01*
X905129Y285628D01*
X904962Y285378D01*
X904920Y285087D01*
X904962Y284837D01*
X905129Y284587D01*
X905379Y284378D01*
X905670Y284295D01*
X906004Y284378D01*
X906295Y284628D01*
X906462Y285003D01*
X906504Y285420D01*
X906420Y285962D01*
X906295Y286253D01*
X906087Y286545D01*
X905795Y286753D01*
X905504Y286795D01*
X905212Y286712D01*
X905004Y286503D01*
G01X902019Y728919D02*
X904519D01*
Y729960D01*
X904394Y730294D01*
X904227Y730502D01*
X903894Y730585D01*
X903561Y730502D01*
X903352Y730252D01*
X903227Y729960D01*
Y728919D01*
G01Y729960D02*
X902019Y730585D01*
G01Y733352D02*
X904519D01*
X902727Y731810D01*
Y733894D01*
G01X902019Y735952D02*
X904519D01*
X904019Y735452D01*
G01X902019D02*
Y736452D01*
G01Y739552D02*
X904519D01*
X902727Y738010D01*
Y740094D01*
G01X902394Y741235D02*
X902186Y741485D01*
X902061Y741777D01*
X902019Y742152D01*
X902102Y742527D01*
X902269Y742819D01*
X902561Y743027D01*
X902894Y743069D01*
X903227Y742985D01*
X903436Y742777D01*
X903602Y742485D01*
X903644Y742194D01*
X903602Y741902D01*
X903436Y741527D01*
X904519Y741652D01*
Y742777D01*
G01X891406Y754098D02*
X895406D01*
Y746698D01*
G01X897729Y728919D02*
X900229D01*
Y729960D01*
X900104Y730294D01*
X899937Y730502D01*
X899604Y730585D01*
X899271Y730502D01*
X899062Y730252D01*
X898937Y729960D01*
Y728919D01*
G01Y729960D02*
X897729Y730585D01*
G01Y733352D02*
X900229D01*
X898437Y731810D01*
Y733894D01*
G01X897729Y735952D02*
X900229D01*
X899729Y735452D01*
G01X897729D02*
Y736452D01*
G01Y739552D02*
X900229D01*
X898437Y738010D01*
Y740094D01*
G01X898229Y741235D02*
X897937Y741485D01*
X897771Y741819D01*
X897729Y742194D01*
X897771Y742527D01*
X897979Y742860D01*
X898229Y743069D01*
X898479Y743110D01*
X898771Y743027D01*
X898979Y742735D01*
X899062Y742444D01*
Y742069D01*
G01Y742444D02*
X899187Y742694D01*
X899396Y742902D01*
X899646Y742985D01*
X899896Y742902D01*
X900104Y742694D01*
X900229Y742319D01*
X900187Y741944D01*
X900021Y741569D01*
G01X887306Y754098D02*
X891306D01*
Y746698D01*
G01X889590Y728874D02*
X892090D01*
Y729915D01*
X891965Y730249D01*
X891798Y730457D01*
X891465Y730540D01*
X891132Y730457D01*
X890923Y730207D01*
X890798Y729915D01*
Y728874D01*
G01Y729915D02*
X889590Y730540D01*
G01Y733307D02*
X892090D01*
X890298Y731765D01*
Y733849D01*
G01X889590Y735907D02*
X892090D01*
X891590Y735407D01*
G01X889590D02*
Y736407D01*
G01Y739507D02*
X892090D01*
X890298Y737965D01*
Y740049D01*
G01X889590Y742107D02*
X892090D01*
X891590Y741607D01*
G01X889590D02*
Y742607D01*
G01X883306Y754098D02*
X887306D01*
Y746698D01*
G01X881876Y729331D02*
X884376D01*
Y730372D01*
X884251Y730706D01*
X884084Y730914D01*
X883751Y730997D01*
X883418Y730914D01*
X883209Y730664D01*
X883084Y730372D01*
Y729331D01*
G01Y730372D02*
X881876Y730997D01*
G01Y733764D02*
X884376D01*
X882584Y732222D01*
Y734306D01*
G01X881876Y736364D02*
X884376D01*
X883876Y735864D01*
G01X881876D02*
Y736864D01*
G01X882376Y738547D02*
X882084Y738797D01*
X881918Y739131D01*
X881876Y739506D01*
X881918Y739839D01*
X882126Y740172D01*
X882376Y740381D01*
X882626Y740422D01*
X882918Y740339D01*
X883126Y740047D01*
X883209Y739756D01*
Y739381D01*
G01Y739756D02*
X883334Y740006D01*
X883543Y740214D01*
X883793Y740297D01*
X884043Y740214D01*
X884251Y740006D01*
X884376Y739631D01*
X884334Y739256D01*
X884168Y738881D01*
G01X882168Y741856D02*
X881959Y742147D01*
X881876Y742481D01*
X881959Y742814D01*
X882209Y743106D01*
X882584Y743314D01*
X882959Y743397D01*
X883418D01*
X883793Y743314D01*
X884126Y743106D01*
X884293Y742856D01*
X884376Y742564D01*
X884293Y742231D01*
X884126Y741981D01*
X883876Y741814D01*
X883543Y741731D01*
X883251Y741814D01*
X882959Y742022D01*
X882793Y742272D01*
X882751Y742564D01*
X882834Y742897D01*
X883043Y743147D01*
X883418Y743397D01*
G01X879306Y754098D02*
X883306D01*
Y746698D01*
G01X875185Y729420D02*
X877685D01*
Y730461D01*
X877560Y730795D01*
X877393Y731003D01*
X877060Y731086D01*
X876727Y731003D01*
X876518Y730753D01*
X876393Y730461D01*
Y729420D01*
G01Y730461D02*
X875185Y731086D01*
G01X875477Y732645D02*
X875268Y732936D01*
X875185Y733270D01*
X875268Y733603D01*
X875518Y733895D01*
X875893Y734103D01*
X876268Y734186D01*
X876727D01*
X877102Y734103D01*
X877435Y733895D01*
X877602Y733645D01*
X877685Y733353D01*
X877602Y733020D01*
X877435Y732770D01*
X877185Y732603D01*
X876852Y732520D01*
X876560Y732603D01*
X876268Y732811D01*
X876102Y733061D01*
X876060Y733353D01*
X876143Y733686D01*
X876352Y733936D01*
X876727Y734186D01*
G01X877685Y736453D02*
X877602Y736120D01*
X877393Y735870D01*
X877143Y735703D01*
X876810Y735578D01*
X876435Y735536D01*
X876060Y735578D01*
X875727Y735703D01*
X875477Y735870D01*
X875268Y736120D01*
X875185Y736453D01*
X875268Y736786D01*
X875477Y737036D01*
X875727Y737203D01*
X876060Y737328D01*
X876435Y737370D01*
X876810Y737328D01*
X877143Y737203D01*
X877393Y737036D01*
X877602Y736786D01*
X877685Y736453D01*
G01X875685Y738636D02*
X875393Y738886D01*
X875227Y739220D01*
X875185Y739595D01*
X875227Y739928D01*
X875435Y740261D01*
X875685Y740470D01*
X875935Y740511D01*
X876227Y740428D01*
X876435Y740136D01*
X876518Y739845D01*
Y739470D01*
G01Y739845D02*
X876643Y740095D01*
X876852Y740303D01*
X877102Y740386D01*
X877352Y740303D01*
X877560Y740095D01*
X877685Y739720D01*
X877643Y739345D01*
X877477Y738970D01*
G01X877268Y741861D02*
X877518Y742111D01*
X877643Y742403D01*
X877685Y742736D01*
X877602Y743153D01*
X877393Y743445D01*
X877143Y743528D01*
X876893Y743486D01*
X876685Y743320D01*
X876268Y742486D01*
X875977Y742111D01*
X875560Y741861D01*
X875185Y741778D01*
Y743528D01*
G01X875200Y754000D02*
X879200D01*
Y746600D01*
G01X905235Y750364D02*
X905360Y750114D01*
X905443Y749822D01*
Y749489D01*
X905318Y749114D01*
X905110Y748822D01*
X904860Y748614D01*
X904443Y748447D01*
X904068Y748405D01*
X903693Y748489D01*
X903443Y748614D01*
X903193Y748864D01*
X903026Y749155D01*
X902943Y749447D01*
Y749739D01*
X903026Y750030D01*
X903151Y750280D01*
X903318Y750489D01*
G01X903443Y751630D02*
X903151Y751880D01*
X902985Y752214D01*
X902943Y752589D01*
X902985Y752922D01*
X903193Y753255D01*
X903443Y753464D01*
X903693Y753505D01*
X903985Y753422D01*
X904193Y753130D01*
X904276Y752839D01*
Y752464D01*
G01Y752839D02*
X904401Y753089D01*
X904610Y753297D01*
X904860Y753380D01*
X905110Y753297D01*
X905318Y753089D01*
X905443Y752714D01*
X905401Y752339D01*
X905235Y751964D01*
G01X905026Y754855D02*
X905276Y755105D01*
X905401Y755397D01*
X905443Y755730D01*
X905360Y756147D01*
X905151Y756439D01*
X904901Y756522D01*
X904651Y756480D01*
X904443Y756314D01*
X904026Y755480D01*
X903735Y755105D01*
X903318Y754855D01*
X902943Y754772D01*
Y756522D01*
G01X905443Y758747D02*
X905360Y758414D01*
X905151Y758164D01*
X904901Y757997D01*
X904568Y757872D01*
X904193Y757830D01*
X903818Y757872D01*
X903485Y757997D01*
X903235Y758164D01*
X903026Y758414D01*
X902943Y758747D01*
X903026Y759080D01*
X903235Y759330D01*
X903485Y759497D01*
X903818Y759622D01*
X904193Y759664D01*
X904568Y759622D01*
X904901Y759497D01*
X905151Y759330D01*
X905360Y759080D01*
X905443Y758747D01*
G01X903318Y760930D02*
X903110Y761180D01*
X902985Y761472D01*
X902943Y761847D01*
X903026Y762222D01*
X903193Y762514D01*
X903485Y762722D01*
X903818Y762764D01*
X904151Y762680D01*
X904360Y762472D01*
X904526Y762180D01*
X904568Y761889D01*
X904526Y761597D01*
X904360Y761222D01*
X905443Y761347D01*
Y762472D01*
G01X904900Y770983D02*
X903108D01*
X902733Y771150D01*
X902483Y771483D01*
X902400Y771900D01*
X902483Y772317D01*
X902733Y772650D01*
X903108Y772817D01*
X904900D01*
G01X903442Y774208D02*
X903733Y774500D01*
X903900Y774750D01*
X903983Y775083D01*
X903900Y775375D01*
X903733Y775583D01*
X903483Y775750D01*
X903192Y775792D01*
X902942Y775750D01*
X902692Y775583D01*
X902483Y775333D01*
X902400Y775042D01*
X902483Y774708D01*
X902733Y774417D01*
X903108Y774250D01*
X903525Y774208D01*
X904067Y774292D01*
X904358Y774417D01*
X904650Y774625D01*
X904858Y774917D01*
X904900Y775208D01*
X904817Y775500D01*
X904608Y775708D01*
G01X902400Y778017D02*
X902942Y778100D01*
X903400Y778225D01*
X903817Y778392D01*
X904275Y778600D01*
X904900Y778933D01*
Y777267D01*
G01X900500Y768800D02*
Y782200D01*
G01X890500Y768800D02*
X900500D01*
G01X890500Y782200D02*
Y768800D01*
G01X900500Y782200D02*
X890500D01*
G01X908900Y771483D02*
X907108D01*
X906733Y771650D01*
X906483Y771983D01*
X906400Y772400D01*
X906483Y772817D01*
X906733Y773150D01*
X907108Y773317D01*
X908900D01*
G01X906400Y775417D02*
X906942Y775500D01*
X907400Y775625D01*
X907817Y775792D01*
X908275Y776000D01*
X908900Y776333D01*
Y774667D01*
G01X908483Y777808D02*
X908733Y778058D01*
X908858Y778350D01*
X908900Y778683D01*
X908817Y779100D01*
X908608Y779392D01*
X908358Y779475D01*
X908108Y779433D01*
X907900Y779267D01*
X907483Y778433D01*
X907192Y778058D01*
X906775Y777808D01*
X906400Y777725D01*
Y779475D01*
G01X884500Y768800D02*
Y782200D01*
G01X874500Y768800D02*
X884500D01*
G01X874500Y782200D02*
Y768800D01*
G01X884500Y782200D02*
X874500D01*
G01X902310Y780798D02*
X904810D01*
Y781839D01*
X904685Y782173D01*
X904518Y782381D01*
X904185Y782464D01*
X903852Y782381D01*
X903643Y782131D01*
X903518Y781839D01*
Y780798D01*
G01Y781839D02*
X902310Y782464D01*
G01X904393Y783939D02*
X904643Y784189D01*
X904768Y784481D01*
X904810Y784814D01*
X904727Y785231D01*
X904518Y785523D01*
X904268Y785606D01*
X904018Y785564D01*
X903810Y785398D01*
X903393Y784564D01*
X903102Y784189D01*
X902685Y783939D01*
X902310Y783856D01*
Y785606D01*
G01Y787748D02*
X902852Y787831D01*
X903310Y787956D01*
X903727Y788123D01*
X904185Y788331D01*
X904810Y788664D01*
Y786998D01*
G01X904393Y790139D02*
X904643Y790389D01*
X904768Y790681D01*
X904810Y791014D01*
X904727Y791431D01*
X904518Y791723D01*
X904268Y791806D01*
X904018Y791764D01*
X903810Y791598D01*
X903393Y790764D01*
X903102Y790389D01*
X902685Y790139D01*
X902310Y790056D01*
Y791806D01*
G01X885500Y786700D02*
X889500D01*
Y779300D01*
G01X880203Y767695D02*
X884203D01*
Y760295D01*
G01X906432Y782851D02*
X908932D01*
Y783892D01*
X908807Y784226D01*
X908640Y784434D01*
X908307Y784517D01*
X907974Y784434D01*
X907765Y784184D01*
X907640Y783892D01*
Y782851D01*
G01Y783892D02*
X906432Y784517D01*
G01X906932Y785867D02*
X906640Y786117D01*
X906474Y786451D01*
X906432Y786826D01*
X906474Y787159D01*
X906682Y787492D01*
X906932Y787701D01*
X907182Y787742D01*
X907474Y787659D01*
X907682Y787367D01*
X907765Y787076D01*
Y786701D01*
G01Y787076D02*
X907890Y787326D01*
X908099Y787534D01*
X908349Y787617D01*
X908599Y787534D01*
X908807Y787326D01*
X908932Y786951D01*
X908890Y786576D01*
X908724Y786201D01*
G01X908515Y789092D02*
X908765Y789342D01*
X908890Y789634D01*
X908932Y789967D01*
X908849Y790384D01*
X908640Y790676D01*
X908390Y790759D01*
X908140Y790717D01*
X907932Y790551D01*
X907515Y789717D01*
X907224Y789342D01*
X906807Y789092D01*
X906432Y789009D01*
Y790759D01*
G01X906932Y792067D02*
X906640Y792317D01*
X906474Y792651D01*
X906432Y793026D01*
X906474Y793359D01*
X906682Y793692D01*
X906932Y793901D01*
X907182Y793942D01*
X907474Y793859D01*
X907682Y793567D01*
X907765Y793276D01*
Y792901D01*
G01Y793276D02*
X907890Y793526D01*
X908099Y793734D01*
X908349Y793817D01*
X908599Y793734D01*
X908807Y793526D01*
X908932Y793151D01*
X908890Y792776D01*
X908724Y792401D01*
G01X906432Y796084D02*
X906474Y796376D01*
X906599Y796709D01*
X906807Y796917D01*
X907099Y797001D01*
X907390Y796917D01*
X907640Y796667D01*
X907765Y796292D01*
Y795876D01*
X907849Y795626D01*
X908057Y795417D01*
X908349Y795334D01*
X908640Y795459D01*
X908849Y795751D01*
X908932Y796084D01*
X908849Y796417D01*
X908640Y796709D01*
X908349Y796834D01*
X908057Y796751D01*
X907849Y796542D01*
X907765Y796292D01*
Y795876D01*
X907640Y795501D01*
X907390Y795251D01*
X907099Y795167D01*
X906807Y795251D01*
X906599Y795459D01*
X906474Y795792D01*
X906432Y796084D01*
G01X917474Y764178D02*
Y766678D01*
X916433D01*
X916099Y766553D01*
X915891Y766386D01*
X915808Y766053D01*
X915891Y765720D01*
X916141Y765511D01*
X916433Y765386D01*
X917474D01*
G01X916433D02*
X915808Y764178D01*
G01X914458Y764678D02*
X914208Y764386D01*
X913874Y764220D01*
X913499Y764178D01*
X913166Y764220D01*
X912833Y764428D01*
X912624Y764678D01*
X912583Y764928D01*
X912666Y765220D01*
X912958Y765428D01*
X913249Y765511D01*
X913624D01*
G01X913249D02*
X912999Y765636D01*
X912791Y765845D01*
X912708Y766095D01*
X912791Y766345D01*
X912999Y766553D01*
X913374Y766678D01*
X913749Y766636D01*
X914124Y766470D01*
G01X911233Y766261D02*
X910983Y766511D01*
X910691Y766636D01*
X910358Y766678D01*
X909941Y766595D01*
X909649Y766386D01*
X909566Y766136D01*
X909608Y765886D01*
X909774Y765678D01*
X910608Y765261D01*
X910983Y764970D01*
X911233Y764553D01*
X911316Y764178D01*
X909566D01*
G01X908258Y764678D02*
X908008Y764386D01*
X907674Y764220D01*
X907299Y764178D01*
X906966Y764220D01*
X906633Y764428D01*
X906424Y764678D01*
X906383Y764928D01*
X906466Y765220D01*
X906758Y765428D01*
X907049Y765511D01*
X907424D01*
G01X907049D02*
X906799Y765636D01*
X906591Y765845D01*
X906508Y766095D01*
X906591Y766345D01*
X906799Y766553D01*
X907174Y766678D01*
X907549Y766636D01*
X907924Y766470D01*
G01X904949Y764470D02*
X904658Y764261D01*
X904324Y764178D01*
X903991Y764261D01*
X903699Y764511D01*
X903491Y764886D01*
X903408Y765261D01*
Y765720D01*
X903491Y766095D01*
X903699Y766428D01*
X903949Y766595D01*
X904241Y766678D01*
X904574Y766595D01*
X904824Y766428D01*
X904991Y766178D01*
X905074Y765845D01*
X904991Y765553D01*
X904783Y765261D01*
X904533Y765095D01*
X904241Y765053D01*
X903908Y765136D01*
X903658Y765345D01*
X903408Y765720D01*
G01X894600Y763400D02*
Y767400D01*
X902000D01*
G01X876600Y790700D02*
X880600D01*
Y783300D01*
G01X894178Y791131D02*
X898178D01*
Y783731D01*
G01X890178Y791131D02*
X894178D01*
Y783731D01*
G01X888533Y807961D02*
Y810461D01*
X887492D01*
X887158Y810336D01*
X886950Y810169D01*
X886867Y809836D01*
X886950Y809503D01*
X887200Y809294D01*
X887492Y809169D01*
X888533D01*
G01X887492D02*
X886867Y807961D01*
G01X885517Y808461D02*
X885267Y808169D01*
X884933Y808003D01*
X884558Y807961D01*
X884225Y808003D01*
X883892Y808211D01*
X883683Y808461D01*
X883642Y808711D01*
X883725Y809003D01*
X884017Y809211D01*
X884308Y809294D01*
X884683D01*
G01X884308D02*
X884058Y809419D01*
X883850Y809628D01*
X883767Y809878D01*
X883850Y810128D01*
X884058Y810336D01*
X884433Y810461D01*
X884808Y810419D01*
X885183Y810253D01*
G01X882292Y810044D02*
X882042Y810294D01*
X881750Y810419D01*
X881417Y810461D01*
X881000Y810378D01*
X880708Y810169D01*
X880625Y809919D01*
X880667Y809669D01*
X880833Y809461D01*
X881667Y809044D01*
X882042Y808753D01*
X882292Y808336D01*
X882375Y807961D01*
X880625D01*
G01X879192Y810044D02*
X878942Y810294D01*
X878650Y810419D01*
X878317Y810461D01*
X877900Y810378D01*
X877608Y810169D01*
X877525Y809919D01*
X877567Y809669D01*
X877733Y809461D01*
X878567Y809044D01*
X878942Y808753D01*
X879192Y808336D01*
X879275Y807961D01*
X877525D01*
G01X876217Y808336D02*
X875967Y808128D01*
X875675Y808003D01*
X875300Y807961D01*
X874925Y808044D01*
X874633Y808211D01*
X874425Y808503D01*
X874383Y808836D01*
X874467Y809169D01*
X874675Y809378D01*
X874967Y809544D01*
X875258Y809586D01*
X875550Y809544D01*
X875925Y809378D01*
X875800Y810461D01*
X874675D01*
G01X883910Y794910D02*
Y790910D01*
X876510D01*
G01X878710Y812908D02*
X881210D01*
Y813949D01*
X881085Y814283D01*
X880918Y814491D01*
X880585Y814574D01*
X880252Y814491D01*
X880043Y814241D01*
X879918Y813949D01*
Y812908D01*
G01Y813949D02*
X878710Y814574D01*
G01Y817341D02*
X881210D01*
X879418Y815799D01*
Y817883D01*
G01X878710Y819941D02*
X881210D01*
X880710Y819441D01*
G01X878710D02*
Y820441D01*
G01Y823541D02*
X881210D01*
X879418Y821999D01*
Y824083D01*
G01X878710Y826641D02*
X881210D01*
X879418Y825099D01*
Y827183D01*
G01X884049Y798260D02*
X880049D01*
Y805660D01*
G01X874610Y812908D02*
X877110D01*
Y813949D01*
X876985Y814283D01*
X876818Y814491D01*
X876485Y814574D01*
X876152Y814491D01*
X875943Y814241D01*
X875818Y813949D01*
Y812908D01*
G01Y813949D02*
X874610Y814574D01*
G01Y817341D02*
X877110D01*
X875318Y815799D01*
Y817883D01*
G01X874610Y819941D02*
X877110D01*
X876610Y819441D01*
G01X874610D02*
Y820441D01*
G01Y823541D02*
X877110D01*
X875318Y821999D01*
Y824083D01*
G01X876693Y825349D02*
X876943Y825599D01*
X877068Y825891D01*
X877110Y826224D01*
X877027Y826641D01*
X876818Y826933D01*
X876568Y827016D01*
X876318Y826974D01*
X876110Y826808D01*
X875693Y825974D01*
X875402Y825599D01*
X874985Y825349D01*
X874610Y825266D01*
Y827016D01*
G01X879949Y798260D02*
X875949D01*
Y805660D01*
G01X882937Y812956D02*
X885437D01*
Y813997D01*
X885312Y814331D01*
X885145Y814539D01*
X884812Y814622D01*
X884479Y814539D01*
X884270Y814289D01*
X884145Y813997D01*
Y812956D01*
G01Y813997D02*
X882937Y814622D01*
G01Y817389D02*
X885437D01*
X883645Y815847D01*
Y817931D01*
G01X882937Y819989D02*
X885437D01*
X884937Y819489D01*
G01X882937D02*
Y820489D01*
G01X883437Y822172D02*
X883145Y822422D01*
X882979Y822756D01*
X882937Y823131D01*
X882979Y823464D01*
X883187Y823797D01*
X883437Y824006D01*
X883687Y824047D01*
X883979Y823964D01*
X884187Y823672D01*
X884270Y823381D01*
Y823006D01*
G01Y823381D02*
X884395Y823631D01*
X884604Y823839D01*
X884854Y823922D01*
X885104Y823839D01*
X885312Y823631D01*
X885437Y823256D01*
X885395Y822881D01*
X885229Y822506D01*
G01X882937Y826189D02*
X882979Y826481D01*
X883104Y826814D01*
X883312Y827022D01*
X883604Y827106D01*
X883895Y827022D01*
X884145Y826772D01*
X884270Y826397D01*
Y825981D01*
X884354Y825731D01*
X884562Y825522D01*
X884854Y825439D01*
X885145Y825564D01*
X885354Y825856D01*
X885437Y826189D01*
X885354Y826522D01*
X885145Y826814D01*
X884854Y826939D01*
X884562Y826856D01*
X884354Y826647D01*
X884270Y826397D01*
Y825981D01*
X884145Y825606D01*
X883895Y825356D01*
X883604Y825272D01*
X883312Y825356D01*
X883104Y825564D01*
X882979Y825897D01*
X882937Y826189D01*
G01X888276Y798308D02*
X884276D01*
Y805708D01*
G01X892567Y805601D02*
X895067D01*
Y806642D01*
X894942Y806976D01*
X894775Y807184D01*
X894442Y807267D01*
X894109Y807184D01*
X893900Y806934D01*
X893775Y806642D01*
Y805601D01*
G01Y806642D02*
X892567Y807267D01*
G01Y810034D02*
X895067D01*
X893275Y808492D01*
Y810576D01*
G01X892567Y812634D02*
X895067D01*
X894567Y812134D01*
G01X892567D02*
Y813134D01*
G01X893067Y814817D02*
X892775Y815067D01*
X892609Y815401D01*
X892567Y815776D01*
X892609Y816109D01*
X892817Y816442D01*
X893067Y816651D01*
X893317Y816692D01*
X893609Y816609D01*
X893817Y816317D01*
X893900Y816026D01*
Y815651D01*
G01Y816026D02*
X894025Y816276D01*
X894234Y816484D01*
X894484Y816567D01*
X894734Y816484D01*
X894942Y816276D01*
X895067Y815901D01*
X895025Y815526D01*
X894859Y815151D01*
G01X893609Y818042D02*
X893900Y818334D01*
X894067Y818584D01*
X894150Y818917D01*
X894067Y819209D01*
X893900Y819417D01*
X893650Y819584D01*
X893359Y819626D01*
X893109Y819584D01*
X892859Y819417D01*
X892650Y819167D01*
X892567Y818876D01*
X892650Y818542D01*
X892900Y818251D01*
X893275Y818084D01*
X893692Y818042D01*
X894234Y818126D01*
X894525Y818251D01*
X894817Y818459D01*
X895025Y818751D01*
X895067Y819042D01*
X894984Y819334D01*
X894775Y819542D01*
G01X896406Y795698D02*
X892406D01*
Y803098D01*
G01X896567Y805601D02*
X899067D01*
Y806642D01*
X898942Y806976D01*
X898775Y807184D01*
X898442Y807267D01*
X898109Y807184D01*
X897900Y806934D01*
X897775Y806642D01*
Y805601D01*
G01Y806642D02*
X896567Y807267D01*
G01Y810034D02*
X899067D01*
X897275Y808492D01*
Y810576D01*
G01X896567Y812634D02*
X899067D01*
X898567Y812134D01*
G01X896567D02*
Y813134D01*
G01X897067Y814817D02*
X896775Y815067D01*
X896609Y815401D01*
X896567Y815776D01*
X896609Y816109D01*
X896817Y816442D01*
X897067Y816651D01*
X897317Y816692D01*
X897609Y816609D01*
X897817Y816317D01*
X897900Y816026D01*
Y815651D01*
G01Y816026D02*
X898025Y816276D01*
X898234Y816484D01*
X898484Y816567D01*
X898734Y816484D01*
X898942Y816276D01*
X899067Y815901D01*
X899025Y815526D01*
X898859Y815151D01*
G01X896567Y819334D02*
X899067D01*
X897275Y817792D01*
Y819876D01*
G01X900406Y795698D02*
X896406D01*
Y803098D01*
G01X943500Y59300D02*
X941000D01*
G01X943500Y58342D02*
Y60258D01*
G01X941000Y61567D02*
X943500D01*
Y62567D01*
X943375Y62900D01*
X943083Y63150D01*
X942750Y63233D01*
X942417Y63150D01*
X942167Y62942D01*
X942042Y62567D01*
Y61567D01*
G01X941000Y65500D02*
X943500D01*
X943000Y65000D01*
G01X941000D02*
Y66000D01*
G01X941292Y67892D02*
X941083Y68183D01*
X941000Y68517D01*
X941083Y68850D01*
X941333Y69142D01*
X941708Y69350D01*
X942083Y69433D01*
X942542D01*
X942917Y69350D01*
X943250Y69142D01*
X943417Y68892D01*
X943500Y68600D01*
X943417Y68267D01*
X943250Y68017D01*
X943000Y67850D01*
X942667Y67767D01*
X942375Y67850D01*
X942083Y68058D01*
X941917Y68308D01*
X941875Y68600D01*
X941958Y68933D01*
X942167Y69183D01*
X942542Y69433D01*
G01X941500Y70783D02*
X941208Y71033D01*
X941042Y71367D01*
X941000Y71742D01*
X941042Y72075D01*
X941250Y72408D01*
X941500Y72617D01*
X941750Y72658D01*
X942042Y72575D01*
X942250Y72283D01*
X942333Y71992D01*
Y71617D01*
G01Y71992D02*
X942458Y72242D01*
X942667Y72450D01*
X942917Y72533D01*
X943167Y72450D01*
X943375Y72242D01*
X943500Y71867D01*
X943458Y71492D01*
X943292Y71117D01*
G01X946823Y104927D02*
Y102427D01*
G01X947781Y104927D02*
X945865D01*
G01X944556Y102427D02*
Y104927D01*
X943556D01*
X943223Y104802D01*
X942973Y104510D01*
X942890Y104177D01*
X942973Y103844D01*
X943181Y103594D01*
X943556Y103469D01*
X944556D01*
G01X941415Y104510D02*
X941165Y104760D01*
X940873Y104885D01*
X940540Y104927D01*
X940123Y104844D01*
X939831Y104635D01*
X939748Y104385D01*
X939790Y104135D01*
X939956Y103927D01*
X940790Y103510D01*
X941165Y103219D01*
X941415Y102802D01*
X941498Y102427D01*
X939748D01*
G01X937523D02*
Y104927D01*
X938023Y104427D01*
G01Y102427D02*
X937023D01*
G01X934423D02*
Y104927D01*
X934923Y104427D01*
G01Y102427D02*
X933923D01*
G01X927484Y107256D02*
Y104756D01*
G01X928442Y107256D02*
X926526D01*
G01X925217Y104756D02*
Y107256D01*
X924217D01*
X923884Y107131D01*
X923634Y106839D01*
X923551Y106506D01*
X923634Y106173D01*
X923842Y105923D01*
X924217Y105798D01*
X925217D01*
G01X922076Y106839D02*
X921826Y107089D01*
X921534Y107214D01*
X921201Y107256D01*
X920784Y107173D01*
X920492Y106964D01*
X920409Y106714D01*
X920451Y106464D01*
X920617Y106256D01*
X921451Y105839D01*
X921826Y105548D01*
X922076Y105131D01*
X922159Y104756D01*
X920409D01*
G01X918184Y107256D02*
X918517Y107173D01*
X918767Y106964D01*
X918934Y106714D01*
X919059Y106381D01*
X919101Y106006D01*
X919059Y105631D01*
X918934Y105298D01*
X918767Y105048D01*
X918517Y104839D01*
X918184Y104756D01*
X917851Y104839D01*
X917601Y105048D01*
X917434Y105298D01*
X917309Y105631D01*
X917267Y106006D01*
X917309Y106381D01*
X917434Y106714D01*
X917601Y106964D01*
X917851Y107173D01*
X918184Y107256D01*
G01X915167Y104756D02*
X915084Y105298D01*
X914959Y105756D01*
X914792Y106173D01*
X914584Y106631D01*
X914251Y107256D01*
X915917D01*
G01X946746Y111217D02*
Y108717D01*
G01X947704Y111217D02*
X945788D01*
G01X944479Y108717D02*
Y111217D01*
X943479D01*
X943146Y111092D01*
X942896Y110800D01*
X942813Y110467D01*
X942896Y110134D01*
X943104Y109884D01*
X943479Y109759D01*
X944479D01*
G01X940546Y108717D02*
Y111217D01*
X941046Y110717D01*
G01Y108717D02*
X940046D01*
G01X938154Y109009D02*
X937863Y108800D01*
X937529Y108717D01*
X937196Y108800D01*
X936904Y109050D01*
X936696Y109425D01*
X936613Y109800D01*
Y110259D01*
X936696Y110634D01*
X936904Y110967D01*
X937154Y111134D01*
X937446Y111217D01*
X937779Y111134D01*
X938029Y110967D01*
X938196Y110717D01*
X938279Y110384D01*
X938196Y110092D01*
X937988Y109800D01*
X937738Y109634D01*
X937446Y109592D01*
X937113Y109675D01*
X936863Y109884D01*
X936613Y110259D01*
G01X935138Y109759D02*
X934846Y110050D01*
X934596Y110217D01*
X934263Y110300D01*
X933971Y110217D01*
X933763Y110050D01*
X933596Y109800D01*
X933554Y109509D01*
X933596Y109259D01*
X933763Y109009D01*
X934013Y108800D01*
X934304Y108717D01*
X934638Y108800D01*
X934929Y109050D01*
X935096Y109425D01*
X935138Y109842D01*
X935054Y110384D01*
X934929Y110675D01*
X934721Y110967D01*
X934429Y111175D01*
X934138Y111217D01*
X933846Y111134D01*
X933638Y110925D01*
G01X933234Y100843D02*
Y98343D01*
G01X934192Y100843D02*
X932276D01*
G01X930967Y98343D02*
Y100843D01*
X929967D01*
X929634Y100718D01*
X929384Y100426D01*
X929301Y100093D01*
X929384Y99760D01*
X929592Y99510D01*
X929967Y99385D01*
X930967D01*
G01X927034Y98343D02*
Y100843D01*
X927534Y100343D01*
G01Y98343D02*
X926534D01*
G01X924642Y98635D02*
X924351Y98426D01*
X924017Y98343D01*
X923684Y98426D01*
X923392Y98676D01*
X923184Y99051D01*
X923101Y99426D01*
Y99885D01*
X923184Y100260D01*
X923392Y100593D01*
X923642Y100760D01*
X923934Y100843D01*
X924267Y100760D01*
X924517Y100593D01*
X924684Y100343D01*
X924767Y100010D01*
X924684Y99718D01*
X924476Y99426D01*
X924226Y99260D01*
X923934Y99218D01*
X923601Y99301D01*
X923351Y99510D01*
X923101Y99885D01*
G01X920334Y98343D02*
Y100843D01*
X921876Y99051D01*
X919792D01*
G01X909000Y84200D02*
X913000D01*
Y76800D01*
G01X913500Y84200D02*
X917500D01*
Y76800D01*
G01X918000Y84200D02*
X922000D01*
Y76800D01*
G01X931500Y84200D02*
X935500D01*
Y76800D01*
G01X927000Y84200D02*
X931000D01*
Y76800D01*
G01X922500Y84200D02*
X926500D01*
Y76800D01*
G01X936000Y84200D02*
X940000D01*
Y76800D01*
G01X940500Y84200D02*
X944500D01*
Y76800D01*
G01X940500Y95200D02*
X944500D01*
Y87800D01*
G01X913000D02*
X909000D01*
Y95200D01*
G01X917500Y87800D02*
X913500D01*
Y95200D01*
G01X922000Y87800D02*
X918000D01*
Y95200D01*
G01X935500Y87800D02*
X931500D01*
Y95200D01*
G01X931000Y87800D02*
X927000D01*
Y95200D01*
G01X926500Y87800D02*
X922500D01*
Y95200D01*
G01X940000Y87800D02*
X936000D01*
Y95200D01*
G01X927066Y134947D02*
X929566D01*
Y135988D01*
X929441Y136322D01*
X929274Y136530D01*
X928941Y136613D01*
X928608Y136530D01*
X928399Y136280D01*
X928274Y135988D01*
Y134947D01*
G01Y135988D02*
X927066Y136613D01*
G01X927358Y138172D02*
X927149Y138463D01*
X927066Y138797D01*
X927149Y139130D01*
X927399Y139422D01*
X927774Y139630D01*
X928149Y139713D01*
X928608D01*
X928983Y139630D01*
X929316Y139422D01*
X929483Y139172D01*
X929566Y138880D01*
X929483Y138547D01*
X929316Y138297D01*
X929066Y138130D01*
X928733Y138047D01*
X928441Y138130D01*
X928149Y138338D01*
X927983Y138588D01*
X927941Y138880D01*
X928024Y139213D01*
X928233Y139463D01*
X928608Y139713D01*
G01X934000Y136917D02*
X936500D01*
Y137958D01*
X936375Y138292D01*
X936208Y138500D01*
X935875Y138583D01*
X935542Y138500D01*
X935333Y138250D01*
X935208Y137958D01*
Y136917D01*
G01Y137958D02*
X934000Y138583D01*
G01Y140850D02*
X934042Y141142D01*
X934167Y141475D01*
X934375Y141683D01*
X934667Y141767D01*
X934958Y141683D01*
X935208Y141433D01*
X935333Y141058D01*
Y140642D01*
X935417Y140392D01*
X935625Y140183D01*
X935917Y140100D01*
X936208Y140225D01*
X936417Y140517D01*
X936500Y140850D01*
X936417Y141183D01*
X936208Y141475D01*
X935917Y141600D01*
X935625Y141517D01*
X935417Y141308D01*
X935333Y141058D01*
Y140642D01*
X935208Y140267D01*
X934958Y140017D01*
X934667Y139933D01*
X934375Y140017D01*
X934167Y140225D01*
X934042Y140558D01*
X934000Y140850D01*
G01X930592Y138132D02*
X933092D01*
Y139173D01*
X932967Y139507D01*
X932800Y139715D01*
X932467Y139798D01*
X932134Y139715D01*
X931925Y139465D01*
X931800Y139173D01*
Y138132D01*
G01Y139173D02*
X930592Y139798D01*
G01Y141982D02*
X931134Y142065D01*
X931592Y142190D01*
X932009Y142357D01*
X932467Y142565D01*
X933092Y142898D01*
Y141232D01*
G01X929212Y131317D02*
X929462Y131442D01*
X929754Y131525D01*
X930087D01*
X930462Y131400D01*
X930754Y131192D01*
X930962Y130942D01*
X931129Y130525D01*
X931171Y130150D01*
X931087Y129775D01*
X930962Y129525D01*
X930712Y129275D01*
X930421Y129108D01*
X930129Y129025D01*
X929837D01*
X929546Y129108D01*
X929296Y129233D01*
X929087Y129400D01*
G01X926529Y129025D02*
Y131525D01*
X928071Y129733D01*
X925987D01*
G01X924721Y130067D02*
X924429Y130358D01*
X924179Y130525D01*
X923846Y130608D01*
X923554Y130525D01*
X923346Y130358D01*
X923179Y130108D01*
X923137Y129817D01*
X923179Y129567D01*
X923346Y129317D01*
X923596Y129108D01*
X923887Y129025D01*
X924221Y129108D01*
X924512Y129358D01*
X924679Y129733D01*
X924721Y130150D01*
X924637Y130692D01*
X924512Y130983D01*
X924304Y131275D01*
X924012Y131483D01*
X923721Y131525D01*
X923429Y131442D01*
X923221Y131233D01*
G01X920912Y129025D02*
X920829Y129567D01*
X920704Y130025D01*
X920537Y130442D01*
X920329Y130900D01*
X919996Y131525D01*
X921662D01*
G01X943744Y135019D02*
X943994Y135144D01*
X944286Y135227D01*
X944619D01*
X944994Y135102D01*
X945286Y134894D01*
X945494Y134644D01*
X945661Y134227D01*
X945703Y133852D01*
X945619Y133477D01*
X945494Y133227D01*
X945244Y132977D01*
X944953Y132810D01*
X944661Y132727D01*
X944369D01*
X944078Y132810D01*
X943828Y132935D01*
X943619Y133102D01*
G01X941061Y132727D02*
Y135227D01*
X942603Y133435D01*
X940519D01*
G01X939253Y133769D02*
X938961Y134060D01*
X938711Y134227D01*
X938378Y134310D01*
X938086Y134227D01*
X937878Y134060D01*
X937711Y133810D01*
X937669Y133519D01*
X937711Y133269D01*
X937878Y133019D01*
X938128Y132810D01*
X938419Y132727D01*
X938753Y132810D01*
X939044Y133060D01*
X939211Y133435D01*
X939253Y133852D01*
X939169Y134394D01*
X939044Y134685D01*
X938836Y134977D01*
X938544Y135185D01*
X938253Y135227D01*
X937961Y135144D01*
X937753Y134935D01*
G01X936153Y133769D02*
X935861Y134060D01*
X935611Y134227D01*
X935278Y134310D01*
X934986Y134227D01*
X934778Y134060D01*
X934611Y133810D01*
X934569Y133519D01*
X934611Y133269D01*
X934778Y133019D01*
X935028Y132810D01*
X935319Y132727D01*
X935653Y132810D01*
X935944Y133060D01*
X936111Y133435D01*
X936153Y133852D01*
X936069Y134394D01*
X935944Y134685D01*
X935736Y134977D01*
X935444Y135185D01*
X935153Y135227D01*
X934861Y135144D01*
X934653Y134935D01*
G01X925798Y138911D02*
X925923Y138661D01*
X926006Y138369D01*
Y138036D01*
X925881Y137661D01*
X925673Y137369D01*
X925423Y137161D01*
X925006Y136994D01*
X924631Y136952D01*
X924256Y137036D01*
X924006Y137161D01*
X923756Y137411D01*
X923589Y137702D01*
X923506Y137994D01*
Y138286D01*
X923589Y138577D01*
X923714Y138827D01*
X923881Y139036D01*
G01X923506Y141594D02*
X926006D01*
X924214Y140052D01*
Y142136D01*
G01X923506Y144194D02*
X923548Y144486D01*
X923673Y144819D01*
X923881Y145027D01*
X924173Y145111D01*
X924464Y145027D01*
X924714Y144777D01*
X924839Y144402D01*
Y143986D01*
X924923Y143736D01*
X925131Y143527D01*
X925423Y143444D01*
X925714Y143569D01*
X925923Y143861D01*
X926006Y144194D01*
X925923Y144527D01*
X925714Y144819D01*
X925423Y144944D01*
X925131Y144861D01*
X924923Y144652D01*
X924839Y144402D01*
Y143986D01*
X924714Y143611D01*
X924464Y143361D01*
X924173Y143277D01*
X923881Y143361D01*
X923673Y143569D01*
X923548Y143902D01*
X923506Y144194D01*
G01Y147294D02*
X926006D01*
X925506Y146794D01*
G01X923506D02*
Y147794D01*
G01X912703Y117576D02*
X912828Y117326D01*
X912911Y117034D01*
Y116701D01*
X912786Y116326D01*
X912578Y116034D01*
X912328Y115826D01*
X911911Y115659D01*
X911536Y115617D01*
X911161Y115701D01*
X910911Y115826D01*
X910661Y116076D01*
X910494Y116367D01*
X910411Y116659D01*
Y116951D01*
X910494Y117242D01*
X910619Y117492D01*
X910786Y117701D01*
G01X910411Y120259D02*
X912911D01*
X911119Y118717D01*
Y120801D01*
G01X910411Y122776D02*
X910953Y122859D01*
X911411Y122984D01*
X911828Y123151D01*
X912286Y123359D01*
X912911Y123692D01*
Y122026D01*
G01X910411Y125959D02*
X910453Y126251D01*
X910578Y126584D01*
X910786Y126792D01*
X911078Y126876D01*
X911369Y126792D01*
X911619Y126542D01*
X911744Y126167D01*
Y125751D01*
X911828Y125501D01*
X912036Y125292D01*
X912328Y125209D01*
X912619Y125334D01*
X912828Y125626D01*
X912911Y125959D01*
X912828Y126292D01*
X912619Y126584D01*
X912328Y126709D01*
X912036Y126626D01*
X911828Y126417D01*
X911744Y126167D01*
Y125751D01*
X911619Y125376D01*
X911369Y125126D01*
X911078Y125042D01*
X910786Y125126D01*
X910578Y125334D01*
X910453Y125667D01*
X910411Y125959D01*
G01X920669Y116903D02*
X920794Y116653D01*
X920877Y116361D01*
Y116028D01*
X920752Y115653D01*
X920544Y115361D01*
X920294Y115153D01*
X919877Y114986D01*
X919502Y114944D01*
X919127Y115028D01*
X918877Y115153D01*
X918627Y115403D01*
X918460Y115694D01*
X918377Y115986D01*
Y116278D01*
X918460Y116569D01*
X918585Y116819D01*
X918752Y117028D01*
G01X918377Y119586D02*
X920877D01*
X919085Y118044D01*
Y120128D01*
G01X918377Y122103D02*
X918919Y122186D01*
X919377Y122311D01*
X919794Y122478D01*
X920252Y122686D01*
X920877Y123019D01*
Y121353D01*
G01X919419Y124494D02*
X919710Y124786D01*
X919877Y125036D01*
X919960Y125369D01*
X919877Y125661D01*
X919710Y125869D01*
X919460Y126036D01*
X919169Y126078D01*
X918919Y126036D01*
X918669Y125869D01*
X918460Y125619D01*
X918377Y125328D01*
X918460Y124994D01*
X918710Y124703D01*
X919085Y124536D01*
X919502Y124494D01*
X920044Y124578D01*
X920335Y124703D01*
X920627Y124911D01*
X920835Y125203D01*
X920877Y125494D01*
X920794Y125786D01*
X920585Y125994D01*
G01X928512Y117160D02*
X928637Y116910D01*
X928720Y116618D01*
Y116285D01*
X928595Y115910D01*
X928387Y115618D01*
X928137Y115410D01*
X927720Y115243D01*
X927345Y115201D01*
X926970Y115285D01*
X926720Y115410D01*
X926470Y115660D01*
X926303Y115951D01*
X926220Y116243D01*
Y116535D01*
X926303Y116826D01*
X926428Y117076D01*
X926595Y117285D01*
G01X926220Y119843D02*
X928720D01*
X926928Y118301D01*
Y120385D01*
G01X926220Y122360D02*
X926762Y122443D01*
X927220Y122568D01*
X927637Y122735D01*
X928095Y122943D01*
X928720Y123276D01*
Y121610D01*
G01X926595Y124626D02*
X926387Y124876D01*
X926262Y125168D01*
X926220Y125543D01*
X926303Y125918D01*
X926470Y126210D01*
X926762Y126418D01*
X927095Y126460D01*
X927428Y126376D01*
X927637Y126168D01*
X927803Y125876D01*
X927845Y125585D01*
X927803Y125293D01*
X927637Y124918D01*
X928720Y125043D01*
Y126168D01*
G01X951700Y119500D02*
Y117000D01*
G01X952658Y119500D02*
X950742D01*
G01X949433Y117000D02*
Y119500D01*
X948433D01*
X948100Y119375D01*
X947850Y119083D01*
X947767Y118750D01*
X947850Y118417D01*
X948058Y118167D01*
X948433Y118042D01*
X949433D01*
G01X946292Y119083D02*
X946042Y119333D01*
X945750Y119458D01*
X945417Y119500D01*
X945000Y119417D01*
X944708Y119208D01*
X944625Y118958D01*
X944667Y118708D01*
X944833Y118500D01*
X945667Y118083D01*
X946042Y117792D01*
X946292Y117375D01*
X946375Y117000D01*
X944625D01*
G01X943192Y118042D02*
X942900Y118333D01*
X942650Y118500D01*
X942317Y118583D01*
X942025Y118500D01*
X941817Y118333D01*
X941650Y118083D01*
X941608Y117792D01*
X941650Y117542D01*
X941817Y117292D01*
X942067Y117083D01*
X942358Y117000D01*
X942692Y117083D01*
X942983Y117333D01*
X943150Y117708D01*
X943192Y118125D01*
X943108Y118667D01*
X942983Y118958D01*
X942775Y119250D01*
X942483Y119458D01*
X942192Y119500D01*
X941900Y119417D01*
X941692Y119208D01*
G01X940217Y117500D02*
X939967Y117208D01*
X939633Y117042D01*
X939258Y117000D01*
X938925Y117042D01*
X938592Y117250D01*
X938383Y117500D01*
X938342Y117750D01*
X938425Y118042D01*
X938717Y118250D01*
X939008Y118333D01*
X939383D01*
G01X939008D02*
X938758Y118458D01*
X938550Y118667D01*
X938467Y118917D01*
X938550Y119167D01*
X938758Y119375D01*
X939133Y119500D01*
X939508Y119458D01*
X939883Y119292D01*
G01X954043Y127597D02*
Y125097D01*
G01X955001Y127597D02*
X953085D01*
G01X951776Y125097D02*
Y127597D01*
X950776D01*
X950443Y127472D01*
X950193Y127180D01*
X950110Y126847D01*
X950193Y126514D01*
X950401Y126264D01*
X950776Y126139D01*
X951776D01*
G01X948635Y127180D02*
X948385Y127430D01*
X948093Y127555D01*
X947760Y127597D01*
X947343Y127514D01*
X947051Y127305D01*
X946968Y127055D01*
X947010Y126805D01*
X947176Y126597D01*
X948010Y126180D01*
X948385Y125889D01*
X948635Y125472D01*
X948718Y125097D01*
X946968D01*
G01X945535Y127180D02*
X945285Y127430D01*
X944993Y127555D01*
X944660Y127597D01*
X944243Y127514D01*
X943951Y127305D01*
X943868Y127055D01*
X943910Y126805D01*
X944076Y126597D01*
X944910Y126180D01*
X945285Y125889D01*
X945535Y125472D01*
X945618Y125097D01*
X943868D01*
G01X942435Y127180D02*
X942185Y127430D01*
X941893Y127555D01*
X941560Y127597D01*
X941143Y127514D01*
X940851Y127305D01*
X940768Y127055D01*
X940810Y126805D01*
X940976Y126597D01*
X941810Y126180D01*
X942185Y125889D01*
X942435Y125472D01*
X942518Y125097D01*
X940768D01*
G01X928546Y111326D02*
Y108826D01*
G01X929504Y111326D02*
X927588D01*
G01X926279Y108826D02*
Y111326D01*
X925279D01*
X924946Y111201D01*
X924696Y110909D01*
X924613Y110576D01*
X924696Y110243D01*
X924904Y109993D01*
X925279Y109868D01*
X926279D01*
G01X922346Y108826D02*
Y111326D01*
X922846Y110826D01*
G01Y108826D02*
X921846D01*
G01X920038Y110909D02*
X919788Y111159D01*
X919496Y111284D01*
X919163Y111326D01*
X918746Y111243D01*
X918454Y111034D01*
X918371Y110784D01*
X918413Y110534D01*
X918579Y110326D01*
X919413Y109909D01*
X919788Y109618D01*
X920038Y109201D01*
X920121Y108826D01*
X918371D01*
G01X916146D02*
Y111326D01*
X916646Y110826D01*
G01Y108826D02*
X915646D01*
G01X940433Y155292D02*
X940683Y155417D01*
X940975Y155500D01*
X941308D01*
X941683Y155375D01*
X941975Y155167D01*
X942183Y154917D01*
X942350Y154500D01*
X942392Y154125D01*
X942308Y153750D01*
X942183Y153500D01*
X941933Y153250D01*
X941642Y153083D01*
X941350Y153000D01*
X941058D01*
X940767Y153083D01*
X940517Y153208D01*
X940308Y153375D01*
G01X939167D02*
X938917Y153167D01*
X938625Y153042D01*
X938250Y153000D01*
X937875Y153083D01*
X937583Y153250D01*
X937375Y153542D01*
X937333Y153875D01*
X937417Y154208D01*
X937625Y154417D01*
X937917Y154583D01*
X938208Y154625D01*
X938500Y154583D01*
X938875Y154417D01*
X938750Y155500D01*
X937625D01*
G01X934650Y153000D02*
Y155500D01*
X936192Y153708D01*
X934108D01*
G01X932133Y153000D02*
X932050Y153542D01*
X931925Y154000D01*
X931758Y154417D01*
X931550Y154875D01*
X931217Y155500D01*
X932883D01*
G01X920292Y176767D02*
X920417Y176517D01*
X920500Y176225D01*
Y175892D01*
X920375Y175517D01*
X920167Y175225D01*
X919917Y175017D01*
X919500Y174850D01*
X919125Y174808D01*
X918750Y174892D01*
X918500Y175017D01*
X918250Y175267D01*
X918083Y175558D01*
X918000Y175850D01*
Y176142D01*
X918083Y176433D01*
X918208Y176683D01*
X918375Y176892D01*
G01Y178033D02*
X918167Y178283D01*
X918042Y178575D01*
X918000Y178950D01*
X918083Y179325D01*
X918250Y179617D01*
X918542Y179825D01*
X918875Y179867D01*
X919208Y179783D01*
X919417Y179575D01*
X919583Y179283D01*
X919625Y178992D01*
X919583Y178700D01*
X919417Y178325D01*
X920500Y178450D01*
Y179575D01*
G01X918000Y182550D02*
X920500D01*
X918708Y181008D01*
Y183092D01*
G01X919042Y184358D02*
X919333Y184650D01*
X919500Y184900D01*
X919583Y185233D01*
X919500Y185525D01*
X919333Y185733D01*
X919083Y185900D01*
X918792Y185942D01*
X918542Y185900D01*
X918292Y185733D01*
X918083Y185483D01*
X918000Y185192D01*
X918083Y184858D01*
X918333Y184567D01*
X918708Y184400D01*
X919125Y184358D01*
X919667Y184442D01*
X919958Y184567D01*
X920250Y184775D01*
X920458Y185067D01*
X920500Y185358D01*
X920417Y185650D01*
X920208Y185858D01*
G01X939533Y151492D02*
X939783Y151617D01*
X940075Y151700D01*
X940408D01*
X940783Y151575D01*
X941075Y151367D01*
X941283Y151117D01*
X941450Y150700D01*
X941492Y150325D01*
X941408Y149950D01*
X941283Y149700D01*
X941033Y149450D01*
X940742Y149283D01*
X940450Y149200D01*
X940158D01*
X939867Y149283D01*
X939617Y149408D01*
X939408Y149575D01*
G01X936850Y149200D02*
Y151700D01*
X938392Y149908D01*
X936308D01*
G01X934250Y149200D02*
X933958Y149242D01*
X933625Y149367D01*
X933417Y149575D01*
X933333Y149867D01*
X933417Y150158D01*
X933667Y150408D01*
X934042Y150533D01*
X934458D01*
X934708Y150617D01*
X934917Y150825D01*
X935000Y151117D01*
X934875Y151408D01*
X934583Y151617D01*
X934250Y151700D01*
X933917Y151617D01*
X933625Y151408D01*
X933500Y151117D01*
X933583Y150825D01*
X933792Y150617D01*
X934042Y150533D01*
X934458D01*
X934833Y150408D01*
X935083Y150158D01*
X935167Y149867D01*
X935083Y149575D01*
X934875Y149367D01*
X934542Y149242D01*
X934250Y149200D01*
G01X931942Y151283D02*
X931692Y151533D01*
X931400Y151658D01*
X931067Y151700D01*
X930650Y151617D01*
X930358Y151408D01*
X930275Y151158D01*
X930317Y150908D01*
X930483Y150700D01*
X931317Y150283D01*
X931692Y149992D01*
X931942Y149575D01*
X932025Y149200D01*
X930275D01*
G01X948933Y170492D02*
X949183Y170617D01*
X949475Y170700D01*
X949808D01*
X950183Y170575D01*
X950475Y170367D01*
X950683Y170117D01*
X950850Y169700D01*
X950892Y169325D01*
X950808Y168950D01*
X950683Y168700D01*
X950433Y168450D01*
X950142Y168283D01*
X949850Y168200D01*
X949558D01*
X949267Y168283D01*
X949017Y168408D01*
X948808Y168575D01*
G01X946250Y168200D02*
Y170700D01*
X947792Y168908D01*
X945708D01*
G01X944567Y168700D02*
X944317Y168408D01*
X943983Y168242D01*
X943608Y168200D01*
X943275Y168242D01*
X942942Y168450D01*
X942733Y168700D01*
X942692Y168950D01*
X942775Y169242D01*
X943067Y169450D01*
X943358Y169533D01*
X943733D01*
G01X943358D02*
X943108Y169658D01*
X942900Y169867D01*
X942817Y170117D01*
X942900Y170367D01*
X943108Y170575D01*
X943483Y170700D01*
X943858Y170658D01*
X944233Y170492D01*
G01X940633Y168200D02*
X940550Y168742D01*
X940425Y169200D01*
X940258Y169617D01*
X940050Y170075D01*
X939717Y170700D01*
X941383D01*
G01X919793Y171319D02*
X920043Y171444D01*
X920335Y171527D01*
X920668D01*
X921043Y171402D01*
X921335Y171194D01*
X921543Y170944D01*
X921710Y170527D01*
X921752Y170152D01*
X921668Y169777D01*
X921543Y169527D01*
X921293Y169277D01*
X921002Y169110D01*
X920710Y169027D01*
X920418D01*
X920127Y169110D01*
X919877Y169235D01*
X919668Y169402D01*
G01X917110Y169027D02*
Y171527D01*
X918652Y169735D01*
X916568D01*
G01X915427Y169527D02*
X915177Y169235D01*
X914843Y169069D01*
X914468Y169027D01*
X914135Y169069D01*
X913802Y169277D01*
X913593Y169527D01*
X913552Y169777D01*
X913635Y170069D01*
X913927Y170277D01*
X914218Y170360D01*
X914593D01*
G01X914218D02*
X913968Y170485D01*
X913760Y170694D01*
X913677Y170944D01*
X913760Y171194D01*
X913968Y171402D01*
X914343Y171527D01*
X914718Y171485D01*
X915093Y171319D01*
G01X912202Y170069D02*
X911910Y170360D01*
X911660Y170527D01*
X911327Y170610D01*
X911035Y170527D01*
X910827Y170360D01*
X910660Y170110D01*
X910618Y169819D01*
X910660Y169569D01*
X910827Y169319D01*
X911077Y169110D01*
X911368Y169027D01*
X911702Y169110D01*
X911993Y169360D01*
X912160Y169735D01*
X912202Y170152D01*
X912118Y170694D01*
X911993Y170985D01*
X911785Y171277D01*
X911493Y171485D01*
X911202Y171527D01*
X910910Y171444D01*
X910702Y171235D01*
G01X935733Y170792D02*
X935983Y170917D01*
X936275Y171000D01*
X936608D01*
X936983Y170875D01*
X937275Y170667D01*
X937483Y170417D01*
X937650Y170000D01*
X937692Y169625D01*
X937608Y169250D01*
X937483Y169000D01*
X937233Y168750D01*
X936942Y168583D01*
X936650Y168500D01*
X936358D01*
X936067Y168583D01*
X935817Y168708D01*
X935608Y168875D01*
G01X933050Y168500D02*
Y171000D01*
X934592Y169208D01*
X932508D01*
G01X931367Y169000D02*
X931117Y168708D01*
X930783Y168542D01*
X930408Y168500D01*
X930075Y168542D01*
X929742Y168750D01*
X929533Y169000D01*
X929492Y169250D01*
X929575Y169542D01*
X929867Y169750D01*
X930158Y169833D01*
X930533D01*
G01X930158D02*
X929908Y169958D01*
X929700Y170167D01*
X929617Y170417D01*
X929700Y170667D01*
X929908Y170875D01*
X930283Y171000D01*
X930658Y170958D01*
X931033Y170792D01*
G01X928267Y168875D02*
X928017Y168667D01*
X927725Y168542D01*
X927350Y168500D01*
X926975Y168583D01*
X926683Y168750D01*
X926475Y169042D01*
X926433Y169375D01*
X926517Y169708D01*
X926725Y169917D01*
X927017Y170083D01*
X927308Y170125D01*
X927600Y170083D01*
X927975Y169917D01*
X927850Y171000D01*
X926725D01*
G01X941233Y162792D02*
X941483Y162917D01*
X941775Y163000D01*
X942108D01*
X942483Y162875D01*
X942775Y162667D01*
X942983Y162417D01*
X943150Y162000D01*
X943192Y161625D01*
X943108Y161250D01*
X942983Y161000D01*
X942733Y160750D01*
X942442Y160583D01*
X942150Y160500D01*
X941858D01*
X941567Y160583D01*
X941317Y160708D01*
X941108Y160875D01*
G01X938550Y160500D02*
Y163000D01*
X940092Y161208D01*
X938008D01*
G01X936867Y161000D02*
X936617Y160708D01*
X936283Y160542D01*
X935908Y160500D01*
X935575Y160542D01*
X935242Y160750D01*
X935033Y161000D01*
X934992Y161250D01*
X935075Y161542D01*
X935367Y161750D01*
X935658Y161833D01*
X936033D01*
G01X935658D02*
X935408Y161958D01*
X935200Y162167D01*
X935117Y162417D01*
X935200Y162667D01*
X935408Y162875D01*
X935783Y163000D01*
X936158Y162958D01*
X936533Y162792D01*
G01X932350Y160500D02*
Y163000D01*
X933892Y161208D01*
X931808D01*
G01X930733Y177892D02*
X930983Y178017D01*
X931275Y178100D01*
X931608D01*
X931983Y177975D01*
X932275Y177767D01*
X932483Y177517D01*
X932650Y177100D01*
X932692Y176725D01*
X932608Y176350D01*
X932483Y176100D01*
X932233Y175850D01*
X931942Y175683D01*
X931650Y175600D01*
X931358D01*
X931067Y175683D01*
X930817Y175808D01*
X930608Y175975D01*
G01X928050Y175600D02*
Y178100D01*
X929592Y176308D01*
X927508D01*
G01X926367Y176100D02*
X926117Y175808D01*
X925783Y175642D01*
X925408Y175600D01*
X925075Y175642D01*
X924742Y175850D01*
X924533Y176100D01*
X924492Y176350D01*
X924575Y176642D01*
X924867Y176850D01*
X925158Y176933D01*
X925533D01*
G01X925158D02*
X924908Y177058D01*
X924700Y177267D01*
X924617Y177517D01*
X924700Y177767D01*
X924908Y177975D01*
X925283Y178100D01*
X925658Y178058D01*
X926033Y177892D01*
G01X923142Y177683D02*
X922892Y177933D01*
X922600Y178058D01*
X922267Y178100D01*
X921850Y178017D01*
X921558Y177808D01*
X921475Y177558D01*
X921517Y177308D01*
X921683Y177100D01*
X922517Y176683D01*
X922892Y176392D01*
X923142Y175975D01*
X923225Y175600D01*
X921475D01*
G01X943533Y177892D02*
X943783Y178017D01*
X944075Y178100D01*
X944408D01*
X944783Y177975D01*
X945075Y177767D01*
X945283Y177517D01*
X945450Y177100D01*
X945492Y176725D01*
X945408Y176350D01*
X945283Y176100D01*
X945033Y175850D01*
X944742Y175683D01*
X944450Y175600D01*
X944158D01*
X943867Y175683D01*
X943617Y175808D01*
X943408Y175975D01*
G01X940850Y175600D02*
Y178100D01*
X942392Y176308D01*
X940308D01*
G01X939042Y177683D02*
X938792Y177933D01*
X938500Y178058D01*
X938167Y178100D01*
X937750Y178017D01*
X937458Y177808D01*
X937375Y177558D01*
X937417Y177308D01*
X937583Y177100D01*
X938417Y176683D01*
X938792Y176392D01*
X939042Y175975D01*
X939125Y175600D01*
X937375D01*
G01X935858Y175892D02*
X935567Y175683D01*
X935233Y175600D01*
X934900Y175683D01*
X934608Y175933D01*
X934400Y176308D01*
X934317Y176683D01*
Y177142D01*
X934400Y177517D01*
X934608Y177850D01*
X934858Y178017D01*
X935150Y178100D01*
X935483Y178017D01*
X935733Y177850D01*
X935900Y177600D01*
X935983Y177267D01*
X935900Y176975D01*
X935692Y176683D01*
X935442Y176517D01*
X935150Y176475D01*
X934817Y176558D01*
X934567Y176767D01*
X934317Y177142D01*
G01X922361Y166535D02*
Y164035D01*
G01X923319Y166535D02*
X921403D01*
G01X920094Y164035D02*
Y166535D01*
X919094D01*
X918761Y166410D01*
X918511Y166118D01*
X918428Y165785D01*
X918511Y165452D01*
X918719Y165202D01*
X919094Y165077D01*
X920094D01*
G01X916161Y164035D02*
Y166535D01*
X916661Y166035D01*
G01Y164035D02*
X915661D01*
G01X913853Y166118D02*
X913603Y166368D01*
X913311Y166493D01*
X912978Y166535D01*
X912561Y166452D01*
X912269Y166243D01*
X912186Y165993D01*
X912228Y165743D01*
X912394Y165535D01*
X913228Y165118D01*
X913603Y164827D01*
X913853Y164410D01*
X913936Y164035D01*
X912186D01*
G01X909961Y166535D02*
X910294Y166452D01*
X910544Y166243D01*
X910711Y165993D01*
X910836Y165660D01*
X910878Y165285D01*
X910836Y164910D01*
X910711Y164577D01*
X910544Y164327D01*
X910294Y164118D01*
X909961Y164035D01*
X909628Y164118D01*
X909378Y164327D01*
X909211Y164577D01*
X909086Y164910D01*
X909044Y165285D01*
X909086Y165660D01*
X909211Y165993D01*
X909378Y166243D01*
X909628Y166452D01*
X909961Y166535D01*
G01X949733Y190292D02*
X949983Y190417D01*
X950275Y190500D01*
X950608D01*
X950983Y190375D01*
X951275Y190167D01*
X951483Y189917D01*
X951650Y189500D01*
X951692Y189125D01*
X951608Y188750D01*
X951483Y188500D01*
X951233Y188250D01*
X950942Y188083D01*
X950650Y188000D01*
X950358D01*
X950067Y188083D01*
X949817Y188208D01*
X949608Y188375D01*
G01X947050Y188000D02*
Y190500D01*
X948592Y188708D01*
X946508D01*
G01X943950Y188000D02*
Y190500D01*
X945492Y188708D01*
X943408D01*
G01X941350Y188000D02*
X941058Y188042D01*
X940725Y188167D01*
X940517Y188375D01*
X940433Y188667D01*
X940517Y188958D01*
X940767Y189208D01*
X941142Y189333D01*
X941558D01*
X941808Y189417D01*
X942017Y189625D01*
X942100Y189917D01*
X941975Y190208D01*
X941683Y190417D01*
X941350Y190500D01*
X941017Y190417D01*
X940725Y190208D01*
X940600Y189917D01*
X940683Y189625D01*
X940892Y189417D01*
X941142Y189333D01*
X941558D01*
X941933Y189208D01*
X942183Y188958D01*
X942267Y188667D01*
X942183Y188375D01*
X941975Y188167D01*
X941642Y188042D01*
X941350Y188000D01*
G01X926183Y190292D02*
X926433Y190417D01*
X926725Y190500D01*
X927058D01*
X927433Y190375D01*
X927725Y190167D01*
X927933Y189917D01*
X928100Y189500D01*
X928142Y189125D01*
X928058Y188750D01*
X927933Y188500D01*
X927683Y188250D01*
X927392Y188083D01*
X927100Y188000D01*
X926808D01*
X926517Y188083D01*
X926267Y188208D01*
X926058Y188375D01*
G01X923500Y188000D02*
Y190500D01*
X925042Y188708D01*
X922958D01*
G01X920900Y190500D02*
X921233Y190417D01*
X921483Y190208D01*
X921650Y189958D01*
X921775Y189625D01*
X921817Y189250D01*
X921775Y188875D01*
X921650Y188542D01*
X921483Y188292D01*
X921233Y188083D01*
X920900Y188000D01*
X920567Y188083D01*
X920317Y188292D01*
X920150Y188542D01*
X920025Y188875D01*
X919983Y189250D01*
X920025Y189625D01*
X920150Y189958D01*
X920317Y190208D01*
X920567Y190417D01*
X920900Y190500D01*
G01X936183Y190292D02*
X936433Y190417D01*
X936725Y190500D01*
X937058D01*
X937433Y190375D01*
X937725Y190167D01*
X937933Y189917D01*
X938100Y189500D01*
X938142Y189125D01*
X938058Y188750D01*
X937933Y188500D01*
X937683Y188250D01*
X937392Y188083D01*
X937100Y188000D01*
X936808D01*
X936517Y188083D01*
X936267Y188208D01*
X936058Y188375D01*
G01X934917Y188500D02*
X934667Y188208D01*
X934333Y188042D01*
X933958Y188000D01*
X933625Y188042D01*
X933292Y188250D01*
X933083Y188500D01*
X933042Y188750D01*
X933125Y189042D01*
X933417Y189250D01*
X933708Y189333D01*
X934083D01*
G01X933708D02*
X933458Y189458D01*
X933250Y189667D01*
X933167Y189917D01*
X933250Y190167D01*
X933458Y190375D01*
X933833Y190500D01*
X934208Y190458D01*
X934583Y190292D01*
G01X931608Y188292D02*
X931317Y188083D01*
X930983Y188000D01*
X930650Y188083D01*
X930358Y188333D01*
X930150Y188708D01*
X930067Y189083D01*
Y189542D01*
X930150Y189917D01*
X930358Y190250D01*
X930608Y190417D01*
X930900Y190500D01*
X931233Y190417D01*
X931483Y190250D01*
X931650Y190000D01*
X931733Y189667D01*
X931650Y189375D01*
X931442Y189083D01*
X931192Y188917D01*
X930900Y188875D01*
X930567Y188958D01*
X930317Y189167D01*
X930067Y189542D01*
G01X943683Y182292D02*
X943933Y182417D01*
X944225Y182500D01*
X944558D01*
X944933Y182375D01*
X945225Y182167D01*
X945433Y181917D01*
X945600Y181500D01*
X945642Y181125D01*
X945558Y180750D01*
X945433Y180500D01*
X945183Y180250D01*
X944892Y180083D01*
X944600Y180000D01*
X944308D01*
X944017Y180083D01*
X943767Y180208D01*
X943558Y180375D01*
G01X942417Y180500D02*
X942167Y180208D01*
X941833Y180042D01*
X941458Y180000D01*
X941125Y180042D01*
X940792Y180250D01*
X940583Y180500D01*
X940542Y180750D01*
X940625Y181042D01*
X940917Y181250D01*
X941208Y181333D01*
X941583D01*
G01X941208D02*
X940958Y181458D01*
X940750Y181667D01*
X940667Y181917D01*
X940750Y182167D01*
X940958Y182375D01*
X941333Y182500D01*
X941708Y182458D01*
X942083Y182292D01*
G01X938400Y180000D02*
X938108Y180042D01*
X937775Y180167D01*
X937567Y180375D01*
X937483Y180667D01*
X937567Y180958D01*
X937817Y181208D01*
X938192Y181333D01*
X938608D01*
X938858Y181417D01*
X939067Y181625D01*
X939150Y181917D01*
X939025Y182208D01*
X938733Y182417D01*
X938400Y182500D01*
X938067Y182417D01*
X937775Y182208D01*
X937650Y181917D01*
X937733Y181625D01*
X937942Y181417D01*
X938192Y181333D01*
X938608D01*
X938983Y181208D01*
X939233Y180958D01*
X939317Y180667D01*
X939233Y180375D01*
X939025Y180167D01*
X938692Y180042D01*
X938400Y180000D01*
G01X925016Y198167D02*
X925266Y198292D01*
X925558Y198375D01*
X925891D01*
X926266Y198250D01*
X926558Y198042D01*
X926766Y197792D01*
X926933Y197375D01*
X926975Y197000D01*
X926891Y196625D01*
X926766Y196375D01*
X926516Y196125D01*
X926225Y195958D01*
X925933Y195875D01*
X925641D01*
X925350Y195958D01*
X925100Y196083D01*
X924891Y196250D01*
G01X923750Y196375D02*
X923500Y196083D01*
X923166Y195917D01*
X922791Y195875D01*
X922458Y195917D01*
X922125Y196125D01*
X921916Y196375D01*
X921875Y196625D01*
X921958Y196917D01*
X922250Y197125D01*
X922541Y197208D01*
X922916D01*
G01X922541D02*
X922291Y197333D01*
X922083Y197542D01*
X922000Y197792D01*
X922083Y198042D01*
X922291Y198250D01*
X922666Y198375D01*
X923041Y198333D01*
X923416Y198167D01*
G01X920525Y196917D02*
X920233Y197208D01*
X919983Y197375D01*
X919650Y197458D01*
X919358Y197375D01*
X919150Y197208D01*
X918983Y196958D01*
X918941Y196667D01*
X918983Y196417D01*
X919150Y196167D01*
X919400Y195958D01*
X919691Y195875D01*
X920025Y195958D01*
X920316Y196208D01*
X920483Y196583D01*
X920525Y197000D01*
X920441Y197542D01*
X920316Y197833D01*
X920108Y198125D01*
X919816Y198333D01*
X919525Y198375D01*
X919233Y198292D01*
X919025Y198083D01*
G01X943683Y201792D02*
X943933Y201917D01*
X944225Y202000D01*
X944558D01*
X944933Y201875D01*
X945225Y201667D01*
X945433Y201417D01*
X945600Y201000D01*
X945642Y200625D01*
X945558Y200250D01*
X945433Y200000D01*
X945183Y199750D01*
X944892Y199583D01*
X944600Y199500D01*
X944308D01*
X944017Y199583D01*
X943767Y199708D01*
X943558Y199875D01*
G01X942417Y200000D02*
X942167Y199708D01*
X941833Y199542D01*
X941458Y199500D01*
X941125Y199542D01*
X940792Y199750D01*
X940583Y200000D01*
X940542Y200250D01*
X940625Y200542D01*
X940917Y200750D01*
X941208Y200833D01*
X941583D01*
G01X941208D02*
X940958Y200958D01*
X940750Y201167D01*
X940667Y201417D01*
X940750Y201667D01*
X940958Y201875D01*
X941333Y202000D01*
X941708Y201958D01*
X942083Y201792D01*
G01X939317Y199875D02*
X939067Y199667D01*
X938775Y199542D01*
X938400Y199500D01*
X938025Y199583D01*
X937733Y199750D01*
X937525Y200042D01*
X937483Y200375D01*
X937567Y200708D01*
X937775Y200917D01*
X938067Y201083D01*
X938358Y201125D01*
X938650Y201083D01*
X939025Y200917D01*
X938900Y202000D01*
X937775D01*
G01X920183Y209292D02*
X920433Y209417D01*
X920725Y209500D01*
X921058D01*
X921433Y209375D01*
X921725Y209167D01*
X921933Y208917D01*
X922100Y208500D01*
X922142Y208125D01*
X922058Y207750D01*
X921933Y207500D01*
X921683Y207250D01*
X921392Y207083D01*
X921100Y207000D01*
X920808D01*
X920517Y207083D01*
X920267Y207208D01*
X920058Y207375D01*
G01X918917Y207500D02*
X918667Y207208D01*
X918333Y207042D01*
X917958Y207000D01*
X917625Y207042D01*
X917292Y207250D01*
X917083Y207500D01*
X917042Y207750D01*
X917125Y208042D01*
X917417Y208250D01*
X917708Y208333D01*
X918083D01*
G01X917708D02*
X917458Y208458D01*
X917250Y208667D01*
X917167Y208917D01*
X917250Y209167D01*
X917458Y209375D01*
X917833Y209500D01*
X918208Y209458D01*
X918583Y209292D01*
G01X915692Y209083D02*
X915442Y209333D01*
X915150Y209458D01*
X914817Y209500D01*
X914400Y209417D01*
X914108Y209208D01*
X914025Y208958D01*
X914067Y208708D01*
X914233Y208500D01*
X915067Y208083D01*
X915442Y207792D01*
X915692Y207375D01*
X915775Y207000D01*
X914025D01*
G01X934683Y197792D02*
X934933Y197917D01*
X935225Y198000D01*
X935558D01*
X935933Y197875D01*
X936225Y197667D01*
X936433Y197417D01*
X936600Y197000D01*
X936642Y196625D01*
X936558Y196250D01*
X936433Y196000D01*
X936183Y195750D01*
X935892Y195583D01*
X935600Y195500D01*
X935308D01*
X935017Y195583D01*
X934767Y195708D01*
X934558Y195875D01*
G01X933417Y196000D02*
X933167Y195708D01*
X932833Y195542D01*
X932458Y195500D01*
X932125Y195542D01*
X931792Y195750D01*
X931583Y196000D01*
X931542Y196250D01*
X931625Y196542D01*
X931917Y196750D01*
X932208Y196833D01*
X932583D01*
G01X932208D02*
X931958Y196958D01*
X931750Y197167D01*
X931667Y197417D01*
X931750Y197667D01*
X931958Y197875D01*
X932333Y198000D01*
X932708Y197958D01*
X933083Y197792D01*
G01X929400Y195500D02*
Y198000D01*
X929900Y197500D01*
G01Y195500D02*
X928900D01*
G01X930683Y209292D02*
X930933Y209417D01*
X931225Y209500D01*
X931558D01*
X931933Y209375D01*
X932225Y209167D01*
X932433Y208917D01*
X932600Y208500D01*
X932642Y208125D01*
X932558Y207750D01*
X932433Y207500D01*
X932183Y207250D01*
X931892Y207083D01*
X931600Y207000D01*
X931308D01*
X931017Y207083D01*
X930767Y207208D01*
X930558Y207375D01*
G01X929417Y207500D02*
X929167Y207208D01*
X928833Y207042D01*
X928458Y207000D01*
X928125Y207042D01*
X927792Y207250D01*
X927583Y207500D01*
X927542Y207750D01*
X927625Y208042D01*
X927917Y208250D01*
X928208Y208333D01*
X928583D01*
G01X928208D02*
X927958Y208458D01*
X927750Y208667D01*
X927667Y208917D01*
X927750Y209167D01*
X927958Y209375D01*
X928333Y209500D01*
X928708Y209458D01*
X929083Y209292D01*
G01X925400Y209500D02*
X925733Y209417D01*
X925983Y209208D01*
X926150Y208958D01*
X926275Y208625D01*
X926317Y208250D01*
X926275Y207875D01*
X926150Y207542D01*
X925983Y207292D01*
X925733Y207083D01*
X925400Y207000D01*
X925067Y207083D01*
X924817Y207292D01*
X924650Y207542D01*
X924525Y207875D01*
X924483Y208250D01*
X924525Y208625D01*
X924650Y208958D01*
X924817Y209208D01*
X925067Y209417D01*
X925400Y209500D01*
G01X941183Y209292D02*
X941433Y209417D01*
X941725Y209500D01*
X942058D01*
X942433Y209375D01*
X942725Y209167D01*
X942933Y208917D01*
X943100Y208500D01*
X943142Y208125D01*
X943058Y207750D01*
X942933Y207500D01*
X942683Y207250D01*
X942392Y207083D01*
X942100Y207000D01*
X941808D01*
X941517Y207083D01*
X941267Y207208D01*
X941058Y207375D01*
G01X939792Y209083D02*
X939542Y209333D01*
X939250Y209458D01*
X938917Y209500D01*
X938500Y209417D01*
X938208Y209208D01*
X938125Y208958D01*
X938167Y208708D01*
X938333Y208500D01*
X939167Y208083D01*
X939542Y207792D01*
X939792Y207375D01*
X939875Y207000D01*
X938125D01*
G01X935983D02*
X935900Y207542D01*
X935775Y208000D01*
X935608Y208417D01*
X935400Y208875D01*
X935067Y209500D01*
X936733D01*
G01X911653Y242967D02*
X911778Y242717D01*
X911861Y242425D01*
Y242092D01*
X911736Y241717D01*
X911528Y241425D01*
X911278Y241217D01*
X910861Y241050D01*
X910486Y241008D01*
X910111Y241092D01*
X909861Y241217D01*
X909611Y241467D01*
X909444Y241758D01*
X909361Y242050D01*
Y242342D01*
X909444Y242633D01*
X909569Y242883D01*
X909736Y243092D01*
G01Y244233D02*
X909528Y244483D01*
X909403Y244775D01*
X909361Y245150D01*
X909444Y245525D01*
X909611Y245817D01*
X909903Y246025D01*
X910236Y246067D01*
X910569Y245983D01*
X910778Y245775D01*
X910944Y245483D01*
X910986Y245192D01*
X910944Y244900D01*
X910778Y244525D01*
X911861Y244650D01*
Y245775D01*
G01X909653Y247542D02*
X909444Y247833D01*
X909361Y248167D01*
X909444Y248500D01*
X909694Y248792D01*
X910069Y249000D01*
X910444Y249083D01*
X910903D01*
X911278Y249000D01*
X911611Y248792D01*
X911778Y248542D01*
X911861Y248250D01*
X911778Y247917D01*
X911611Y247667D01*
X911361Y247500D01*
X911028Y247417D01*
X910736Y247500D01*
X910444Y247708D01*
X910278Y247958D01*
X910236Y248250D01*
X910319Y248583D01*
X910528Y248833D01*
X910903Y249083D01*
G01X909361Y251350D02*
X909403Y251642D01*
X909528Y251975D01*
X909736Y252183D01*
X910028Y252267D01*
X910319Y252183D01*
X910569Y251933D01*
X910694Y251558D01*
Y251142D01*
X910778Y250892D01*
X910986Y250683D01*
X911278Y250600D01*
X911569Y250725D01*
X911778Y251017D01*
X911861Y251350D01*
X911778Y251683D01*
X911569Y251975D01*
X911278Y252100D01*
X910986Y252017D01*
X910778Y251808D01*
X910694Y251558D01*
Y251142D01*
X910569Y250767D01*
X910319Y250517D01*
X910028Y250433D01*
X909736Y250517D01*
X909528Y250725D01*
X909403Y251058D01*
X909361Y251350D01*
G01X921233Y221292D02*
X921483Y221417D01*
X921775Y221500D01*
X922108D01*
X922483Y221375D01*
X922775Y221167D01*
X922983Y220917D01*
X923150Y220500D01*
X923192Y220125D01*
X923108Y219750D01*
X922983Y219500D01*
X922733Y219250D01*
X922442Y219083D01*
X922150Y219000D01*
X921858D01*
X921567Y219083D01*
X921317Y219208D01*
X921108Y219375D01*
G01X919967D02*
X919717Y219167D01*
X919425Y219042D01*
X919050Y219000D01*
X918675Y219083D01*
X918383Y219250D01*
X918175Y219542D01*
X918133Y219875D01*
X918217Y220208D01*
X918425Y220417D01*
X918717Y220583D01*
X919008Y220625D01*
X919300Y220583D01*
X919675Y220417D01*
X919550Y221500D01*
X918425D01*
G01X915450Y219000D02*
Y221500D01*
X916992Y219708D01*
X914908D01*
G01X913767Y219375D02*
X913517Y219167D01*
X913225Y219042D01*
X912850Y219000D01*
X912475Y219083D01*
X912183Y219250D01*
X911975Y219542D01*
X911933Y219875D01*
X912017Y220208D01*
X912225Y220417D01*
X912517Y220583D01*
X912808Y220625D01*
X913100Y220583D01*
X913475Y220417D01*
X913350Y221500D01*
X912225D01*
G01X915557Y243067D02*
X915682Y242817D01*
X915765Y242525D01*
Y242192D01*
X915640Y241817D01*
X915432Y241525D01*
X915182Y241317D01*
X914765Y241150D01*
X914390Y241108D01*
X914015Y241192D01*
X913765Y241317D01*
X913515Y241567D01*
X913348Y241858D01*
X913265Y242150D01*
Y242442D01*
X913348Y242733D01*
X913473Y242983D01*
X913640Y243192D01*
G01Y244333D02*
X913432Y244583D01*
X913307Y244875D01*
X913265Y245250D01*
X913348Y245625D01*
X913515Y245917D01*
X913807Y246125D01*
X914140Y246167D01*
X914473Y246083D01*
X914682Y245875D01*
X914848Y245583D01*
X914890Y245292D01*
X914848Y245000D01*
X914682Y244625D01*
X915765Y244750D01*
Y245875D01*
G01X913265Y248850D02*
X915765D01*
X913973Y247308D01*
Y249392D01*
G01X913265Y251450D02*
X915765D01*
X915265Y250950D01*
G01X913265D02*
Y251950D01*
G01X939733Y217792D02*
X939983Y217917D01*
X940275Y218000D01*
X940608D01*
X940983Y217875D01*
X941275Y217667D01*
X941483Y217417D01*
X941650Y217000D01*
X941692Y216625D01*
X941608Y216250D01*
X941483Y216000D01*
X941233Y215750D01*
X940942Y215583D01*
X940650Y215500D01*
X940358D01*
X940067Y215583D01*
X939817Y215708D01*
X939608Y215875D01*
G01X938467D02*
X938217Y215667D01*
X937925Y215542D01*
X937550Y215500D01*
X937175Y215583D01*
X936883Y215750D01*
X936675Y216042D01*
X936633Y216375D01*
X936717Y216708D01*
X936925Y216917D01*
X937217Y217083D01*
X937508Y217125D01*
X937800Y217083D01*
X938175Y216917D01*
X938050Y218000D01*
X936925D01*
G01X935367Y216000D02*
X935117Y215708D01*
X934783Y215542D01*
X934408Y215500D01*
X934075Y215542D01*
X933742Y215750D01*
X933533Y216000D01*
X933492Y216250D01*
X933575Y216542D01*
X933867Y216750D01*
X934158Y216833D01*
X934533D01*
G01X934158D02*
X933908Y216958D01*
X933700Y217167D01*
X933617Y217417D01*
X933700Y217667D01*
X933908Y217875D01*
X934283Y218000D01*
X934658Y217958D01*
X935033Y217792D01*
G01X931350Y215500D02*
Y218000D01*
X931850Y217500D01*
G01Y215500D02*
X930850D01*
G01X941733Y242933D02*
X941983Y243058D01*
X942275Y243141D01*
X942608D01*
X942983Y243016D01*
X943275Y242808D01*
X943483Y242558D01*
X943650Y242141D01*
X943692Y241766D01*
X943608Y241391D01*
X943483Y241141D01*
X943233Y240891D01*
X942942Y240724D01*
X942650Y240641D01*
X942358D01*
X942067Y240724D01*
X941817Y240849D01*
X941608Y241016D01*
G01X940467D02*
X940217Y240808D01*
X939925Y240683D01*
X939550Y240641D01*
X939175Y240724D01*
X938883Y240891D01*
X938675Y241183D01*
X938633Y241516D01*
X938717Y241849D01*
X938925Y242058D01*
X939217Y242224D01*
X939508Y242266D01*
X939800Y242224D01*
X940175Y242058D01*
X940050Y243141D01*
X938925D01*
G01X937242Y242724D02*
X936992Y242974D01*
X936700Y243099D01*
X936367Y243141D01*
X935950Y243058D01*
X935658Y242849D01*
X935575Y242599D01*
X935617Y242349D01*
X935783Y242141D01*
X936617Y241724D01*
X936992Y241433D01*
X937242Y241016D01*
X937325Y240641D01*
X935575D01*
G01X934142Y242724D02*
X933892Y242974D01*
X933600Y243099D01*
X933267Y243141D01*
X932850Y243058D01*
X932558Y242849D01*
X932475Y242599D01*
X932517Y242349D01*
X932683Y242141D01*
X933517Y241724D01*
X933892Y241433D01*
X934142Y241016D01*
X934225Y240641D01*
X932475D01*
G01X928795Y243242D02*
X929045Y243367D01*
X929337Y243450D01*
X929670D01*
X930045Y243325D01*
X930337Y243117D01*
X930545Y242867D01*
X930712Y242450D01*
X930754Y242075D01*
X930670Y241700D01*
X930545Y241450D01*
X930295Y241200D01*
X930004Y241033D01*
X929712Y240950D01*
X929420D01*
X929129Y241033D01*
X928879Y241158D01*
X928670Y241325D01*
G01X927529D02*
X927279Y241117D01*
X926987Y240992D01*
X926612Y240950D01*
X926237Y241033D01*
X925945Y241200D01*
X925737Y241492D01*
X925695Y241825D01*
X925779Y242158D01*
X925987Y242367D01*
X926279Y242533D01*
X926570Y242575D01*
X926862Y242533D01*
X927237Y242367D01*
X927112Y243450D01*
X925987D01*
G01X924304Y243033D02*
X924054Y243283D01*
X923762Y243408D01*
X923429Y243450D01*
X923012Y243367D01*
X922720Y243158D01*
X922637Y242908D01*
X922679Y242658D01*
X922845Y242450D01*
X923679Y242033D01*
X924054Y241742D01*
X924304Y241325D01*
X924387Y240950D01*
X922637D01*
G01X920412D02*
Y243450D01*
X920912Y242950D01*
G01Y240950D02*
X919912D01*
G01X920183Y213792D02*
X920433Y213917D01*
X920725Y214000D01*
X921058D01*
X921433Y213875D01*
X921725Y213667D01*
X921933Y213417D01*
X922100Y213000D01*
X922142Y212625D01*
X922058Y212250D01*
X921933Y212000D01*
X921683Y211750D01*
X921392Y211583D01*
X921100Y211500D01*
X920808D01*
X920517Y211583D01*
X920267Y211708D01*
X920058Y211875D01*
G01X918792Y213583D02*
X918542Y213833D01*
X918250Y213958D01*
X917917Y214000D01*
X917500Y213917D01*
X917208Y213708D01*
X917125Y213458D01*
X917167Y213208D01*
X917333Y213000D01*
X918167Y212583D01*
X918542Y212292D01*
X918792Y211875D01*
X918875Y211500D01*
X917125D01*
G01X914900D02*
X914608Y211542D01*
X914275Y211667D01*
X914067Y211875D01*
X913983Y212167D01*
X914067Y212458D01*
X914317Y212708D01*
X914692Y212833D01*
X915108D01*
X915358Y212917D01*
X915567Y213125D01*
X915650Y213417D01*
X915525Y213708D01*
X915233Y213917D01*
X914900Y214000D01*
X914567Y213917D01*
X914275Y213708D01*
X914150Y213417D01*
X914233Y213125D01*
X914442Y212917D01*
X914692Y212833D01*
X915108D01*
X915483Y212708D01*
X915733Y212458D01*
X915817Y212167D01*
X915733Y211875D01*
X915525Y211667D01*
X915192Y211542D01*
X914900Y211500D01*
G01X941733Y254753D02*
X941983Y254878D01*
X942275Y254961D01*
X942608D01*
X942983Y254836D01*
X943275Y254628D01*
X943483Y254378D01*
X943650Y253961D01*
X943692Y253586D01*
X943608Y253211D01*
X943483Y252961D01*
X943233Y252711D01*
X942942Y252544D01*
X942650Y252461D01*
X942358D01*
X942067Y252544D01*
X941817Y252669D01*
X941608Y252836D01*
G01X940467D02*
X940217Y252628D01*
X939925Y252503D01*
X939550Y252461D01*
X939175Y252544D01*
X938883Y252711D01*
X938675Y253003D01*
X938633Y253336D01*
X938717Y253669D01*
X938925Y253878D01*
X939217Y254044D01*
X939508Y254086D01*
X939800Y254044D01*
X940175Y253878D01*
X940050Y254961D01*
X938925D01*
G01X937242Y254544D02*
X936992Y254794D01*
X936700Y254919D01*
X936367Y254961D01*
X935950Y254878D01*
X935658Y254669D01*
X935575Y254419D01*
X935617Y254169D01*
X935783Y253961D01*
X936617Y253544D01*
X936992Y253253D01*
X937242Y252836D01*
X937325Y252461D01*
X935575D01*
G01X934058Y252753D02*
X933767Y252544D01*
X933433Y252461D01*
X933100Y252544D01*
X932808Y252794D01*
X932600Y253169D01*
X932517Y253544D01*
Y254003D01*
X932600Y254378D01*
X932808Y254711D01*
X933058Y254878D01*
X933350Y254961D01*
X933683Y254878D01*
X933933Y254711D01*
X934100Y254461D01*
X934183Y254128D01*
X934100Y253836D01*
X933892Y253544D01*
X933642Y253378D01*
X933350Y253336D01*
X933017Y253419D01*
X932767Y253628D01*
X932517Y254003D01*
G01X928795Y255062D02*
X929045Y255187D01*
X929337Y255270D01*
X929670D01*
X930045Y255145D01*
X930337Y254937D01*
X930545Y254687D01*
X930712Y254270D01*
X930754Y253895D01*
X930670Y253520D01*
X930545Y253270D01*
X930295Y253020D01*
X930004Y252853D01*
X929712Y252770D01*
X929420D01*
X929129Y252853D01*
X928879Y252978D01*
X928670Y253145D01*
G01X927529D02*
X927279Y252937D01*
X926987Y252812D01*
X926612Y252770D01*
X926237Y252853D01*
X925945Y253020D01*
X925737Y253312D01*
X925695Y253645D01*
X925779Y253978D01*
X925987Y254187D01*
X926279Y254353D01*
X926570Y254395D01*
X926862Y254353D01*
X927237Y254187D01*
X927112Y255270D01*
X925987D01*
G01X924304Y254853D02*
X924054Y255103D01*
X923762Y255228D01*
X923429Y255270D01*
X923012Y255187D01*
X922720Y254978D01*
X922637Y254728D01*
X922679Y254478D01*
X922845Y254270D01*
X923679Y253853D01*
X924054Y253562D01*
X924304Y253145D01*
X924387Y252770D01*
X922637D01*
G01X920412D02*
X920120Y252812D01*
X919787Y252937D01*
X919579Y253145D01*
X919495Y253437D01*
X919579Y253728D01*
X919829Y253978D01*
X920204Y254103D01*
X920620D01*
X920870Y254187D01*
X921079Y254395D01*
X921162Y254687D01*
X921037Y254978D01*
X920745Y255187D01*
X920412Y255270D01*
X920079Y255187D01*
X919787Y254978D01*
X919662Y254687D01*
X919745Y254395D01*
X919954Y254187D01*
X920204Y254103D01*
X920620D01*
X920995Y253978D01*
X921245Y253728D01*
X921329Y253437D01*
X921245Y253145D01*
X921037Y252937D01*
X920704Y252812D01*
X920412Y252770D01*
G01X941733Y258663D02*
X941983Y258788D01*
X942275Y258871D01*
X942608D01*
X942983Y258746D01*
X943275Y258538D01*
X943483Y258288D01*
X943650Y257871D01*
X943692Y257496D01*
X943608Y257121D01*
X943483Y256871D01*
X943233Y256621D01*
X942942Y256454D01*
X942650Y256371D01*
X942358D01*
X942067Y256454D01*
X941817Y256579D01*
X941608Y256746D01*
G01X940467D02*
X940217Y256538D01*
X939925Y256413D01*
X939550Y256371D01*
X939175Y256454D01*
X938883Y256621D01*
X938675Y256913D01*
X938633Y257246D01*
X938717Y257579D01*
X938925Y257788D01*
X939217Y257954D01*
X939508Y257996D01*
X939800Y257954D01*
X940175Y257788D01*
X940050Y258871D01*
X938925D01*
G01X937242Y258454D02*
X936992Y258704D01*
X936700Y258829D01*
X936367Y258871D01*
X935950Y258788D01*
X935658Y258579D01*
X935575Y258329D01*
X935617Y258079D01*
X935783Y257871D01*
X936617Y257454D01*
X936992Y257163D01*
X937242Y256746D01*
X937325Y256371D01*
X935575D01*
G01X934142Y257413D02*
X933850Y257704D01*
X933600Y257871D01*
X933267Y257954D01*
X932975Y257871D01*
X932767Y257704D01*
X932600Y257454D01*
X932558Y257163D01*
X932600Y256913D01*
X932767Y256663D01*
X933017Y256454D01*
X933308Y256371D01*
X933642Y256454D01*
X933933Y256704D01*
X934100Y257079D01*
X934142Y257496D01*
X934058Y258038D01*
X933933Y258329D01*
X933725Y258621D01*
X933433Y258829D01*
X933142Y258871D01*
X932850Y258788D01*
X932642Y258579D01*
G01X928795Y258972D02*
X929045Y259097D01*
X929337Y259180D01*
X929670D01*
X930045Y259055D01*
X930337Y258847D01*
X930545Y258597D01*
X930712Y258180D01*
X930754Y257805D01*
X930670Y257430D01*
X930545Y257180D01*
X930295Y256930D01*
X930004Y256763D01*
X929712Y256680D01*
X929420D01*
X929129Y256763D01*
X928879Y256888D01*
X928670Y257055D01*
G01X927529D02*
X927279Y256847D01*
X926987Y256722D01*
X926612Y256680D01*
X926237Y256763D01*
X925945Y256930D01*
X925737Y257222D01*
X925695Y257555D01*
X925779Y257888D01*
X925987Y258097D01*
X926279Y258263D01*
X926570Y258305D01*
X926862Y258263D01*
X927237Y258097D01*
X927112Y259180D01*
X925987D01*
G01X924304Y258763D02*
X924054Y259013D01*
X923762Y259138D01*
X923429Y259180D01*
X923012Y259097D01*
X922720Y258888D01*
X922637Y258638D01*
X922679Y258388D01*
X922845Y258180D01*
X923679Y257763D01*
X924054Y257472D01*
X924304Y257055D01*
X924387Y256680D01*
X922637D01*
G01X921329Y257055D02*
X921079Y256847D01*
X920787Y256722D01*
X920412Y256680D01*
X920037Y256763D01*
X919745Y256930D01*
X919537Y257222D01*
X919495Y257555D01*
X919579Y257888D01*
X919787Y258097D01*
X920079Y258263D01*
X920370Y258305D01*
X920662Y258263D01*
X921037Y258097D01*
X920912Y259180D01*
X919787D01*
G01X941733Y250780D02*
X941983Y250905D01*
X942275Y250988D01*
X942608D01*
X942983Y250863D01*
X943275Y250655D01*
X943483Y250405D01*
X943650Y249988D01*
X943692Y249613D01*
X943608Y249238D01*
X943483Y248988D01*
X943233Y248738D01*
X942942Y248571D01*
X942650Y248488D01*
X942358D01*
X942067Y248571D01*
X941817Y248696D01*
X941608Y248863D01*
G01X940467D02*
X940217Y248655D01*
X939925Y248530D01*
X939550Y248488D01*
X939175Y248571D01*
X938883Y248738D01*
X938675Y249030D01*
X938633Y249363D01*
X938717Y249696D01*
X938925Y249905D01*
X939217Y250071D01*
X939508Y250113D01*
X939800Y250071D01*
X940175Y249905D01*
X940050Y250988D01*
X938925D01*
G01X937242Y250571D02*
X936992Y250821D01*
X936700Y250946D01*
X936367Y250988D01*
X935950Y250905D01*
X935658Y250696D01*
X935575Y250446D01*
X935617Y250196D01*
X935783Y249988D01*
X936617Y249571D01*
X936992Y249280D01*
X937242Y248863D01*
X937325Y248488D01*
X935575D01*
G01X932850D02*
Y250988D01*
X934392Y249196D01*
X932308D01*
G01X941733Y246853D02*
X941983Y246978D01*
X942275Y247061D01*
X942608D01*
X942983Y246936D01*
X943275Y246728D01*
X943483Y246478D01*
X943650Y246061D01*
X943692Y245686D01*
X943608Y245311D01*
X943483Y245061D01*
X943233Y244811D01*
X942942Y244644D01*
X942650Y244561D01*
X942358D01*
X942067Y244644D01*
X941817Y244769D01*
X941608Y244936D01*
G01X940467D02*
X940217Y244728D01*
X939925Y244603D01*
X939550Y244561D01*
X939175Y244644D01*
X938883Y244811D01*
X938675Y245103D01*
X938633Y245436D01*
X938717Y245769D01*
X938925Y245978D01*
X939217Y246144D01*
X939508Y246186D01*
X939800Y246144D01*
X940175Y245978D01*
X940050Y247061D01*
X938925D01*
G01X937242Y246644D02*
X936992Y246894D01*
X936700Y247019D01*
X936367Y247061D01*
X935950Y246978D01*
X935658Y246769D01*
X935575Y246519D01*
X935617Y246269D01*
X935783Y246061D01*
X936617Y245644D01*
X936992Y245353D01*
X937242Y244936D01*
X937325Y244561D01*
X935575D01*
G01X933350Y247061D02*
X933683Y246978D01*
X933933Y246769D01*
X934100Y246519D01*
X934225Y246186D01*
X934267Y245811D01*
X934225Y245436D01*
X934100Y245103D01*
X933933Y244853D01*
X933683Y244644D01*
X933350Y244561D01*
X933017Y244644D01*
X932767Y244853D01*
X932600Y245103D01*
X932475Y245436D01*
X932433Y245811D01*
X932475Y246186D01*
X932600Y246519D01*
X932767Y246769D01*
X933017Y246978D01*
X933350Y247061D01*
G01X928795Y247162D02*
X929045Y247287D01*
X929337Y247370D01*
X929670D01*
X930045Y247245D01*
X930337Y247037D01*
X930545Y246787D01*
X930712Y246370D01*
X930754Y245995D01*
X930670Y245620D01*
X930545Y245370D01*
X930295Y245120D01*
X930004Y244953D01*
X929712Y244870D01*
X929420D01*
X929129Y244953D01*
X928879Y245078D01*
X928670Y245245D01*
G01X927529D02*
X927279Y245037D01*
X926987Y244912D01*
X926612Y244870D01*
X926237Y244953D01*
X925945Y245120D01*
X925737Y245412D01*
X925695Y245745D01*
X925779Y246078D01*
X925987Y246287D01*
X926279Y246453D01*
X926570Y246495D01*
X926862Y246453D01*
X927237Y246287D01*
X927112Y247370D01*
X925987D01*
G01X923512Y244870D02*
Y247370D01*
X924012Y246870D01*
G01Y244870D02*
X923012D01*
G01X921120Y245162D02*
X920829Y244953D01*
X920495Y244870D01*
X920162Y244953D01*
X919870Y245203D01*
X919662Y245578D01*
X919579Y245953D01*
Y246412D01*
X919662Y246787D01*
X919870Y247120D01*
X920120Y247287D01*
X920412Y247370D01*
X920745Y247287D01*
X920995Y247120D01*
X921162Y246870D01*
X921245Y246537D01*
X921162Y246245D01*
X920954Y245953D01*
X920704Y245787D01*
X920412Y245745D01*
X920079Y245828D01*
X919829Y246037D01*
X919579Y246412D01*
G01X928795Y251089D02*
X929045Y251214D01*
X929337Y251297D01*
X929670D01*
X930045Y251172D01*
X930337Y250964D01*
X930545Y250714D01*
X930712Y250297D01*
X930754Y249922D01*
X930670Y249547D01*
X930545Y249297D01*
X930295Y249047D01*
X930004Y248880D01*
X929712Y248797D01*
X929420D01*
X929129Y248880D01*
X928879Y249005D01*
X928670Y249172D01*
G01X927529D02*
X927279Y248964D01*
X926987Y248839D01*
X926612Y248797D01*
X926237Y248880D01*
X925945Y249047D01*
X925737Y249339D01*
X925695Y249672D01*
X925779Y250005D01*
X925987Y250214D01*
X926279Y250380D01*
X926570Y250422D01*
X926862Y250380D01*
X927237Y250214D01*
X927112Y251297D01*
X925987D01*
G01X923512D02*
X923845Y251214D01*
X924095Y251005D01*
X924262Y250755D01*
X924387Y250422D01*
X924429Y250047D01*
X924387Y249672D01*
X924262Y249339D01*
X924095Y249089D01*
X923845Y248880D01*
X923512Y248797D01*
X923179Y248880D01*
X922929Y249089D01*
X922762Y249339D01*
X922637Y249672D01*
X922595Y250047D01*
X922637Y250422D01*
X922762Y250755D01*
X922929Y251005D01*
X923179Y251214D01*
X923512Y251297D01*
G01X921329Y249297D02*
X921079Y249005D01*
X920745Y248839D01*
X920370Y248797D01*
X920037Y248839D01*
X919704Y249047D01*
X919495Y249297D01*
X919454Y249547D01*
X919537Y249839D01*
X919829Y250047D01*
X920120Y250130D01*
X920495D01*
G01X920120D02*
X919870Y250255D01*
X919662Y250464D01*
X919579Y250714D01*
X919662Y250964D01*
X919870Y251172D01*
X920245Y251297D01*
X920620Y251255D01*
X920995Y251089D01*
G01X913400Y771483D02*
X911608D01*
X911233Y771650D01*
X910983Y771983D01*
X910900Y772400D01*
X910983Y772817D01*
X911233Y773150D01*
X911608Y773317D01*
X913400D01*
G01X910900Y775417D02*
X911442Y775500D01*
X911900Y775625D01*
X912317Y775792D01*
X912775Y776000D01*
X913400Y776333D01*
Y774667D01*
G01X911942Y777808D02*
X912233Y778100D01*
X912400Y778350D01*
X912483Y778683D01*
X912400Y778975D01*
X912233Y779183D01*
X911983Y779350D01*
X911692Y779392D01*
X911442Y779350D01*
X911192Y779183D01*
X910983Y778933D01*
X910900Y778642D01*
X910983Y778308D01*
X911233Y778017D01*
X911608Y777850D01*
X912025Y777808D01*
X912567Y777892D01*
X912858Y778017D01*
X913150Y778225D01*
X913358Y778517D01*
X913400Y778808D01*
X913317Y779100D01*
X913108Y779308D01*
G01X910432Y782851D02*
X912932D01*
Y783892D01*
X912807Y784226D01*
X912640Y784434D01*
X912307Y784517D01*
X911974Y784434D01*
X911765Y784184D01*
X911640Y783892D01*
Y782851D01*
G01Y783892D02*
X910432Y784517D01*
G01X910932Y785867D02*
X910640Y786117D01*
X910474Y786451D01*
X910432Y786826D01*
X910474Y787159D01*
X910682Y787492D01*
X910932Y787701D01*
X911182Y787742D01*
X911474Y787659D01*
X911682Y787367D01*
X911765Y787076D01*
Y786701D01*
G01Y787076D02*
X911890Y787326D01*
X912099Y787534D01*
X912349Y787617D01*
X912599Y787534D01*
X912807Y787326D01*
X912932Y786951D01*
X912890Y786576D01*
X912724Y786201D01*
G01X912515Y789092D02*
X912765Y789342D01*
X912890Y789634D01*
X912932Y789967D01*
X912849Y790384D01*
X912640Y790676D01*
X912390Y790759D01*
X912140Y790717D01*
X911932Y790551D01*
X911515Y789717D01*
X911224Y789342D01*
X910807Y789092D01*
X910432Y789009D01*
Y790759D01*
G01X910932Y792067D02*
X910640Y792317D01*
X910474Y792651D01*
X910432Y793026D01*
X910474Y793359D01*
X910682Y793692D01*
X910932Y793901D01*
X911182Y793942D01*
X911474Y793859D01*
X911682Y793567D01*
X911765Y793276D01*
Y792901D01*
G01Y793276D02*
X911890Y793526D01*
X912099Y793734D01*
X912349Y793817D01*
X912599Y793734D01*
X912807Y793526D01*
X912932Y793151D01*
X912890Y792776D01*
X912724Y792401D01*
G01X910432Y796001D02*
X910974Y796084D01*
X911432Y796209D01*
X911849Y796376D01*
X912307Y796584D01*
X912932Y796917D01*
Y795251D01*
G01X952933Y37000D02*
Y39500D01*
X951892D01*
X951558Y39375D01*
X951350Y39208D01*
X951267Y38875D01*
X951350Y38542D01*
X951600Y38333D01*
X951892Y38208D01*
X952933D01*
G01X951892D02*
X951267Y37000D01*
G01X948500D02*
Y39500D01*
X950042Y37708D01*
X947958D01*
G01X945900Y37000D02*
Y39500D01*
X946400Y39000D01*
G01Y37000D02*
X945400D01*
G01X962033Y56561D02*
Y59061D01*
X960992D01*
X960658Y58936D01*
X960450Y58769D01*
X960367Y58436D01*
X960450Y58103D01*
X960700Y57894D01*
X960992Y57769D01*
X962033D01*
G01X960992D02*
X960367Y56561D01*
G01X957600D02*
Y59061D01*
X959142Y57269D01*
X957058D01*
G01X955000Y56561D02*
Y59061D01*
X955500Y58561D01*
G01Y56561D02*
X954500D01*
G01X951983D02*
X951900Y57103D01*
X951775Y57561D01*
X951608Y57978D01*
X951400Y58436D01*
X951067Y59061D01*
X952733D01*
G01X948883Y56561D02*
X948800Y57103D01*
X948675Y57561D01*
X948508Y57978D01*
X948300Y58436D01*
X947967Y59061D01*
X949633D01*
G01X958200Y69900D02*
Y65900D01*
X950800D01*
G01X966600Y66267D02*
X969100D01*
Y67308D01*
X968975Y67642D01*
X968808Y67850D01*
X968475Y67933D01*
X968142Y67850D01*
X967933Y67600D01*
X967808Y67308D01*
Y66267D01*
G01Y67308D02*
X966600Y67933D01*
G01X967100Y69283D02*
X966808Y69533D01*
X966642Y69867D01*
X966600Y70242D01*
X966642Y70575D01*
X966850Y70908D01*
X967100Y71117D01*
X967350Y71158D01*
X967642Y71075D01*
X967850Y70783D01*
X967933Y70492D01*
Y70117D01*
G01Y70492D02*
X968058Y70742D01*
X968267Y70950D01*
X968517Y71033D01*
X968767Y70950D01*
X968975Y70742D01*
X969100Y70367D01*
X969058Y69992D01*
X968892Y69617D01*
G01X966600Y73217D02*
X967142Y73300D01*
X967600Y73425D01*
X968017Y73592D01*
X968475Y73800D01*
X969100Y74133D01*
Y72467D01*
G01Y76400D02*
X969017Y76067D01*
X968808Y75817D01*
X968558Y75650D01*
X968225Y75525D01*
X967850Y75483D01*
X967475Y75525D01*
X967142Y75650D01*
X966892Y75817D01*
X966683Y76067D01*
X966600Y76400D01*
X966683Y76733D01*
X966892Y76983D01*
X967142Y77150D01*
X967475Y77275D01*
X967850Y77317D01*
X968225Y77275D01*
X968558Y77150D01*
X968808Y76983D01*
X969017Y76733D01*
X969100Y76400D01*
G01X967642Y78708D02*
X967933Y79000D01*
X968100Y79250D01*
X968183Y79583D01*
X968100Y79875D01*
X967933Y80083D01*
X967683Y80250D01*
X967392Y80292D01*
X967142Y80250D01*
X966892Y80083D01*
X966683Y79833D01*
X966600Y79542D01*
X966683Y79208D01*
X966933Y78917D01*
X967308Y78750D01*
X967725Y78708D01*
X968267Y78792D01*
X968558Y78917D01*
X968850Y79125D01*
X969058Y79417D01*
X969100Y79708D01*
X969017Y80000D01*
X968808Y80208D01*
G01X975600Y66267D02*
X978100D01*
Y67308D01*
X977975Y67642D01*
X977808Y67850D01*
X977475Y67933D01*
X977142Y67850D01*
X976933Y67600D01*
X976808Y67308D01*
Y66267D01*
G01Y67308D02*
X975600Y67933D01*
G01X976100Y69283D02*
X975808Y69533D01*
X975642Y69867D01*
X975600Y70242D01*
X975642Y70575D01*
X975850Y70908D01*
X976100Y71117D01*
X976350Y71158D01*
X976642Y71075D01*
X976850Y70783D01*
X976933Y70492D01*
Y70117D01*
G01Y70492D02*
X977058Y70742D01*
X977267Y70950D01*
X977517Y71033D01*
X977767Y70950D01*
X977975Y70742D01*
X978100Y70367D01*
X978058Y69992D01*
X977892Y69617D01*
G01X975600Y73217D02*
X976142Y73300D01*
X976600Y73425D01*
X977017Y73592D01*
X977475Y73800D01*
X978100Y74133D01*
Y72467D01*
G01Y76400D02*
X978017Y76067D01*
X977808Y75817D01*
X977558Y75650D01*
X977225Y75525D01*
X976850Y75483D01*
X976475Y75525D01*
X976142Y75650D01*
X975892Y75817D01*
X975683Y76067D01*
X975600Y76400D01*
X975683Y76733D01*
X975892Y76983D01*
X976142Y77150D01*
X976475Y77275D01*
X976850Y77317D01*
X977225Y77275D01*
X977558Y77150D01*
X977808Y76983D01*
X978017Y76733D01*
X978100Y76400D01*
G01X975600Y79417D02*
X976142Y79500D01*
X976600Y79625D01*
X977017Y79792D01*
X977475Y80000D01*
X978100Y80333D01*
Y78667D01*
G01X971100Y66267D02*
X973600D01*
Y67308D01*
X973475Y67642D01*
X973308Y67850D01*
X972975Y67933D01*
X972642Y67850D01*
X972433Y67600D01*
X972308Y67308D01*
Y66267D01*
G01Y67308D02*
X971100Y67933D01*
G01X971600Y69283D02*
X971308Y69533D01*
X971142Y69867D01*
X971100Y70242D01*
X971142Y70575D01*
X971350Y70908D01*
X971600Y71117D01*
X971850Y71158D01*
X972142Y71075D01*
X972350Y70783D01*
X972433Y70492D01*
Y70117D01*
G01Y70492D02*
X972558Y70742D01*
X972767Y70950D01*
X973017Y71033D01*
X973267Y70950D01*
X973475Y70742D01*
X973600Y70367D01*
X973558Y69992D01*
X973392Y69617D01*
G01X971100Y73217D02*
X971642Y73300D01*
X972100Y73425D01*
X972517Y73592D01*
X972975Y73800D01*
X973600Y74133D01*
Y72467D01*
G01Y76400D02*
X973517Y76067D01*
X973308Y75817D01*
X973058Y75650D01*
X972725Y75525D01*
X972350Y75483D01*
X971975Y75525D01*
X971642Y75650D01*
X971392Y75817D01*
X971183Y76067D01*
X971100Y76400D01*
X971183Y76733D01*
X971392Y76983D01*
X971642Y77150D01*
X971975Y77275D01*
X972350Y77317D01*
X972725Y77275D01*
X973058Y77150D01*
X973308Y76983D01*
X973517Y76733D01*
X973600Y76400D01*
G01X971100Y79500D02*
X971142Y79792D01*
X971267Y80125D01*
X971475Y80333D01*
X971767Y80417D01*
X972058Y80333D01*
X972308Y80083D01*
X972433Y79708D01*
Y79292D01*
X972517Y79042D01*
X972725Y78833D01*
X973017Y78750D01*
X973308Y78875D01*
X973517Y79167D01*
X973600Y79500D01*
X973517Y79833D01*
X973308Y80125D01*
X973017Y80250D01*
X972725Y80167D01*
X972517Y79958D01*
X972433Y79708D01*
Y79292D01*
X972308Y78917D01*
X972058Y78667D01*
X971767Y78583D01*
X971475Y78667D01*
X971267Y78875D01*
X971142Y79208D01*
X971100Y79500D01*
G01X962600Y67817D02*
X965100D01*
Y68858D01*
X964975Y69192D01*
X964808Y69400D01*
X964475Y69483D01*
X964142Y69400D01*
X963933Y69150D01*
X963808Y68858D01*
Y67817D01*
G01Y68858D02*
X962600Y69483D01*
G01Y71667D02*
X963142Y71750D01*
X963600Y71875D01*
X964017Y72042D01*
X964475Y72250D01*
X965100Y72583D01*
Y70917D01*
G01X962600Y74850D02*
X965100D01*
X964600Y74350D01*
G01X962600D02*
Y75350D01*
G01X965100Y77950D02*
X965017Y77617D01*
X964808Y77367D01*
X964558Y77200D01*
X964225Y77075D01*
X963850Y77033D01*
X963475Y77075D01*
X963142Y77200D01*
X962892Y77367D01*
X962683Y77617D01*
X962600Y77950D01*
X962683Y78283D01*
X962892Y78533D01*
X963142Y78700D01*
X963475Y78825D01*
X963850Y78867D01*
X964225Y78825D01*
X964558Y78700D01*
X964808Y78533D01*
X965017Y78283D01*
X965100Y77950D01*
G01X958933Y60661D02*
Y63161D01*
X957892D01*
X957558Y63036D01*
X957350Y62869D01*
X957267Y62536D01*
X957350Y62203D01*
X957600Y61994D01*
X957892Y61869D01*
X958933D01*
G01X957892D02*
X957267Y60661D01*
G01X955792Y62744D02*
X955542Y62994D01*
X955250Y63119D01*
X954917Y63161D01*
X954500Y63078D01*
X954208Y62869D01*
X954125Y62619D01*
X954167Y62369D01*
X954333Y62161D01*
X955167Y61744D01*
X955542Y61453D01*
X955792Y61036D01*
X955875Y60661D01*
X954125D01*
G01X951900D02*
X951608Y60703D01*
X951275Y60828D01*
X951067Y61036D01*
X950983Y61328D01*
X951067Y61619D01*
X951317Y61869D01*
X951692Y61994D01*
X952108D01*
X952358Y62078D01*
X952567Y62286D01*
X952650Y62578D01*
X952525Y62869D01*
X952233Y63078D01*
X951900Y63161D01*
X951567Y63078D01*
X951275Y62869D01*
X951150Y62578D01*
X951233Y62286D01*
X951442Y62078D01*
X951692Y61994D01*
X952108D01*
X952483Y61869D01*
X952733Y61619D01*
X952817Y61328D01*
X952733Y61036D01*
X952525Y60828D01*
X952192Y60703D01*
X951900Y60661D01*
G01X958200Y74000D02*
Y70000D01*
X950800D01*
G01X982534Y110928D02*
Y108428D01*
G01X983492Y110928D02*
X981576D01*
G01X980267Y108428D02*
Y110928D01*
X979267D01*
X978934Y110803D01*
X978684Y110511D01*
X978601Y110178D01*
X978684Y109845D01*
X978892Y109595D01*
X979267Y109470D01*
X980267D01*
G01X977126Y110511D02*
X976876Y110761D01*
X976584Y110886D01*
X976251Y110928D01*
X975834Y110845D01*
X975542Y110636D01*
X975459Y110386D01*
X975501Y110136D01*
X975667Y109928D01*
X976501Y109511D01*
X976876Y109220D01*
X977126Y108803D01*
X977209Y108428D01*
X975459D01*
G01X973234D02*
X972942Y108470D01*
X972609Y108595D01*
X972401Y108803D01*
X972317Y109095D01*
X972401Y109386D01*
X972651Y109636D01*
X973026Y109761D01*
X973442D01*
X973692Y109845D01*
X973901Y110053D01*
X973984Y110345D01*
X973859Y110636D01*
X973567Y110845D01*
X973234Y110928D01*
X972901Y110845D01*
X972609Y110636D01*
X972484Y110345D01*
X972567Y110053D01*
X972776Y109845D01*
X973026Y109761D01*
X973442D01*
X973817Y109636D01*
X974067Y109386D01*
X974151Y109095D01*
X974067Y108803D01*
X973859Y108595D01*
X973526Y108470D01*
X973234Y108428D01*
G01X969634D02*
Y110928D01*
X971176Y109136D01*
X969092D01*
G01X965877Y110972D02*
Y108472D01*
G01X966835Y110972D02*
X964919D01*
G01X963610Y108472D02*
Y110972D01*
X962610D01*
X962277Y110847D01*
X962027Y110555D01*
X961944Y110222D01*
X962027Y109889D01*
X962235Y109639D01*
X962610Y109514D01*
X963610D01*
G01X959677Y108472D02*
Y110972D01*
X960177Y110472D01*
G01Y108472D02*
X959177D01*
G01X957285Y108764D02*
X956994Y108555D01*
X956660Y108472D01*
X956327Y108555D01*
X956035Y108805D01*
X955827Y109180D01*
X955744Y109555D01*
Y110014D01*
X955827Y110389D01*
X956035Y110722D01*
X956285Y110889D01*
X956577Y110972D01*
X956910Y110889D01*
X957160Y110722D01*
X957327Y110472D01*
X957410Y110139D01*
X957327Y109847D01*
X957119Y109555D01*
X956869Y109389D01*
X956577Y109347D01*
X956244Y109430D01*
X955994Y109639D01*
X955744Y110014D01*
G01X953477Y110972D02*
X953810Y110889D01*
X954060Y110680D01*
X954227Y110430D01*
X954352Y110097D01*
X954394Y109722D01*
X954352Y109347D01*
X954227Y109014D01*
X954060Y108764D01*
X953810Y108555D01*
X953477Y108472D01*
X953144Y108555D01*
X952894Y108764D01*
X952727Y109014D01*
X952602Y109347D01*
X952560Y109722D01*
X952602Y110097D01*
X952727Y110430D01*
X952894Y110680D01*
X953144Y110889D01*
X953477Y110972D01*
G01X960661Y82017D02*
X963161D01*
Y83058D01*
X963036Y83392D01*
X962869Y83600D01*
X962536Y83683D01*
X962203Y83600D01*
X961994Y83350D01*
X961869Y83058D01*
Y82017D01*
G01Y83058D02*
X960661Y83683D01*
G01Y85950D02*
X960703Y86242D01*
X960828Y86575D01*
X961036Y86783D01*
X961328Y86867D01*
X961619Y86783D01*
X961869Y86533D01*
X961994Y86158D01*
Y85742D01*
X962078Y85492D01*
X962286Y85283D01*
X962578Y85200D01*
X962869Y85325D01*
X963078Y85617D01*
X963161Y85950D01*
X963078Y86283D01*
X962869Y86575D01*
X962578Y86700D01*
X962286Y86617D01*
X962078Y86408D01*
X961994Y86158D01*
Y85742D01*
X961869Y85367D01*
X961619Y85117D01*
X961328Y85033D01*
X961036Y85117D01*
X960828Y85325D01*
X960703Y85658D01*
X960661Y85950D01*
G01X961161Y88133D02*
X960869Y88383D01*
X960703Y88717D01*
X960661Y89092D01*
X960703Y89425D01*
X960911Y89758D01*
X961161Y89967D01*
X961411Y90008D01*
X961703Y89925D01*
X961911Y89633D01*
X961994Y89342D01*
Y88967D01*
G01Y89342D02*
X962119Y89592D01*
X962328Y89800D01*
X962578Y89883D01*
X962828Y89800D01*
X963036Y89592D01*
X963161Y89217D01*
X963119Y88842D01*
X962953Y88467D01*
G01X962744Y91358D02*
X962994Y91608D01*
X963119Y91900D01*
X963161Y92233D01*
X963078Y92650D01*
X962869Y92942D01*
X962619Y93025D01*
X962369Y92983D01*
X962161Y92817D01*
X961744Y91983D01*
X961453Y91608D01*
X961036Y91358D01*
X960661Y91275D01*
Y93025D01*
G01X965161Y82017D02*
X967661D01*
Y83058D01*
X967536Y83392D01*
X967369Y83600D01*
X967036Y83683D01*
X966703Y83600D01*
X966494Y83350D01*
X966369Y83058D01*
Y82017D01*
G01Y83058D02*
X965161Y83683D01*
G01Y85950D02*
X965203Y86242D01*
X965328Y86575D01*
X965536Y86783D01*
X965828Y86867D01*
X966119Y86783D01*
X966369Y86533D01*
X966494Y86158D01*
Y85742D01*
X966578Y85492D01*
X966786Y85283D01*
X967078Y85200D01*
X967369Y85325D01*
X967578Y85617D01*
X967661Y85950D01*
X967578Y86283D01*
X967369Y86575D01*
X967078Y86700D01*
X966786Y86617D01*
X966578Y86408D01*
X966494Y86158D01*
Y85742D01*
X966369Y85367D01*
X966119Y85117D01*
X965828Y85033D01*
X965536Y85117D01*
X965328Y85325D01*
X965203Y85658D01*
X965161Y85950D01*
G01X965661Y88133D02*
X965369Y88383D01*
X965203Y88717D01*
X965161Y89092D01*
X965203Y89425D01*
X965411Y89758D01*
X965661Y89967D01*
X965911Y90008D01*
X966203Y89925D01*
X966411Y89633D01*
X966494Y89342D01*
Y88967D01*
G01Y89342D02*
X966619Y89592D01*
X966828Y89800D01*
X967078Y89883D01*
X967328Y89800D01*
X967536Y89592D01*
X967661Y89217D01*
X967619Y88842D01*
X967453Y88467D01*
G01X965161Y92150D02*
X967661D01*
X967161Y91650D01*
G01X965161D02*
Y92650D01*
G01X969661Y82017D02*
X972161D01*
Y83058D01*
X972036Y83392D01*
X971869Y83600D01*
X971536Y83683D01*
X971203Y83600D01*
X970994Y83350D01*
X970869Y83058D01*
Y82017D01*
G01Y83058D02*
X969661Y83683D01*
G01Y85950D02*
X969703Y86242D01*
X969828Y86575D01*
X970036Y86783D01*
X970328Y86867D01*
X970619Y86783D01*
X970869Y86533D01*
X970994Y86158D01*
Y85742D01*
X971078Y85492D01*
X971286Y85283D01*
X971578Y85200D01*
X971869Y85325D01*
X972078Y85617D01*
X972161Y85950D01*
X972078Y86283D01*
X971869Y86575D01*
X971578Y86700D01*
X971286Y86617D01*
X971078Y86408D01*
X970994Y86158D01*
Y85742D01*
X970869Y85367D01*
X970619Y85117D01*
X970328Y85033D01*
X970036Y85117D01*
X969828Y85325D01*
X969703Y85658D01*
X969661Y85950D01*
G01X970161Y88133D02*
X969869Y88383D01*
X969703Y88717D01*
X969661Y89092D01*
X969703Y89425D01*
X969911Y89758D01*
X970161Y89967D01*
X970411Y90008D01*
X970703Y89925D01*
X970911Y89633D01*
X970994Y89342D01*
Y88967D01*
G01Y89342D02*
X971119Y89592D01*
X971328Y89800D01*
X971578Y89883D01*
X971828Y89800D01*
X972036Y89592D01*
X972161Y89217D01*
X972119Y88842D01*
X971953Y88467D01*
G01X972161Y92150D02*
X972078Y91817D01*
X971869Y91567D01*
X971619Y91400D01*
X971286Y91275D01*
X970911Y91233D01*
X970536Y91275D01*
X970203Y91400D01*
X969953Y91567D01*
X969744Y91817D01*
X969661Y92150D01*
X969744Y92483D01*
X969953Y92733D01*
X970203Y92900D01*
X970536Y93025D01*
X970911Y93067D01*
X971286Y93025D01*
X971619Y92900D01*
X971869Y92733D01*
X972078Y92483D01*
X972161Y92150D01*
G01X974161Y82017D02*
X976661D01*
Y83058D01*
X976536Y83392D01*
X976369Y83600D01*
X976036Y83683D01*
X975703Y83600D01*
X975494Y83350D01*
X975369Y83058D01*
Y82017D01*
G01Y83058D02*
X974161Y83683D01*
G01Y85950D02*
X974203Y86242D01*
X974328Y86575D01*
X974536Y86783D01*
X974828Y86867D01*
X975119Y86783D01*
X975369Y86533D01*
X975494Y86158D01*
Y85742D01*
X975578Y85492D01*
X975786Y85283D01*
X976078Y85200D01*
X976369Y85325D01*
X976578Y85617D01*
X976661Y85950D01*
X976578Y86283D01*
X976369Y86575D01*
X976078Y86700D01*
X975786Y86617D01*
X975578Y86408D01*
X975494Y86158D01*
Y85742D01*
X975369Y85367D01*
X975119Y85117D01*
X974828Y85033D01*
X974536Y85117D01*
X974328Y85325D01*
X974203Y85658D01*
X974161Y85950D01*
G01X976244Y88258D02*
X976494Y88508D01*
X976619Y88800D01*
X976661Y89133D01*
X976578Y89550D01*
X976369Y89842D01*
X976119Y89925D01*
X975869Y89883D01*
X975661Y89717D01*
X975244Y88883D01*
X974953Y88508D01*
X974536Y88258D01*
X974161Y88175D01*
Y89925D01*
G01X974453Y91442D02*
X974244Y91733D01*
X974161Y92067D01*
X974244Y92400D01*
X974494Y92692D01*
X974869Y92900D01*
X975244Y92983D01*
X975703D01*
X976078Y92900D01*
X976411Y92692D01*
X976578Y92442D01*
X976661Y92150D01*
X976578Y91817D01*
X976411Y91567D01*
X976161Y91400D01*
X975828Y91317D01*
X975536Y91400D01*
X975244Y91608D01*
X975078Y91858D01*
X975036Y92150D01*
X975119Y92483D01*
X975328Y92733D01*
X975703Y92983D01*
G01X949500Y84200D02*
X953500D01*
Y76800D01*
G01X949500Y95200D02*
X953500D01*
Y87800D01*
G01X945000Y84200D02*
X949000D01*
Y76800D01*
G01X945000Y95200D02*
X949000D01*
Y87800D01*
G01X954000Y84200D02*
X958000D01*
Y76800D01*
G01Y87800D02*
X954000D01*
Y95200D01*
G01X943016Y137274D02*
X945516D01*
Y138315D01*
X945391Y138649D01*
X945224Y138857D01*
X944891Y138940D01*
X944558Y138857D01*
X944349Y138607D01*
X944224Y138315D01*
Y137274D01*
G01Y138315D02*
X943016Y138940D01*
G01X943391Y140290D02*
X943183Y140540D01*
X943058Y140832D01*
X943016Y141207D01*
X943099Y141582D01*
X943266Y141874D01*
X943558Y142082D01*
X943891Y142124D01*
X944224Y142040D01*
X944433Y141832D01*
X944599Y141540D01*
X944641Y141249D01*
X944599Y140957D01*
X944433Y140582D01*
X945516Y140707D01*
Y141832D01*
G01X960887Y134968D02*
X961137Y135093D01*
X961429Y135176D01*
X961762D01*
X962137Y135051D01*
X962429Y134843D01*
X962637Y134593D01*
X962804Y134176D01*
X962846Y133801D01*
X962762Y133426D01*
X962637Y133176D01*
X962387Y132926D01*
X962096Y132759D01*
X961804Y132676D01*
X961512D01*
X961221Y132759D01*
X960971Y132884D01*
X960762Y133051D01*
G01X958204Y132676D02*
Y135176D01*
X959746Y133384D01*
X957662D01*
G01X955687Y132676D02*
X955604Y133218D01*
X955479Y133676D01*
X955312Y134093D01*
X955104Y134551D01*
X954771Y135176D01*
X956437D01*
G01X952004Y132676D02*
Y135176D01*
X953546Y133384D01*
X951462D01*
G01X951183Y123161D02*
X951433Y123286D01*
X951725Y123369D01*
X952058D01*
X952433Y123244D01*
X952725Y123036D01*
X952933Y122786D01*
X953100Y122369D01*
X953142Y121994D01*
X953058Y121619D01*
X952933Y121369D01*
X952683Y121119D01*
X952392Y120952D01*
X952100Y120869D01*
X951808D01*
X951517Y120952D01*
X951267Y121077D01*
X951058Y121244D01*
G01X948500Y120869D02*
Y123369D01*
X950042Y121577D01*
X947958D01*
G01X945983Y120869D02*
X945900Y121411D01*
X945775Y121869D01*
X945608Y122286D01*
X945400Y122744D01*
X945067Y123369D01*
X946733D01*
G01X943717Y121369D02*
X943467Y121077D01*
X943133Y120911D01*
X942758Y120869D01*
X942425Y120911D01*
X942092Y121119D01*
X941883Y121369D01*
X941842Y121619D01*
X941925Y121911D01*
X942217Y122119D01*
X942508Y122202D01*
X942883D01*
G01X942508D02*
X942258Y122327D01*
X942050Y122536D01*
X941967Y122786D01*
X942050Y123036D01*
X942258Y123244D01*
X942633Y123369D01*
X943008Y123327D01*
X943383Y123161D01*
G01X966175Y122994D02*
X966425Y123119D01*
X966717Y123202D01*
X967050D01*
X967425Y123077D01*
X967717Y122869D01*
X967925Y122619D01*
X968092Y122202D01*
X968134Y121827D01*
X968050Y121452D01*
X967925Y121202D01*
X967675Y120952D01*
X967384Y120785D01*
X967092Y120702D01*
X966800D01*
X966509Y120785D01*
X966259Y120910D01*
X966050Y121077D01*
G01X963492Y120702D02*
Y123202D01*
X965034Y121410D01*
X962950D01*
G01X960975Y120702D02*
X960892Y121244D01*
X960767Y121702D01*
X960600Y122119D01*
X960392Y122577D01*
X960059Y123202D01*
X961725D01*
G01X958584Y122785D02*
X958334Y123035D01*
X958042Y123160D01*
X957709Y123202D01*
X957292Y123119D01*
X957000Y122910D01*
X956917Y122660D01*
X956959Y122410D01*
X957125Y122202D01*
X957959Y121785D01*
X958334Y121494D01*
X958584Y121077D01*
X958667Y120702D01*
X956917D01*
G01X972347Y120202D02*
X969847D01*
G01X972347Y119244D02*
Y121160D01*
G01X969847Y122469D02*
X972347D01*
Y123469D01*
X972222Y123802D01*
X971930Y124052D01*
X971597Y124135D01*
X971264Y124052D01*
X971014Y123844D01*
X970889Y123469D01*
Y122469D01*
G01X971930Y125610D02*
X972180Y125860D01*
X972305Y126152D01*
X972347Y126485D01*
X972264Y126902D01*
X972055Y127194D01*
X971805Y127277D01*
X971555Y127235D01*
X971347Y127069D01*
X970930Y126235D01*
X970639Y125860D01*
X970222Y125610D01*
X969847Y125527D01*
Y127277D01*
G01X970139Y128794D02*
X969930Y129085D01*
X969847Y129419D01*
X969930Y129752D01*
X970180Y130044D01*
X970555Y130252D01*
X970930Y130335D01*
X971389D01*
X971764Y130252D01*
X972097Y130044D01*
X972264Y129794D01*
X972347Y129502D01*
X972264Y129169D01*
X972097Y128919D01*
X971847Y128752D01*
X971514Y128669D01*
X971222Y128752D01*
X970930Y128960D01*
X970764Y129210D01*
X970722Y129502D01*
X970805Y129835D01*
X971014Y130085D01*
X971389Y130335D01*
G01X970139Y131894D02*
X969930Y132185D01*
X969847Y132519D01*
X969930Y132852D01*
X970180Y133144D01*
X970555Y133352D01*
X970930Y133435D01*
X971389D01*
X971764Y133352D01*
X972097Y133144D01*
X972264Y132894D01*
X972347Y132602D01*
X972264Y132269D01*
X972097Y132019D01*
X971847Y131852D01*
X971514Y131769D01*
X971222Y131852D01*
X970930Y132060D01*
X970764Y132310D01*
X970722Y132602D01*
X970805Y132935D01*
X971014Y133185D01*
X971389Y133435D01*
G01X964230Y137169D02*
X961730D01*
G01X964230Y136211D02*
Y138127D01*
G01X961730Y139436D02*
X964230D01*
Y140436D01*
X964105Y140769D01*
X963813Y141019D01*
X963480Y141102D01*
X963147Y141019D01*
X962897Y140811D01*
X962772Y140436D01*
Y139436D01*
G01X963813Y142577D02*
X964063Y142827D01*
X964188Y143119D01*
X964230Y143452D01*
X964147Y143869D01*
X963938Y144161D01*
X963688Y144244D01*
X963438Y144202D01*
X963230Y144036D01*
X962813Y143202D01*
X962522Y142827D01*
X962105Y142577D01*
X961730Y142494D01*
Y144244D01*
G01Y146469D02*
X961772Y146761D01*
X961897Y147094D01*
X962105Y147302D01*
X962397Y147386D01*
X962688Y147302D01*
X962938Y147052D01*
X963063Y146677D01*
Y146261D01*
X963147Y146011D01*
X963355Y145802D01*
X963647Y145719D01*
X963938Y145844D01*
X964147Y146136D01*
X964230Y146469D01*
X964147Y146802D01*
X963938Y147094D01*
X963647Y147219D01*
X963355Y147136D01*
X963147Y146927D01*
X963063Y146677D01*
Y146261D01*
X962938Y145886D01*
X962688Y145636D01*
X962397Y145552D01*
X962105Y145636D01*
X961897Y145844D01*
X961772Y146177D01*
X961730Y146469D01*
G01X962230Y148652D02*
X961938Y148902D01*
X961772Y149236D01*
X961730Y149611D01*
X961772Y149944D01*
X961980Y150277D01*
X962230Y150486D01*
X962480Y150527D01*
X962772Y150444D01*
X962980Y150152D01*
X963063Y149861D01*
Y149486D01*
G01Y149861D02*
X963188Y150111D01*
X963397Y150319D01*
X963647Y150402D01*
X963897Y150319D01*
X964105Y150111D01*
X964230Y149736D01*
X964188Y149361D01*
X964022Y148986D01*
G01X982711Y114556D02*
Y112056D01*
G01X983669Y114556D02*
X981753D01*
G01X980444Y112056D02*
Y114556D01*
X979444D01*
X979111Y114431D01*
X978861Y114139D01*
X978778Y113806D01*
X978861Y113473D01*
X979069Y113223D01*
X979444Y113098D01*
X980444D01*
G01X977303Y114139D02*
X977053Y114389D01*
X976761Y114514D01*
X976428Y114556D01*
X976011Y114473D01*
X975719Y114264D01*
X975636Y114014D01*
X975678Y113764D01*
X975844Y113556D01*
X976678Y113139D01*
X977053Y112848D01*
X977303Y112431D01*
X977386Y112056D01*
X975636D01*
G01X973411D02*
X973119Y112098D01*
X972786Y112223D01*
X972578Y112431D01*
X972494Y112723D01*
X972578Y113014D01*
X972828Y113264D01*
X973203Y113389D01*
X973619D01*
X973869Y113473D01*
X974078Y113681D01*
X974161Y113973D01*
X974036Y114264D01*
X973744Y114473D01*
X973411Y114556D01*
X973078Y114473D01*
X972786Y114264D01*
X972661Y113973D01*
X972744Y113681D01*
X972953Y113473D01*
X973203Y113389D01*
X973619D01*
X973994Y113264D01*
X974244Y113014D01*
X974328Y112723D01*
X974244Y112431D01*
X974036Y112223D01*
X973703Y112098D01*
X973411Y112056D01*
G01X971228Y112431D02*
X970978Y112223D01*
X970686Y112098D01*
X970311Y112056D01*
X969936Y112139D01*
X969644Y112306D01*
X969436Y112598D01*
X969394Y112931D01*
X969478Y113264D01*
X969686Y113473D01*
X969978Y113639D01*
X970269Y113681D01*
X970561Y113639D01*
X970936Y113473D01*
X970811Y114556D01*
X969686D01*
G01X965878Y114820D02*
Y112320D01*
G01X966836Y114820D02*
X964920D01*
G01X963611Y112320D02*
Y114820D01*
X962611D01*
X962278Y114695D01*
X962028Y114403D01*
X961945Y114070D01*
X962028Y113737D01*
X962236Y113487D01*
X962611Y113362D01*
X963611D01*
G01X959678Y112320D02*
Y114820D01*
X960178Y114320D01*
G01Y112320D02*
X959178D01*
G01X957286Y112612D02*
X956995Y112403D01*
X956661Y112320D01*
X956328Y112403D01*
X956036Y112653D01*
X955828Y113028D01*
X955745Y113403D01*
Y113862D01*
X955828Y114237D01*
X956036Y114570D01*
X956286Y114737D01*
X956578Y114820D01*
X956911Y114737D01*
X957161Y114570D01*
X957328Y114320D01*
X957411Y113987D01*
X957328Y113695D01*
X957120Y113403D01*
X956870Y113237D01*
X956578Y113195D01*
X956245Y113278D01*
X955995Y113487D01*
X955745Y113862D01*
G01X953561Y112320D02*
X953478Y112862D01*
X953353Y113320D01*
X953186Y113737D01*
X952978Y114195D01*
X952645Y114820D01*
X954311D01*
G01X944866Y143697D02*
X947366D01*
Y144738D01*
X947241Y145072D01*
X947074Y145280D01*
X946741Y145363D01*
X946408Y145280D01*
X946199Y145030D01*
X946074Y144738D01*
Y143697D01*
G01Y144738D02*
X944866Y145363D01*
G01X945908Y146838D02*
X946199Y147130D01*
X946366Y147380D01*
X946449Y147713D01*
X946366Y148005D01*
X946199Y148213D01*
X945949Y148380D01*
X945658Y148422D01*
X945408Y148380D01*
X945158Y148213D01*
X944949Y147963D01*
X944866Y147672D01*
X944949Y147338D01*
X945199Y147047D01*
X945574Y146880D01*
X945991Y146838D01*
X946533Y146922D01*
X946824Y147047D01*
X947116Y147255D01*
X947324Y147547D01*
X947366Y147838D01*
X947283Y148130D01*
X947074Y148338D01*
G01X961733Y170392D02*
X961983Y170517D01*
X962275Y170600D01*
X962608D01*
X962983Y170475D01*
X963275Y170267D01*
X963483Y170017D01*
X963650Y169600D01*
X963692Y169225D01*
X963608Y168850D01*
X963483Y168600D01*
X963233Y168350D01*
X962942Y168183D01*
X962650Y168100D01*
X962358D01*
X962067Y168183D01*
X961817Y168308D01*
X961608Y168475D01*
G01X959050Y168100D02*
Y170600D01*
X960592Y168808D01*
X958508D01*
G01X957367Y168475D02*
X957117Y168267D01*
X956825Y168142D01*
X956450Y168100D01*
X956075Y168183D01*
X955783Y168350D01*
X955575Y168642D01*
X955533Y168975D01*
X955617Y169308D01*
X955825Y169517D01*
X956117Y169683D01*
X956408Y169725D01*
X956700Y169683D01*
X957075Y169517D01*
X956950Y170600D01*
X955825D01*
G01X953350Y168100D02*
Y170600D01*
X953850Y170100D01*
G01Y168100D02*
X952850D01*
G01X969333Y177992D02*
X969583Y178117D01*
X969875Y178200D01*
X970208D01*
X970583Y178075D01*
X970875Y177867D01*
X971083Y177617D01*
X971250Y177200D01*
X971292Y176825D01*
X971208Y176450D01*
X971083Y176200D01*
X970833Y175950D01*
X970542Y175783D01*
X970250Y175700D01*
X969958D01*
X969667Y175783D01*
X969417Y175908D01*
X969208Y176075D01*
G01X966650Y175700D02*
Y178200D01*
X968192Y176408D01*
X966108D01*
G01X964967Y176075D02*
X964717Y175867D01*
X964425Y175742D01*
X964050Y175700D01*
X963675Y175783D01*
X963383Y175950D01*
X963175Y176242D01*
X963133Y176575D01*
X963217Y176908D01*
X963425Y177117D01*
X963717Y177283D01*
X964008Y177325D01*
X964300Y177283D01*
X964675Y177117D01*
X964550Y178200D01*
X963425D01*
G01X960950D02*
X961283Y178117D01*
X961533Y177908D01*
X961700Y177658D01*
X961825Y177325D01*
X961867Y176950D01*
X961825Y176575D01*
X961700Y176242D01*
X961533Y175992D01*
X961283Y175783D01*
X960950Y175700D01*
X960617Y175783D01*
X960367Y175992D01*
X960200Y176242D01*
X960075Y176575D01*
X960033Y176950D01*
X960075Y177325D01*
X960200Y177658D01*
X960367Y177908D01*
X960617Y178117D01*
X960950Y178200D01*
G01X975733Y170792D02*
X975983Y170917D01*
X976275Y171000D01*
X976608D01*
X976983Y170875D01*
X977275Y170667D01*
X977483Y170417D01*
X977650Y170000D01*
X977692Y169625D01*
X977608Y169250D01*
X977483Y169000D01*
X977233Y168750D01*
X976942Y168583D01*
X976650Y168500D01*
X976358D01*
X976067Y168583D01*
X975817Y168708D01*
X975608Y168875D01*
G01X973050Y168500D02*
Y171000D01*
X974592Y169208D01*
X972508D01*
G01X971367Y169000D02*
X971117Y168708D01*
X970783Y168542D01*
X970408Y168500D01*
X970075Y168542D01*
X969742Y168750D01*
X969533Y169000D01*
X969492Y169250D01*
X969575Y169542D01*
X969867Y169750D01*
X970158Y169833D01*
X970533D01*
G01X970158D02*
X969908Y169958D01*
X969700Y170167D01*
X969617Y170417D01*
X969700Y170667D01*
X969908Y170875D01*
X970283Y171000D01*
X970658Y170958D01*
X971033Y170792D01*
G01X967350Y168500D02*
X967058Y168542D01*
X966725Y168667D01*
X966517Y168875D01*
X966433Y169167D01*
X966517Y169458D01*
X966767Y169708D01*
X967142Y169833D01*
X967558D01*
X967808Y169917D01*
X968017Y170125D01*
X968100Y170417D01*
X967975Y170708D01*
X967683Y170917D01*
X967350Y171000D01*
X967017Y170917D01*
X966725Y170708D01*
X966600Y170417D01*
X966683Y170125D01*
X966892Y169917D01*
X967142Y169833D01*
X967558D01*
X967933Y169708D01*
X968183Y169458D01*
X968267Y169167D01*
X968183Y168875D01*
X967975Y168667D01*
X967642Y168542D01*
X967350Y168500D01*
G01X956233Y177992D02*
X956483Y178117D01*
X956775Y178200D01*
X957108D01*
X957483Y178075D01*
X957775Y177867D01*
X957983Y177617D01*
X958150Y177200D01*
X958192Y176825D01*
X958108Y176450D01*
X957983Y176200D01*
X957733Y175950D01*
X957442Y175783D01*
X957150Y175700D01*
X956858D01*
X956567Y175783D01*
X956317Y175908D01*
X956108Y176075D01*
G01X953550Y175700D02*
Y178200D01*
X955092Y176408D01*
X953008D01*
G01X951742Y177783D02*
X951492Y178033D01*
X951200Y178158D01*
X950867Y178200D01*
X950450Y178117D01*
X950158Y177908D01*
X950075Y177658D01*
X950117Y177408D01*
X950283Y177200D01*
X951117Y176783D01*
X951492Y176492D01*
X951742Y176075D01*
X951825Y175700D01*
X950075D01*
G01X947850D02*
X947558Y175742D01*
X947225Y175867D01*
X947017Y176075D01*
X946933Y176367D01*
X947017Y176658D01*
X947267Y176908D01*
X947642Y177033D01*
X948058D01*
X948308Y177117D01*
X948517Y177325D01*
X948600Y177617D01*
X948475Y177908D01*
X948183Y178117D01*
X947850Y178200D01*
X947517Y178117D01*
X947225Y177908D01*
X947100Y177617D01*
X947183Y177325D01*
X947392Y177117D01*
X947642Y177033D01*
X948058D01*
X948433Y176908D01*
X948683Y176658D01*
X948767Y176367D01*
X948683Y176075D01*
X948475Y175867D01*
X948142Y175742D01*
X947850Y175700D01*
G01X974933Y182092D02*
X975183Y182217D01*
X975475Y182300D01*
X975808D01*
X976183Y182175D01*
X976475Y181967D01*
X976683Y181717D01*
X976850Y181300D01*
X976892Y180925D01*
X976808Y180550D01*
X976683Y180300D01*
X976433Y180050D01*
X976142Y179883D01*
X975850Y179800D01*
X975558D01*
X975267Y179883D01*
X975017Y180008D01*
X974808Y180175D01*
G01X973667D02*
X973417Y179967D01*
X973125Y179842D01*
X972750Y179800D01*
X972375Y179883D01*
X972083Y180050D01*
X971875Y180342D01*
X971833Y180675D01*
X971917Y181008D01*
X972125Y181217D01*
X972417Y181383D01*
X972708Y181425D01*
X973000Y181383D01*
X973375Y181217D01*
X973250Y182300D01*
X972125D01*
G01X970358Y180092D02*
X970067Y179883D01*
X969733Y179800D01*
X969400Y179883D01*
X969108Y180133D01*
X968900Y180508D01*
X968817Y180883D01*
Y181342D01*
X968900Y181717D01*
X969108Y182050D01*
X969358Y182217D01*
X969650Y182300D01*
X969983Y182217D01*
X970233Y182050D01*
X970400Y181800D01*
X970483Y181467D01*
X970400Y181175D01*
X970192Y180883D01*
X969942Y180717D01*
X969650Y180675D01*
X969317Y180758D01*
X969067Y180967D01*
X968817Y181342D01*
G01X967467Y180175D02*
X967217Y179967D01*
X966925Y179842D01*
X966550Y179800D01*
X966175Y179883D01*
X965883Y180050D01*
X965675Y180342D01*
X965633Y180675D01*
X965717Y181008D01*
X965925Y181217D01*
X966217Y181383D01*
X966508Y181425D01*
X966800Y181383D01*
X967175Y181217D01*
X967050Y182300D01*
X965925D01*
G01X961733Y182792D02*
X961983Y182917D01*
X962275Y183000D01*
X962608D01*
X962983Y182875D01*
X963275Y182667D01*
X963483Y182417D01*
X963650Y182000D01*
X963692Y181625D01*
X963608Y181250D01*
X963483Y181000D01*
X963233Y180750D01*
X962942Y180583D01*
X962650Y180500D01*
X962358D01*
X962067Y180583D01*
X961817Y180708D01*
X961608Y180875D01*
G01X959050Y180500D02*
Y183000D01*
X960592Y181208D01*
X958508D01*
G01X957242Y181542D02*
X956950Y181833D01*
X956700Y182000D01*
X956367Y182083D01*
X956075Y182000D01*
X955867Y181833D01*
X955700Y181583D01*
X955658Y181292D01*
X955700Y181042D01*
X955867Y180792D01*
X956117Y180583D01*
X956408Y180500D01*
X956742Y180583D01*
X957033Y180833D01*
X957200Y181208D01*
X957242Y181625D01*
X957158Y182167D01*
X957033Y182458D01*
X956825Y182750D01*
X956533Y182958D01*
X956242Y183000D01*
X955950Y182917D01*
X955742Y182708D01*
G01X954142Y182583D02*
X953892Y182833D01*
X953600Y182958D01*
X953267Y183000D01*
X952850Y182917D01*
X952558Y182708D01*
X952475Y182458D01*
X952517Y182208D01*
X952683Y182000D01*
X953517Y181583D01*
X953892Y181292D01*
X954142Y180875D01*
X954225Y180500D01*
X952475D01*
G01X963233Y190292D02*
X963483Y190417D01*
X963775Y190500D01*
X964108D01*
X964483Y190375D01*
X964775Y190167D01*
X964983Y189917D01*
X965150Y189500D01*
X965192Y189125D01*
X965108Y188750D01*
X964983Y188500D01*
X964733Y188250D01*
X964442Y188083D01*
X964150Y188000D01*
X963858D01*
X963567Y188083D01*
X963317Y188208D01*
X963108Y188375D01*
G01X960550Y188000D02*
Y190500D01*
X962092Y188708D01*
X960008D01*
G01X958742Y189042D02*
X958450Y189333D01*
X958200Y189500D01*
X957867Y189583D01*
X957575Y189500D01*
X957367Y189333D01*
X957200Y189083D01*
X957158Y188792D01*
X957200Y188542D01*
X957367Y188292D01*
X957617Y188083D01*
X957908Y188000D01*
X958242Y188083D01*
X958533Y188333D01*
X958700Y188708D01*
X958742Y189125D01*
X958658Y189667D01*
X958533Y189958D01*
X958325Y190250D01*
X958033Y190458D01*
X957742Y190500D01*
X957450Y190417D01*
X957242Y190208D01*
G01X954850Y188000D02*
Y190500D01*
X955350Y190000D01*
G01Y188000D02*
X954350D01*
G01X955233Y209292D02*
X955483Y209417D01*
X955775Y209500D01*
X956108D01*
X956483Y209375D01*
X956775Y209167D01*
X956983Y208917D01*
X957150Y208500D01*
X957192Y208125D01*
X957108Y207750D01*
X956983Y207500D01*
X956733Y207250D01*
X956442Y207083D01*
X956150Y207000D01*
X955858D01*
X955567Y207083D01*
X955317Y207208D01*
X955108Y207375D01*
G01X952550Y207000D02*
Y209500D01*
X954092Y207708D01*
X952008D01*
G01X950742Y208042D02*
X950450Y208333D01*
X950200Y208500D01*
X949867Y208583D01*
X949575Y208500D01*
X949367Y208333D01*
X949200Y208083D01*
X949158Y207792D01*
X949200Y207542D01*
X949367Y207292D01*
X949617Y207083D01*
X949908Y207000D01*
X950242Y207083D01*
X950533Y207333D01*
X950700Y207708D01*
X950742Y208125D01*
X950658Y208667D01*
X950533Y208958D01*
X950325Y209250D01*
X950033Y209458D01*
X949742Y209500D01*
X949450Y209417D01*
X949242Y209208D01*
G01X946850Y209500D02*
X947183Y209417D01*
X947433Y209208D01*
X947600Y208958D01*
X947725Y208625D01*
X947767Y208250D01*
X947725Y207875D01*
X947600Y207542D01*
X947433Y207292D01*
X947183Y207083D01*
X946850Y207000D01*
X946517Y207083D01*
X946267Y207292D01*
X946100Y207542D01*
X945975Y207875D01*
X945933Y208250D01*
X945975Y208625D01*
X946100Y208958D01*
X946267Y209208D01*
X946517Y209417D01*
X946850Y209500D01*
G01X976233Y190292D02*
X976483Y190417D01*
X976775Y190500D01*
X977108D01*
X977483Y190375D01*
X977775Y190167D01*
X977983Y189917D01*
X978150Y189500D01*
X978192Y189125D01*
X978108Y188750D01*
X977983Y188500D01*
X977733Y188250D01*
X977442Y188083D01*
X977150Y188000D01*
X976858D01*
X976567Y188083D01*
X976317Y188208D01*
X976108Y188375D01*
G01X973550Y188000D02*
Y190500D01*
X975092Y188708D01*
X973008D01*
G01X971867Y188375D02*
X971617Y188167D01*
X971325Y188042D01*
X970950Y188000D01*
X970575Y188083D01*
X970283Y188250D01*
X970075Y188542D01*
X970033Y188875D01*
X970117Y189208D01*
X970325Y189417D01*
X970617Y189583D01*
X970908Y189625D01*
X971200Y189583D01*
X971575Y189417D01*
X971450Y190500D01*
X970325D01*
G01X968642Y190083D02*
X968392Y190333D01*
X968100Y190458D01*
X967767Y190500D01*
X967350Y190417D01*
X967058Y190208D01*
X966975Y189958D01*
X967017Y189708D01*
X967183Y189500D01*
X968017Y189083D01*
X968392Y188792D01*
X968642Y188375D01*
X968725Y188000D01*
X966975D01*
G01X961233Y197792D02*
X961483Y197917D01*
X961775Y198000D01*
X962108D01*
X962483Y197875D01*
X962775Y197667D01*
X962983Y197417D01*
X963150Y197000D01*
X963192Y196625D01*
X963108Y196250D01*
X962983Y196000D01*
X962733Y195750D01*
X962442Y195583D01*
X962150Y195500D01*
X961858D01*
X961567Y195583D01*
X961317Y195708D01*
X961108Y195875D01*
G01X958550Y195500D02*
Y198000D01*
X960092Y196208D01*
X958008D01*
G01X955450Y195500D02*
Y198000D01*
X956992Y196208D01*
X954908D01*
G01X952933Y195500D02*
X952850Y196042D01*
X952725Y196500D01*
X952558Y196917D01*
X952350Y197375D01*
X952017Y198000D01*
X953683D01*
G01X974733Y197792D02*
X974983Y197917D01*
X975275Y198000D01*
X975608D01*
X975983Y197875D01*
X976275Y197667D01*
X976483Y197417D01*
X976650Y197000D01*
X976692Y196625D01*
X976608Y196250D01*
X976483Y196000D01*
X976233Y195750D01*
X975942Y195583D01*
X975650Y195500D01*
X975358D01*
X975067Y195583D01*
X974817Y195708D01*
X974608Y195875D01*
G01X972050Y195500D02*
Y198000D01*
X973592Y196208D01*
X971508D01*
G01X968950Y195500D02*
Y198000D01*
X970492Y196208D01*
X968408D01*
G01X967142Y196542D02*
X966850Y196833D01*
X966600Y197000D01*
X966267Y197083D01*
X965975Y197000D01*
X965767Y196833D01*
X965600Y196583D01*
X965558Y196292D01*
X965600Y196042D01*
X965767Y195792D01*
X966017Y195583D01*
X966308Y195500D01*
X966642Y195583D01*
X966933Y195833D01*
X967100Y196208D01*
X967142Y196625D01*
X967058Y197167D01*
X966933Y197458D01*
X966725Y197750D01*
X966433Y197958D01*
X966142Y198000D01*
X965850Y197917D01*
X965642Y197708D01*
G01X961233Y202292D02*
X961483Y202417D01*
X961775Y202500D01*
X962108D01*
X962483Y202375D01*
X962775Y202167D01*
X962983Y201917D01*
X963150Y201500D01*
X963192Y201125D01*
X963108Y200750D01*
X962983Y200500D01*
X962733Y200250D01*
X962442Y200083D01*
X962150Y200000D01*
X961858D01*
X961567Y200083D01*
X961317Y200208D01*
X961108Y200375D01*
G01X958550Y200000D02*
Y202500D01*
X960092Y200708D01*
X958008D01*
G01X955450Y200000D02*
Y202500D01*
X956992Y200708D01*
X954908D01*
G01X952350Y200000D02*
Y202500D01*
X953892Y200708D01*
X951808D01*
G01X974733Y202292D02*
X974983Y202417D01*
X975275Y202500D01*
X975608D01*
X975983Y202375D01*
X976275Y202167D01*
X976483Y201917D01*
X976650Y201500D01*
X976692Y201125D01*
X976608Y200750D01*
X976483Y200500D01*
X976233Y200250D01*
X975942Y200083D01*
X975650Y200000D01*
X975358D01*
X975067Y200083D01*
X974817Y200208D01*
X974608Y200375D01*
G01X972050Y200000D02*
Y202500D01*
X973592Y200708D01*
X971508D01*
G01X968950Y200000D02*
Y202500D01*
X970492Y200708D01*
X968408D01*
G01X967267Y200500D02*
X967017Y200208D01*
X966683Y200042D01*
X966308Y200000D01*
X965975Y200042D01*
X965642Y200250D01*
X965433Y200500D01*
X965392Y200750D01*
X965475Y201042D01*
X965767Y201250D01*
X966058Y201333D01*
X966433D01*
G01X966058D02*
X965808Y201458D01*
X965600Y201667D01*
X965517Y201917D01*
X965600Y202167D01*
X965808Y202375D01*
X966183Y202500D01*
X966558Y202458D01*
X966933Y202292D01*
G01X972683Y210292D02*
X972933Y210417D01*
X973225Y210500D01*
X973558D01*
X973933Y210375D01*
X974225Y210167D01*
X974433Y209917D01*
X974600Y209500D01*
X974642Y209125D01*
X974558Y208750D01*
X974433Y208500D01*
X974183Y208250D01*
X973892Y208083D01*
X973600Y208000D01*
X973308D01*
X973017Y208083D01*
X972767Y208208D01*
X972558Y208375D01*
G01X970000Y208000D02*
Y210500D01*
X971542Y208708D01*
X969458D01*
G01X966900Y208000D02*
Y210500D01*
X968442Y208708D01*
X966358D01*
G01X947683Y197792D02*
X947933Y197917D01*
X948225Y198000D01*
X948558D01*
X948933Y197875D01*
X949225Y197667D01*
X949433Y197417D01*
X949600Y197000D01*
X949642Y196625D01*
X949558Y196250D01*
X949433Y196000D01*
X949183Y195750D01*
X948892Y195583D01*
X948600Y195500D01*
X948308D01*
X948017Y195583D01*
X947767Y195708D01*
X947558Y195875D01*
G01X946417Y196000D02*
X946167Y195708D01*
X945833Y195542D01*
X945458Y195500D01*
X945125Y195542D01*
X944792Y195750D01*
X944583Y196000D01*
X944542Y196250D01*
X944625Y196542D01*
X944917Y196750D01*
X945208Y196833D01*
X945583D01*
G01X945208D02*
X944958Y196958D01*
X944750Y197167D01*
X944667Y197417D01*
X944750Y197667D01*
X944958Y197875D01*
X945333Y198000D01*
X945708Y197958D01*
X946083Y197792D01*
G01X941900Y195500D02*
Y198000D01*
X943442Y196208D01*
X941358D01*
G01X980733Y225792D02*
X980983Y225917D01*
X981275Y226000D01*
X981608D01*
X981983Y225875D01*
X982275Y225667D01*
X982483Y225417D01*
X982650Y225000D01*
X982692Y224625D01*
X982608Y224250D01*
X982483Y224000D01*
X982233Y223750D01*
X981942Y223583D01*
X981650Y223500D01*
X981358D01*
X981067Y223583D01*
X980817Y223708D01*
X980608Y223875D01*
G01X979467D02*
X979217Y223667D01*
X978925Y223542D01*
X978550Y223500D01*
X978175Y223583D01*
X977883Y223750D01*
X977675Y224042D01*
X977633Y224375D01*
X977717Y224708D01*
X977925Y224917D01*
X978217Y225083D01*
X978508Y225125D01*
X978800Y225083D01*
X979175Y224917D01*
X979050Y226000D01*
X977925D01*
G01X976158Y223792D02*
X975867Y223583D01*
X975533Y223500D01*
X975200Y223583D01*
X974908Y223833D01*
X974700Y224208D01*
X974617Y224583D01*
Y225042D01*
X974700Y225417D01*
X974908Y225750D01*
X975158Y225917D01*
X975450Y226000D01*
X975783Y225917D01*
X976033Y225750D01*
X976200Y225500D01*
X976283Y225167D01*
X976200Y224875D01*
X975992Y224583D01*
X975742Y224417D01*
X975450Y224375D01*
X975117Y224458D01*
X974867Y224667D01*
X974617Y225042D01*
G01X971850Y223500D02*
Y226000D01*
X973392Y224208D01*
X971308D01*
G01X947292Y229267D02*
X947417Y229017D01*
X947500Y228725D01*
Y228392D01*
X947375Y228017D01*
X947167Y227725D01*
X946917Y227517D01*
X946500Y227350D01*
X946125Y227308D01*
X945750Y227392D01*
X945500Y227517D01*
X945250Y227767D01*
X945083Y228058D01*
X945000Y228350D01*
Y228642D01*
X945083Y228933D01*
X945208Y229183D01*
X945375Y229392D01*
G01Y230533D02*
X945167Y230783D01*
X945042Y231075D01*
X945000Y231450D01*
X945083Y231825D01*
X945250Y232117D01*
X945542Y232325D01*
X945875Y232367D01*
X946208Y232283D01*
X946417Y232075D01*
X946583Y231783D01*
X946625Y231492D01*
X946583Y231200D01*
X946417Y230825D01*
X947500Y230950D01*
Y232075D01*
G01X945500Y233633D02*
X945208Y233883D01*
X945042Y234217D01*
X945000Y234592D01*
X945042Y234925D01*
X945250Y235258D01*
X945500Y235467D01*
X945750Y235508D01*
X946042Y235425D01*
X946250Y235133D01*
X946333Y234842D01*
Y234467D01*
G01Y234842D02*
X946458Y235092D01*
X946667Y235300D01*
X946917Y235383D01*
X947167Y235300D01*
X947375Y235092D01*
X947500Y234717D01*
X947458Y234342D01*
X947292Y233967D01*
G01X947500Y237650D02*
X947417Y237317D01*
X947208Y237067D01*
X946958Y236900D01*
X946625Y236775D01*
X946250Y236733D01*
X945875Y236775D01*
X945542Y236900D01*
X945292Y237067D01*
X945083Y237317D01*
X945000Y237650D01*
X945083Y237983D01*
X945292Y238233D01*
X945542Y238400D01*
X945875Y238525D01*
X946250Y238567D01*
X946625Y238525D01*
X946958Y238400D01*
X947208Y238233D01*
X947417Y237983D01*
X947500Y237650D01*
G01X982533Y242953D02*
X982783Y243078D01*
X983075Y243161D01*
X983408D01*
X983783Y243036D01*
X984075Y242828D01*
X984283Y242578D01*
X984450Y242161D01*
X984492Y241786D01*
X984408Y241411D01*
X984283Y241161D01*
X984033Y240911D01*
X983742Y240744D01*
X983450Y240661D01*
X983158D01*
X982867Y240744D01*
X982617Y240869D01*
X982408Y241036D01*
G01X981267D02*
X981017Y240828D01*
X980725Y240703D01*
X980350Y240661D01*
X979975Y240744D01*
X979683Y240911D01*
X979475Y241203D01*
X979433Y241536D01*
X979517Y241869D01*
X979725Y242078D01*
X980017Y242244D01*
X980308Y242286D01*
X980600Y242244D01*
X980975Y242078D01*
X980850Y243161D01*
X979725D01*
G01X978042Y242744D02*
X977792Y242994D01*
X977500Y243119D01*
X977167Y243161D01*
X976750Y243078D01*
X976458Y242869D01*
X976375Y242619D01*
X976417Y242369D01*
X976583Y242161D01*
X977417Y241744D01*
X977792Y241453D01*
X978042Y241036D01*
X978125Y240661D01*
X976375D01*
G01X975067Y241161D02*
X974817Y240869D01*
X974483Y240703D01*
X974108Y240661D01*
X973775Y240703D01*
X973442Y240911D01*
X973233Y241161D01*
X973192Y241411D01*
X973275Y241703D01*
X973567Y241911D01*
X973858Y241994D01*
X974233D01*
G01X973858D02*
X973608Y242119D01*
X973400Y242328D01*
X973317Y242578D01*
X973400Y242828D01*
X973608Y243036D01*
X973983Y243161D01*
X974358Y243119D01*
X974733Y242953D01*
G01X969133D02*
X969383Y243078D01*
X969675Y243161D01*
X970008D01*
X970383Y243036D01*
X970675Y242828D01*
X970883Y242578D01*
X971050Y242161D01*
X971092Y241786D01*
X971008Y241411D01*
X970883Y241161D01*
X970633Y240911D01*
X970342Y240744D01*
X970050Y240661D01*
X969758D01*
X969467Y240744D01*
X969217Y240869D01*
X969008Y241036D01*
G01X967867D02*
X967617Y240828D01*
X967325Y240703D01*
X966950Y240661D01*
X966575Y240744D01*
X966283Y240911D01*
X966075Y241203D01*
X966033Y241536D01*
X966117Y241869D01*
X966325Y242078D01*
X966617Y242244D01*
X966908Y242286D01*
X967200Y242244D01*
X967575Y242078D01*
X967450Y243161D01*
X966325D01*
G01X963850Y240661D02*
Y243161D01*
X964350Y242661D01*
G01Y240661D02*
X963350D01*
G01X960750Y243161D02*
X961083Y243078D01*
X961333Y242869D01*
X961500Y242619D01*
X961625Y242286D01*
X961667Y241911D01*
X961625Y241536D01*
X961500Y241203D01*
X961333Y240953D01*
X961083Y240744D01*
X960750Y240661D01*
X960417Y240744D01*
X960167Y240953D01*
X960000Y241203D01*
X959875Y241536D01*
X959833Y241911D01*
X959875Y242286D01*
X960000Y242619D01*
X960167Y242869D01*
X960417Y243078D01*
X960750Y243161D01*
G01X955433Y242953D02*
X955683Y243078D01*
X955975Y243161D01*
X956308D01*
X956683Y243036D01*
X956975Y242828D01*
X957183Y242578D01*
X957350Y242161D01*
X957392Y241786D01*
X957308Y241411D01*
X957183Y241161D01*
X956933Y240911D01*
X956642Y240744D01*
X956350Y240661D01*
X956058D01*
X955767Y240744D01*
X955517Y240869D01*
X955308Y241036D01*
G01X954167D02*
X953917Y240828D01*
X953625Y240703D01*
X953250Y240661D01*
X952875Y240744D01*
X952583Y240911D01*
X952375Y241203D01*
X952333Y241536D01*
X952417Y241869D01*
X952625Y242078D01*
X952917Y242244D01*
X953208Y242286D01*
X953500Y242244D01*
X953875Y242078D01*
X953750Y243161D01*
X952625D01*
G01X950150D02*
X950483Y243078D01*
X950733Y242869D01*
X950900Y242619D01*
X951025Y242286D01*
X951067Y241911D01*
X951025Y241536D01*
X950900Y241203D01*
X950733Y240953D01*
X950483Y240744D01*
X950150Y240661D01*
X949817Y240744D01*
X949567Y240953D01*
X949400Y241203D01*
X949275Y241536D01*
X949233Y241911D01*
X949275Y242286D01*
X949400Y242619D01*
X949567Y242869D01*
X949817Y243078D01*
X950150Y243161D01*
G01X947842Y242744D02*
X947592Y242994D01*
X947300Y243119D01*
X946967Y243161D01*
X946550Y243078D01*
X946258Y242869D01*
X946175Y242619D01*
X946217Y242369D01*
X946383Y242161D01*
X947217Y241744D01*
X947592Y241453D01*
X947842Y241036D01*
X947925Y240661D01*
X946175D01*
G01X952733Y217792D02*
X952983Y217917D01*
X953275Y218000D01*
X953608D01*
X953983Y217875D01*
X954275Y217667D01*
X954483Y217417D01*
X954650Y217000D01*
X954692Y216625D01*
X954608Y216250D01*
X954483Y216000D01*
X954233Y215750D01*
X953942Y215583D01*
X953650Y215500D01*
X953358D01*
X953067Y215583D01*
X952817Y215708D01*
X952608Y215875D01*
G01X950050Y215500D02*
Y218000D01*
X951592Y216208D01*
X949508D01*
G01X946950Y215500D02*
Y218000D01*
X948492Y216208D01*
X946408D01*
G01X944350Y215500D02*
Y218000D01*
X944850Y217500D01*
G01Y215500D02*
X943850D01*
G01X965733Y217792D02*
X965983Y217917D01*
X966275Y218000D01*
X966608D01*
X966983Y217875D01*
X967275Y217667D01*
X967483Y217417D01*
X967650Y217000D01*
X967692Y216625D01*
X967608Y216250D01*
X967483Y216000D01*
X967233Y215750D01*
X966942Y215583D01*
X966650Y215500D01*
X966358D01*
X966067Y215583D01*
X965817Y215708D01*
X965608Y215875D01*
G01X963050Y215500D02*
Y218000D01*
X964592Y216208D01*
X962508D01*
G01X959950Y215500D02*
Y218000D01*
X961492Y216208D01*
X959408D01*
G01X957350Y218000D02*
X957683Y217917D01*
X957933Y217708D01*
X958100Y217458D01*
X958225Y217125D01*
X958267Y216750D01*
X958225Y216375D01*
X958100Y216042D01*
X957933Y215792D01*
X957683Y215583D01*
X957350Y215500D01*
X957017Y215583D01*
X956767Y215792D01*
X956600Y216042D01*
X956475Y216375D01*
X956433Y216750D01*
X956475Y217125D01*
X956600Y217458D01*
X956767Y217708D01*
X957017Y217917D01*
X957350Y218000D01*
G01X955433Y258663D02*
X955683Y258788D01*
X955975Y258871D01*
X956308D01*
X956683Y258746D01*
X956975Y258538D01*
X957183Y258288D01*
X957350Y257871D01*
X957392Y257496D01*
X957308Y257121D01*
X957183Y256871D01*
X956933Y256621D01*
X956642Y256454D01*
X956350Y256371D01*
X956058D01*
X955767Y256454D01*
X955517Y256579D01*
X955308Y256746D01*
G01X954167D02*
X953917Y256538D01*
X953625Y256413D01*
X953250Y256371D01*
X952875Y256454D01*
X952583Y256621D01*
X952375Y256913D01*
X952333Y257246D01*
X952417Y257579D01*
X952625Y257788D01*
X952917Y257954D01*
X953208Y257996D01*
X953500Y257954D01*
X953875Y257788D01*
X953750Y258871D01*
X952625D01*
G01X950942Y258454D02*
X950692Y258704D01*
X950400Y258829D01*
X950067Y258871D01*
X949650Y258788D01*
X949358Y258579D01*
X949275Y258329D01*
X949317Y258079D01*
X949483Y257871D01*
X950317Y257454D01*
X950692Y257163D01*
X950942Y256746D01*
X951025Y256371D01*
X949275D01*
G01X947133D02*
X947050Y256913D01*
X946925Y257371D01*
X946758Y257788D01*
X946550Y258246D01*
X946217Y258871D01*
X947883D01*
G01X969233Y246853D02*
X969483Y246978D01*
X969775Y247061D01*
X970108D01*
X970483Y246936D01*
X970775Y246728D01*
X970983Y246478D01*
X971150Y246061D01*
X971192Y245686D01*
X971108Y245311D01*
X970983Y245061D01*
X970733Y244811D01*
X970442Y244644D01*
X970150Y244561D01*
X969858D01*
X969567Y244644D01*
X969317Y244769D01*
X969108Y244936D01*
G01X967967D02*
X967717Y244728D01*
X967425Y244603D01*
X967050Y244561D01*
X966675Y244644D01*
X966383Y244811D01*
X966175Y245103D01*
X966133Y245436D01*
X966217Y245769D01*
X966425Y245978D01*
X966717Y246144D01*
X967008Y246186D01*
X967300Y246144D01*
X967675Y245978D01*
X967550Y247061D01*
X966425D01*
G01X963950Y244561D02*
Y247061D01*
X964450Y246561D01*
G01Y244561D02*
X963450D01*
G01X960350D02*
Y247061D01*
X961892Y245269D01*
X959808D01*
G01X955433Y246853D02*
X955683Y246978D01*
X955975Y247061D01*
X956308D01*
X956683Y246936D01*
X956975Y246728D01*
X957183Y246478D01*
X957350Y246061D01*
X957392Y245686D01*
X957308Y245311D01*
X957183Y245061D01*
X956933Y244811D01*
X956642Y244644D01*
X956350Y244561D01*
X956058D01*
X955767Y244644D01*
X955517Y244769D01*
X955308Y244936D01*
G01X954167D02*
X953917Y244728D01*
X953625Y244603D01*
X953250Y244561D01*
X952875Y244644D01*
X952583Y244811D01*
X952375Y245103D01*
X952333Y245436D01*
X952417Y245769D01*
X952625Y245978D01*
X952917Y246144D01*
X953208Y246186D01*
X953500Y246144D01*
X953875Y245978D01*
X953750Y247061D01*
X952625D01*
G01X950150Y244561D02*
Y247061D01*
X950650Y246561D01*
G01Y244561D02*
X949650D01*
G01X947967Y245061D02*
X947717Y244769D01*
X947383Y244603D01*
X947008Y244561D01*
X946675Y244603D01*
X946342Y244811D01*
X946133Y245061D01*
X946092Y245311D01*
X946175Y245603D01*
X946467Y245811D01*
X946758Y245894D01*
X947133D01*
G01X946758D02*
X946508Y246019D01*
X946300Y246228D01*
X946217Y246478D01*
X946300Y246728D01*
X946508Y246936D01*
X946883Y247061D01*
X947258Y247019D01*
X947633Y246853D01*
G01X982633D02*
X982883Y246978D01*
X983175Y247061D01*
X983508D01*
X983883Y246936D01*
X984175Y246728D01*
X984383Y246478D01*
X984550Y246061D01*
X984592Y245686D01*
X984508Y245311D01*
X984383Y245061D01*
X984133Y244811D01*
X983842Y244644D01*
X983550Y244561D01*
X983258D01*
X982967Y244644D01*
X982717Y244769D01*
X982508Y244936D01*
G01X981367D02*
X981117Y244728D01*
X980825Y244603D01*
X980450Y244561D01*
X980075Y244644D01*
X979783Y244811D01*
X979575Y245103D01*
X979533Y245436D01*
X979617Y245769D01*
X979825Y245978D01*
X980117Y246144D01*
X980408Y246186D01*
X980700Y246144D01*
X981075Y245978D01*
X980950Y247061D01*
X979825D01*
G01X977350Y244561D02*
Y247061D01*
X977850Y246561D01*
G01Y244561D02*
X976850D01*
G01X975042Y246644D02*
X974792Y246894D01*
X974500Y247019D01*
X974167Y247061D01*
X973750Y246978D01*
X973458Y246769D01*
X973375Y246519D01*
X973417Y246269D01*
X973583Y246061D01*
X974417Y245644D01*
X974792Y245353D01*
X975042Y244936D01*
X975125Y244561D01*
X973375D01*
G01X969233Y250780D02*
X969483Y250905D01*
X969775Y250988D01*
X970108D01*
X970483Y250863D01*
X970775Y250655D01*
X970983Y250405D01*
X971150Y249988D01*
X971192Y249613D01*
X971108Y249238D01*
X970983Y248988D01*
X970733Y248738D01*
X970442Y248571D01*
X970150Y248488D01*
X969858D01*
X969567Y248571D01*
X969317Y248696D01*
X969108Y248863D01*
G01X967967D02*
X967717Y248655D01*
X967425Y248530D01*
X967050Y248488D01*
X966675Y248571D01*
X966383Y248738D01*
X966175Y249030D01*
X966133Y249363D01*
X966217Y249696D01*
X966425Y249905D01*
X966717Y250071D01*
X967008Y250113D01*
X967300Y250071D01*
X967675Y249905D01*
X967550Y250988D01*
X966425D01*
G01X963950Y248488D02*
Y250988D01*
X964450Y250488D01*
G01Y248488D02*
X963450D01*
G01X960850D02*
Y250988D01*
X961350Y250488D01*
G01Y248488D02*
X960350D01*
G01X955433Y254753D02*
X955683Y254878D01*
X955975Y254961D01*
X956308D01*
X956683Y254836D01*
X956975Y254628D01*
X957183Y254378D01*
X957350Y253961D01*
X957392Y253586D01*
X957308Y253211D01*
X957183Y252961D01*
X956933Y252711D01*
X956642Y252544D01*
X956350Y252461D01*
X956058D01*
X955767Y252544D01*
X955517Y252669D01*
X955308Y252836D01*
G01X954167D02*
X953917Y252628D01*
X953625Y252503D01*
X953250Y252461D01*
X952875Y252544D01*
X952583Y252711D01*
X952375Y253003D01*
X952333Y253336D01*
X952417Y253669D01*
X952625Y253878D01*
X952917Y254044D01*
X953208Y254086D01*
X953500Y254044D01*
X953875Y253878D01*
X953750Y254961D01*
X952625D01*
G01X950150D02*
X950483Y254878D01*
X950733Y254669D01*
X950900Y254419D01*
X951025Y254086D01*
X951067Y253711D01*
X951025Y253336D01*
X950900Y253003D01*
X950733Y252753D01*
X950483Y252544D01*
X950150Y252461D01*
X949817Y252544D01*
X949567Y252753D01*
X949400Y253003D01*
X949275Y253336D01*
X949233Y253711D01*
X949275Y254086D01*
X949400Y254419D01*
X949567Y254669D01*
X949817Y254878D01*
X950150Y254961D01*
G01X947758Y252753D02*
X947467Y252544D01*
X947133Y252461D01*
X946800Y252544D01*
X946508Y252794D01*
X946300Y253169D01*
X946217Y253544D01*
Y254003D01*
X946300Y254378D01*
X946508Y254711D01*
X946758Y254878D01*
X947050Y254961D01*
X947383Y254878D01*
X947633Y254711D01*
X947800Y254461D01*
X947883Y254128D01*
X947800Y253836D01*
X947592Y253544D01*
X947342Y253378D01*
X947050Y253336D01*
X946717Y253419D01*
X946467Y253628D01*
X946217Y254003D01*
G01X969233Y254753D02*
X969483Y254878D01*
X969775Y254961D01*
X970108D01*
X970483Y254836D01*
X970775Y254628D01*
X970983Y254378D01*
X971150Y253961D01*
X971192Y253586D01*
X971108Y253211D01*
X970983Y252961D01*
X970733Y252711D01*
X970442Y252544D01*
X970150Y252461D01*
X969858D01*
X969567Y252544D01*
X969317Y252669D01*
X969108Y252836D01*
G01X967967D02*
X967717Y252628D01*
X967425Y252503D01*
X967050Y252461D01*
X966675Y252544D01*
X966383Y252711D01*
X966175Y253003D01*
X966133Y253336D01*
X966217Y253669D01*
X966425Y253878D01*
X966717Y254044D01*
X967008Y254086D01*
X967300Y254044D01*
X967675Y253878D01*
X967550Y254961D01*
X966425D01*
G01X963950D02*
X964283Y254878D01*
X964533Y254669D01*
X964700Y254419D01*
X964825Y254086D01*
X964867Y253711D01*
X964825Y253336D01*
X964700Y253003D01*
X964533Y252753D01*
X964283Y252544D01*
X963950Y252461D01*
X963617Y252544D01*
X963367Y252753D01*
X963200Y253003D01*
X963075Y253336D01*
X963033Y253711D01*
X963075Y254086D01*
X963200Y254419D01*
X963367Y254669D01*
X963617Y254878D01*
X963950Y254961D01*
G01X960850Y252461D02*
X960558Y252503D01*
X960225Y252628D01*
X960017Y252836D01*
X959933Y253128D01*
X960017Y253419D01*
X960267Y253669D01*
X960642Y253794D01*
X961058D01*
X961308Y253878D01*
X961517Y254086D01*
X961600Y254378D01*
X961475Y254669D01*
X961183Y254878D01*
X960850Y254961D01*
X960517Y254878D01*
X960225Y254669D01*
X960100Y254378D01*
X960183Y254086D01*
X960392Y253878D01*
X960642Y253794D01*
X961058D01*
X961433Y253669D01*
X961683Y253419D01*
X961767Y253128D01*
X961683Y252836D01*
X961475Y252628D01*
X961142Y252503D01*
X960850Y252461D01*
G01X982633Y254753D02*
X982883Y254878D01*
X983175Y254961D01*
X983508D01*
X983883Y254836D01*
X984175Y254628D01*
X984383Y254378D01*
X984550Y253961D01*
X984592Y253586D01*
X984508Y253211D01*
X984383Y252961D01*
X984133Y252711D01*
X983842Y252544D01*
X983550Y252461D01*
X983258D01*
X982967Y252544D01*
X982717Y252669D01*
X982508Y252836D01*
G01X981367D02*
X981117Y252628D01*
X980825Y252503D01*
X980450Y252461D01*
X980075Y252544D01*
X979783Y252711D01*
X979575Y253003D01*
X979533Y253336D01*
X979617Y253669D01*
X979825Y253878D01*
X980117Y254044D01*
X980408Y254086D01*
X980700Y254044D01*
X981075Y253878D01*
X980950Y254961D01*
X979825D01*
G01X977350D02*
X977683Y254878D01*
X977933Y254669D01*
X978100Y254419D01*
X978225Y254086D01*
X978267Y253711D01*
X978225Y253336D01*
X978100Y253003D01*
X977933Y252753D01*
X977683Y252544D01*
X977350Y252461D01*
X977017Y252544D01*
X976767Y252753D01*
X976600Y253003D01*
X976475Y253336D01*
X976433Y253711D01*
X976475Y254086D01*
X976600Y254419D01*
X976767Y254669D01*
X977017Y254878D01*
X977350Y254961D01*
G01X975042Y253503D02*
X974750Y253794D01*
X974500Y253961D01*
X974167Y254044D01*
X973875Y253961D01*
X973667Y253794D01*
X973500Y253544D01*
X973458Y253253D01*
X973500Y253003D01*
X973667Y252753D01*
X973917Y252544D01*
X974208Y252461D01*
X974542Y252544D01*
X974833Y252794D01*
X975000Y253169D01*
X975042Y253586D01*
X974958Y254128D01*
X974833Y254419D01*
X974625Y254711D01*
X974333Y254919D01*
X974042Y254961D01*
X973750Y254878D01*
X973542Y254669D01*
G01X969233Y258663D02*
X969483Y258788D01*
X969775Y258871D01*
X970108D01*
X970483Y258746D01*
X970775Y258538D01*
X970983Y258288D01*
X971150Y257871D01*
X971192Y257496D01*
X971108Y257121D01*
X970983Y256871D01*
X970733Y256621D01*
X970442Y256454D01*
X970150Y256371D01*
X969858D01*
X969567Y256454D01*
X969317Y256579D01*
X969108Y256746D01*
G01X967967D02*
X967717Y256538D01*
X967425Y256413D01*
X967050Y256371D01*
X966675Y256454D01*
X966383Y256621D01*
X966175Y256913D01*
X966133Y257246D01*
X966217Y257579D01*
X966425Y257788D01*
X966717Y257954D01*
X967008Y257996D01*
X967300Y257954D01*
X967675Y257788D01*
X967550Y258871D01*
X966425D01*
G01X963950D02*
X964283Y258788D01*
X964533Y258579D01*
X964700Y258329D01*
X964825Y257996D01*
X964867Y257621D01*
X964825Y257246D01*
X964700Y256913D01*
X964533Y256663D01*
X964283Y256454D01*
X963950Y256371D01*
X963617Y256454D01*
X963367Y256663D01*
X963200Y256913D01*
X963075Y257246D01*
X963033Y257621D01*
X963075Y257996D01*
X963200Y258329D01*
X963367Y258579D01*
X963617Y258788D01*
X963950Y258871D01*
G01X961767Y256746D02*
X961517Y256538D01*
X961225Y256413D01*
X960850Y256371D01*
X960475Y256454D01*
X960183Y256621D01*
X959975Y256913D01*
X959933Y257246D01*
X960017Y257579D01*
X960225Y257788D01*
X960517Y257954D01*
X960808Y257996D01*
X961100Y257954D01*
X961475Y257788D01*
X961350Y258871D01*
X960225D01*
G01X982633Y258653D02*
X982883Y258778D01*
X983175Y258861D01*
X983508D01*
X983883Y258736D01*
X984175Y258528D01*
X984383Y258278D01*
X984550Y257861D01*
X984592Y257486D01*
X984508Y257111D01*
X984383Y256861D01*
X984133Y256611D01*
X983842Y256444D01*
X983550Y256361D01*
X983258D01*
X982967Y256444D01*
X982717Y256569D01*
X982508Y256736D01*
G01X981367D02*
X981117Y256528D01*
X980825Y256403D01*
X980450Y256361D01*
X980075Y256444D01*
X979783Y256611D01*
X979575Y256903D01*
X979533Y257236D01*
X979617Y257569D01*
X979825Y257778D01*
X980117Y257944D01*
X980408Y257986D01*
X980700Y257944D01*
X981075Y257778D01*
X980950Y258861D01*
X979825D01*
G01X977350D02*
X977683Y258778D01*
X977933Y258569D01*
X978100Y258319D01*
X978225Y257986D01*
X978267Y257611D01*
X978225Y257236D01*
X978100Y256903D01*
X977933Y256653D01*
X977683Y256444D01*
X977350Y256361D01*
X977017Y256444D01*
X976767Y256653D01*
X976600Y256903D01*
X976475Y257236D01*
X976433Y257611D01*
X976475Y257986D01*
X976600Y258319D01*
X976767Y258569D01*
X977017Y258778D01*
X977350Y258861D01*
G01X973750Y256361D02*
Y258861D01*
X975292Y257069D01*
X973208D01*
G01X982633Y250753D02*
X982883Y250878D01*
X983175Y250961D01*
X983508D01*
X983883Y250836D01*
X984175Y250628D01*
X984383Y250378D01*
X984550Y249961D01*
X984592Y249586D01*
X984508Y249211D01*
X984383Y248961D01*
X984133Y248711D01*
X983842Y248544D01*
X983550Y248461D01*
X983258D01*
X982967Y248544D01*
X982717Y248669D01*
X982508Y248836D01*
G01X981367D02*
X981117Y248628D01*
X980825Y248503D01*
X980450Y248461D01*
X980075Y248544D01*
X979783Y248711D01*
X979575Y249003D01*
X979533Y249336D01*
X979617Y249669D01*
X979825Y249878D01*
X980117Y250044D01*
X980408Y250086D01*
X980700Y250044D01*
X981075Y249878D01*
X980950Y250961D01*
X979825D01*
G01X977350D02*
X977683Y250878D01*
X977933Y250669D01*
X978100Y250419D01*
X978225Y250086D01*
X978267Y249711D01*
X978225Y249336D01*
X978100Y249003D01*
X977933Y248753D01*
X977683Y248544D01*
X977350Y248461D01*
X977017Y248544D01*
X976767Y248753D01*
X976600Y249003D01*
X976475Y249336D01*
X976433Y249711D01*
X976475Y250086D01*
X976600Y250419D01*
X976767Y250669D01*
X977017Y250878D01*
X977350Y250961D01*
G01X974250Y248461D02*
Y250961D01*
X974750Y250461D01*
G01Y248461D02*
X973750D01*
G01X955433Y250780D02*
X955683Y250905D01*
X955975Y250988D01*
X956308D01*
X956683Y250863D01*
X956975Y250655D01*
X957183Y250405D01*
X957350Y249988D01*
X957392Y249613D01*
X957308Y249238D01*
X957183Y248988D01*
X956933Y248738D01*
X956642Y248571D01*
X956350Y248488D01*
X956058D01*
X955767Y248571D01*
X955517Y248696D01*
X955308Y248863D01*
G01X954167D02*
X953917Y248655D01*
X953625Y248530D01*
X953250Y248488D01*
X952875Y248571D01*
X952583Y248738D01*
X952375Y249030D01*
X952333Y249363D01*
X952417Y249696D01*
X952625Y249905D01*
X952917Y250071D01*
X953208Y250113D01*
X953500Y250071D01*
X953875Y249905D01*
X953750Y250988D01*
X952625D01*
G01X950150D02*
X950483Y250905D01*
X950733Y250696D01*
X950900Y250446D01*
X951025Y250113D01*
X951067Y249738D01*
X951025Y249363D01*
X950900Y249030D01*
X950733Y248780D01*
X950483Y248571D01*
X950150Y248488D01*
X949817Y248571D01*
X949567Y248780D01*
X949400Y249030D01*
X949275Y249363D01*
X949233Y249738D01*
X949275Y250113D01*
X949400Y250446D01*
X949567Y250696D01*
X949817Y250905D01*
X950150Y250988D01*
G01X947050D02*
X947383Y250905D01*
X947633Y250696D01*
X947800Y250446D01*
X947925Y250113D01*
X947967Y249738D01*
X947925Y249363D01*
X947800Y249030D01*
X947633Y248780D01*
X947383Y248571D01*
X947050Y248488D01*
X946717Y248571D01*
X946467Y248780D01*
X946300Y249030D01*
X946175Y249363D01*
X946133Y249738D01*
X946175Y250113D01*
X946300Y250446D01*
X946467Y250696D01*
X946717Y250905D01*
X947050Y250988D01*
G01X1005426Y-8025D02*
Y-5525D01*
X1004385D01*
X1004051Y-5650D01*
X1003843Y-5817D01*
X1003760Y-6150D01*
X1003843Y-6483D01*
X1004093Y-6692D01*
X1004385Y-6817D01*
X1005426D01*
G01X1004385D02*
X1003760Y-8025D01*
G01X1002285Y-5942D02*
X1002035Y-5692D01*
X1001743Y-5567D01*
X1001410Y-5525D01*
X1000993Y-5608D01*
X1000701Y-5817D01*
X1000618Y-6067D01*
X1000660Y-6317D01*
X1000826Y-6525D01*
X1001660Y-6942D01*
X1002035Y-7233D01*
X1002285Y-7650D01*
X1002368Y-8025D01*
X1000618D01*
G01X998393Y-5525D02*
X998726Y-5608D01*
X998976Y-5817D01*
X999143Y-6067D01*
X999268Y-6400D01*
X999310Y-6775D01*
X999268Y-7150D01*
X999143Y-7483D01*
X998976Y-7733D01*
X998726Y-7942D01*
X998393Y-8025D01*
X998060Y-7942D01*
X997810Y-7733D01*
X997643Y-7483D01*
X997518Y-7150D01*
X997476Y-6775D01*
X997518Y-6400D01*
X997643Y-6067D01*
X997810Y-5817D01*
X998060Y-5608D01*
X998393Y-5525D01*
G01X994793Y-8025D02*
Y-5525D01*
X996335Y-7317D01*
X994251D01*
G01X992325Y-7830D02*
Y-5330D01*
X991284D01*
X990950Y-5455D01*
X990742Y-5622D01*
X990659Y-5955D01*
X990742Y-6288D01*
X990992Y-6497D01*
X991284Y-6622D01*
X992325D01*
G01X991284D02*
X990659Y-7830D01*
G01X989184Y-5747D02*
X988934Y-5497D01*
X988642Y-5372D01*
X988309Y-5330D01*
X987892Y-5413D01*
X987600Y-5622D01*
X987517Y-5872D01*
X987559Y-6122D01*
X987725Y-6330D01*
X988559Y-6747D01*
X988934Y-7038D01*
X989184Y-7455D01*
X989267Y-7830D01*
X987517D01*
G01X985292Y-5330D02*
X985625Y-5413D01*
X985875Y-5622D01*
X986042Y-5872D01*
X986167Y-6205D01*
X986209Y-6580D01*
X986167Y-6955D01*
X986042Y-7288D01*
X985875Y-7538D01*
X985625Y-7747D01*
X985292Y-7830D01*
X984959Y-7747D01*
X984709Y-7538D01*
X984542Y-7288D01*
X984417Y-6955D01*
X984375Y-6580D01*
X984417Y-6205D01*
X984542Y-5872D01*
X984709Y-5622D01*
X984959Y-5413D01*
X985292Y-5330D01*
G01X983109Y-7330D02*
X982859Y-7622D01*
X982525Y-7788D01*
X982150Y-7830D01*
X981817Y-7788D01*
X981484Y-7580D01*
X981275Y-7330D01*
X981234Y-7080D01*
X981317Y-6788D01*
X981609Y-6580D01*
X981900Y-6497D01*
X982275D01*
G01X981900D02*
X981650Y-6372D01*
X981442Y-6163D01*
X981359Y-5913D01*
X981442Y-5663D01*
X981650Y-5455D01*
X982025Y-5330D01*
X982400Y-5372D01*
X982775Y-5538D01*
G01X999299Y-3755D02*
X1001799D01*
Y-2714D01*
X1001674Y-2380D01*
X1001507Y-2172D01*
X1001174Y-2089D01*
X1000841Y-2172D01*
X1000632Y-2422D01*
X1000507Y-2714D01*
Y-3755D01*
G01Y-2714D02*
X999299Y-2089D01*
G01X1001382Y-614D02*
X1001632Y-364D01*
X1001757Y-72D01*
X1001799Y261D01*
X1001716Y678D01*
X1001507Y970D01*
X1001257Y1053D01*
X1001007Y1011D01*
X1000799Y845D01*
X1000382Y11D01*
X1000091Y-364D01*
X999674Y-614D01*
X999299Y-697D01*
Y1053D01*
G01X1001799Y3278D02*
X1001716Y2945D01*
X1001507Y2695D01*
X1001257Y2528D01*
X1000924Y2403D01*
X1000549Y2361D01*
X1000174Y2403D01*
X999841Y2528D01*
X999591Y2695D01*
X999382Y2945D01*
X999299Y3278D01*
X999382Y3611D01*
X999591Y3861D01*
X999841Y4028D01*
X1000174Y4153D01*
X1000549Y4195D01*
X1000924Y4153D01*
X1001257Y4028D01*
X1001507Y3861D01*
X1001716Y3611D01*
X1001799Y3278D01*
G01X1001382Y5586D02*
X1001632Y5836D01*
X1001757Y6128D01*
X1001799Y6461D01*
X1001716Y6878D01*
X1001507Y7170D01*
X1001257Y7253D01*
X1001007Y7211D01*
X1000799Y7045D01*
X1000382Y6211D01*
X1000091Y5836D01*
X999674Y5586D01*
X999299Y5503D01*
Y7253D01*
G01X995429Y-3726D02*
X997929D01*
Y-2685D01*
X997804Y-2351D01*
X997637Y-2143D01*
X997304Y-2060D01*
X996971Y-2143D01*
X996762Y-2393D01*
X996637Y-2685D01*
Y-3726D01*
G01Y-2685D02*
X995429Y-2060D01*
G01X997512Y-585D02*
X997762Y-335D01*
X997887Y-43D01*
X997929Y290D01*
X997846Y707D01*
X997637Y999D01*
X997387Y1082D01*
X997137Y1040D01*
X996929Y874D01*
X996512Y40D01*
X996221Y-335D01*
X995804Y-585D01*
X995429Y-668D01*
Y1082D01*
G01X997929Y3307D02*
X997846Y2974D01*
X997637Y2724D01*
X997387Y2557D01*
X997054Y2432D01*
X996679Y2390D01*
X996304Y2432D01*
X995971Y2557D01*
X995721Y2724D01*
X995512Y2974D01*
X995429Y3307D01*
X995512Y3640D01*
X995721Y3890D01*
X995971Y4057D01*
X996304Y4182D01*
X996679Y4224D01*
X997054Y4182D01*
X997387Y4057D01*
X997637Y3890D01*
X997846Y3640D01*
X997929Y3307D01*
G01X995429Y6407D02*
X997929D01*
X997429Y5907D01*
G01X995429D02*
Y6907D01*
G01X1003388Y-3690D02*
X1005888D01*
Y-2649D01*
X1005763Y-2315D01*
X1005596Y-2107D01*
X1005263Y-2024D01*
X1004930Y-2107D01*
X1004721Y-2357D01*
X1004596Y-2649D01*
Y-3690D01*
G01Y-2649D02*
X1003388Y-2024D01*
G01Y243D02*
X1005888D01*
X1005388Y-257D01*
G01X1003388D02*
Y743D01*
G01X1003680Y2635D02*
X1003471Y2926D01*
X1003388Y3260D01*
X1003471Y3593D01*
X1003721Y3885D01*
X1004096Y4093D01*
X1004471Y4176D01*
X1004930D01*
X1005305Y4093D01*
X1005638Y3885D01*
X1005805Y3635D01*
X1005888Y3343D01*
X1005805Y3010D01*
X1005638Y2760D01*
X1005388Y2593D01*
X1005055Y2510D01*
X1004763Y2593D01*
X1004471Y2801D01*
X1004305Y3051D01*
X1004263Y3343D01*
X1004346Y3676D01*
X1004555Y3926D01*
X1004930Y4176D01*
G01X1003763Y5526D02*
X1003555Y5776D01*
X1003430Y6068D01*
X1003388Y6443D01*
X1003471Y6818D01*
X1003638Y7110D01*
X1003930Y7318D01*
X1004263Y7360D01*
X1004596Y7276D01*
X1004805Y7068D01*
X1004971Y6776D01*
X1005013Y6485D01*
X1004971Y6193D01*
X1004805Y5818D01*
X1005888Y5943D01*
Y7068D01*
G01X1007516Y-5177D02*
X1010016D01*
Y-4136D01*
X1009891Y-3802D01*
X1009724Y-3594D01*
X1009391Y-3511D01*
X1009058Y-3594D01*
X1008849Y-3844D01*
X1008724Y-4136D01*
Y-5177D01*
G01Y-4136D02*
X1007516Y-3511D01*
G01Y-1244D02*
X1010016D01*
X1009516Y-1744D01*
G01X1007516D02*
Y-744D01*
G01Y1856D02*
X1007558Y2148D01*
X1007683Y2481D01*
X1007891Y2689D01*
X1008183Y2773D01*
X1008474Y2689D01*
X1008724Y2439D01*
X1008849Y2064D01*
Y1648D01*
X1008933Y1398D01*
X1009141Y1189D01*
X1009433Y1106D01*
X1009724Y1231D01*
X1009933Y1523D01*
X1010016Y1856D01*
X1009933Y2189D01*
X1009724Y2481D01*
X1009433Y2606D01*
X1009141Y2523D01*
X1008933Y2314D01*
X1008849Y2064D01*
Y1648D01*
X1008724Y1273D01*
X1008474Y1023D01*
X1008183Y939D01*
X1007891Y1023D01*
X1007683Y1231D01*
X1007558Y1564D01*
X1007516Y1856D01*
G01Y4956D02*
X1007558Y5248D01*
X1007683Y5581D01*
X1007891Y5789D01*
X1008183Y5873D01*
X1008474Y5789D01*
X1008724Y5539D01*
X1008849Y5164D01*
Y4748D01*
X1008933Y4498D01*
X1009141Y4289D01*
X1009433Y4206D01*
X1009724Y4331D01*
X1009933Y4623D01*
X1010016Y4956D01*
X1009933Y5289D01*
X1009724Y5581D01*
X1009433Y5706D01*
X1009141Y5623D01*
X1008933Y5414D01*
X1008849Y5164D01*
Y4748D01*
X1008724Y4373D01*
X1008474Y4123D01*
X1008183Y4039D01*
X1007891Y4123D01*
X1007683Y4331D01*
X1007558Y4664D01*
X1007516Y4956D01*
G01X1015494Y8628D02*
Y11128D01*
X1014453D01*
X1014119Y11003D01*
X1013911Y10836D01*
X1013828Y10503D01*
X1013911Y10170D01*
X1014161Y9961D01*
X1014453Y9836D01*
X1015494D01*
G01X1014453D02*
X1013828Y8628D01*
G01X1011561D02*
Y11128D01*
X1012061Y10628D01*
G01Y8628D02*
X1011061D01*
G01X1009169Y8920D02*
X1008878Y8711D01*
X1008544Y8628D01*
X1008211Y8711D01*
X1007919Y8961D01*
X1007711Y9336D01*
X1007628Y9711D01*
Y10170D01*
X1007711Y10545D01*
X1007919Y10878D01*
X1008169Y11045D01*
X1008461Y11128D01*
X1008794Y11045D01*
X1009044Y10878D01*
X1009211Y10628D01*
X1009294Y10295D01*
X1009211Y10003D01*
X1009003Y9711D01*
X1008753Y9545D01*
X1008461Y9503D01*
X1008128Y9586D01*
X1007878Y9795D01*
X1007628Y10170D01*
G01X1006153Y9670D02*
X1005861Y9961D01*
X1005611Y10128D01*
X1005278Y10211D01*
X1004986Y10128D01*
X1004778Y9961D01*
X1004611Y9711D01*
X1004569Y9420D01*
X1004611Y9170D01*
X1004778Y8920D01*
X1005028Y8711D01*
X1005319Y8628D01*
X1005653Y8711D01*
X1005944Y8961D01*
X1006111Y9336D01*
X1006153Y9753D01*
X1006069Y10295D01*
X1005944Y10586D01*
X1005736Y10878D01*
X1005444Y11086D01*
X1005153Y11128D01*
X1004861Y11045D01*
X1004653Y10836D01*
G01X997811Y15405D02*
Y17905D01*
X996770D01*
X996436Y17780D01*
X996228Y17613D01*
X996145Y17280D01*
X996228Y16947D01*
X996478Y16738D01*
X996770Y16613D01*
X997811D01*
G01X996770D02*
X996145Y15405D01*
G01X993878D02*
Y17905D01*
X994378Y17405D01*
G01Y15405D02*
X993378D01*
G01X991486Y15697D02*
X991195Y15488D01*
X990861Y15405D01*
X990528Y15488D01*
X990236Y15738D01*
X990028Y16113D01*
X989945Y16488D01*
Y16947D01*
X990028Y17322D01*
X990236Y17655D01*
X990486Y17822D01*
X990778Y17905D01*
X991111Y17822D01*
X991361Y17655D01*
X991528Y17405D01*
X991611Y17072D01*
X991528Y16780D01*
X991320Y16488D01*
X991070Y16322D01*
X990778Y16280D01*
X990445Y16363D01*
X990195Y16572D01*
X989945Y16947D01*
G01X987678Y15405D02*
Y17905D01*
X988178Y17405D01*
G01Y15405D02*
X987178D01*
G01X1002228Y21605D02*
Y25605D01*
X1009628D01*
G01X997811Y19405D02*
Y21905D01*
X996770D01*
X996436Y21780D01*
X996228Y21613D01*
X996145Y21280D01*
X996228Y20947D01*
X996478Y20738D01*
X996770Y20613D01*
X997811D01*
G01X996770D02*
X996145Y19405D01*
G01X993878D02*
Y21905D01*
X994378Y21405D01*
G01Y19405D02*
X993378D01*
G01X991486Y19697D02*
X991195Y19488D01*
X990861Y19405D01*
X990528Y19488D01*
X990236Y19738D01*
X990028Y20113D01*
X989945Y20488D01*
Y20947D01*
X990028Y21322D01*
X990236Y21655D01*
X990486Y21822D01*
X990778Y21905D01*
X991111Y21822D01*
X991361Y21655D01*
X991528Y21405D01*
X991611Y21072D01*
X991528Y20780D01*
X991320Y20488D01*
X991070Y20322D01*
X990778Y20280D01*
X990445Y20363D01*
X990195Y20572D01*
X989945Y20947D01*
G01X987678Y21905D02*
X988011Y21822D01*
X988261Y21613D01*
X988428Y21363D01*
X988553Y21030D01*
X988595Y20655D01*
X988553Y20280D01*
X988428Y19947D01*
X988261Y19697D01*
X988011Y19488D01*
X987678Y19405D01*
X987345Y19488D01*
X987095Y19697D01*
X986928Y19947D01*
X986803Y20280D01*
X986761Y20655D01*
X986803Y21030D01*
X986928Y21363D01*
X987095Y21613D01*
X987345Y21822D01*
X987678Y21905D01*
G01X1002228Y25605D02*
Y29605D01*
X1009628D01*
G01X1000761Y8965D02*
X1003261D01*
Y10006D01*
X1003136Y10340D01*
X1002969Y10548D01*
X1002636Y10631D01*
X1002303Y10548D01*
X1002094Y10298D01*
X1001969Y10006D01*
Y8965D01*
G01Y10006D02*
X1000761Y10631D01*
G01Y12898D02*
X1003261D01*
X1002761Y12398D01*
G01X1000761D02*
Y13398D01*
G01Y15998D02*
X1000803Y16290D01*
X1000928Y16623D01*
X1001136Y16831D01*
X1001428Y16915D01*
X1001719Y16831D01*
X1001969Y16581D01*
X1002094Y16206D01*
Y15790D01*
X1002178Y15540D01*
X1002386Y15331D01*
X1002678Y15248D01*
X1002969Y15373D01*
X1003178Y15665D01*
X1003261Y15998D01*
X1003178Y16331D01*
X1002969Y16623D01*
X1002678Y16748D01*
X1002386Y16665D01*
X1002178Y16456D01*
X1002094Y16206D01*
Y15790D01*
X1001969Y15415D01*
X1001719Y15165D01*
X1001428Y15081D01*
X1001136Y15165D01*
X1000928Y15373D01*
X1000803Y15706D01*
X1000761Y15998D01*
G01X1001053Y18390D02*
X1000844Y18681D01*
X1000761Y19015D01*
X1000844Y19348D01*
X1001094Y19640D01*
X1001469Y19848D01*
X1001844Y19931D01*
X1002303D01*
X1002678Y19848D01*
X1003011Y19640D01*
X1003178Y19390D01*
X1003261Y19098D01*
X1003178Y18765D01*
X1003011Y18515D01*
X1002761Y18348D01*
X1002428Y18265D01*
X1002136Y18348D01*
X1001844Y18556D01*
X1001678Y18806D01*
X1001636Y19098D01*
X1001719Y19431D01*
X1001928Y19681D01*
X1002303Y19931D01*
G01X997765Y10858D02*
X998015Y10983D01*
X998307Y11066D01*
X998640D01*
X999015Y10941D01*
X999307Y10733D01*
X999515Y10483D01*
X999682Y10066D01*
X999724Y9691D01*
X999640Y9316D01*
X999515Y9066D01*
X999265Y8816D01*
X998974Y8649D01*
X998682Y8566D01*
X998390D01*
X998099Y8649D01*
X997849Y8774D01*
X997640Y8941D01*
G01X995582Y8566D02*
Y11066D01*
X996082Y10566D01*
G01Y8566D02*
X995082D01*
G01X993399Y8941D02*
X993149Y8733D01*
X992857Y8608D01*
X992482Y8566D01*
X992107Y8649D01*
X991815Y8816D01*
X991607Y9108D01*
X991565Y9441D01*
X991649Y9774D01*
X991857Y9983D01*
X992149Y10149D01*
X992440Y10191D01*
X992732Y10149D01*
X993107Y9983D01*
X992982Y11066D01*
X991857D01*
G01X990299Y9066D02*
X990049Y8774D01*
X989715Y8608D01*
X989340Y8566D01*
X989007Y8608D01*
X988674Y8816D01*
X988465Y9066D01*
X988424Y9316D01*
X988507Y9608D01*
X988799Y9816D01*
X989090Y9899D01*
X989465D01*
G01X989090D02*
X988840Y10024D01*
X988632Y10233D01*
X988549Y10483D01*
X988632Y10733D01*
X988840Y10941D01*
X989215Y11066D01*
X989590Y11024D01*
X989965Y10858D01*
G01X1002130Y50726D02*
X1004630D01*
Y51726D01*
X1004505Y52059D01*
X1004213Y52309D01*
X1003880Y52392D01*
X1003547Y52309D01*
X1003297Y52101D01*
X1003172Y51726D01*
Y50726D01*
G01X1004422Y55576D02*
X1004547Y55326D01*
X1004630Y55034D01*
Y54701D01*
X1004505Y54326D01*
X1004297Y54034D01*
X1004047Y53826D01*
X1003630Y53659D01*
X1003255Y53617D01*
X1002880Y53701D01*
X1002630Y53826D01*
X1002380Y54076D01*
X1002213Y54367D01*
X1002130Y54659D01*
Y54951D01*
X1002213Y55242D01*
X1002338Y55492D01*
X1002505Y55701D01*
G01X1004213Y56967D02*
X1004463Y57217D01*
X1004588Y57509D01*
X1004630Y57842D01*
X1004547Y58259D01*
X1004338Y58551D01*
X1004088Y58634D01*
X1003838Y58592D01*
X1003630Y58426D01*
X1003213Y57592D01*
X1002922Y57217D01*
X1002505Y56967D01*
X1002130Y56884D01*
Y58634D01*
G01X1004213Y60067D02*
X1004463Y60317D01*
X1004588Y60609D01*
X1004630Y60942D01*
X1004547Y61359D01*
X1004338Y61651D01*
X1004088Y61734D01*
X1003838Y61692D01*
X1003630Y61526D01*
X1003213Y60692D01*
X1002922Y60317D01*
X1002505Y60067D01*
X1002130Y59984D01*
Y61734D01*
G01X1002630Y63042D02*
X1002338Y63292D01*
X1002172Y63626D01*
X1002130Y64001D01*
X1002172Y64334D01*
X1002380Y64667D01*
X1002630Y64876D01*
X1002880Y64917D01*
X1003172Y64834D01*
X1003380Y64542D01*
X1003463Y64251D01*
Y63876D01*
G01Y64251D02*
X1003588Y64501D01*
X1003797Y64709D01*
X1004047Y64792D01*
X1004297Y64709D01*
X1004505Y64501D01*
X1004630Y64126D01*
X1004588Y63751D01*
X1004422Y63376D01*
G01X998100Y66267D02*
X1000600D01*
Y67308D01*
X1000475Y67642D01*
X1000308Y67850D01*
X999975Y67933D01*
X999642Y67850D01*
X999433Y67600D01*
X999308Y67308D01*
Y66267D01*
G01Y67308D02*
X998100Y67933D01*
G01X998600Y69283D02*
X998308Y69533D01*
X998142Y69867D01*
X998100Y70242D01*
X998142Y70575D01*
X998350Y70908D01*
X998600Y71117D01*
X998850Y71158D01*
X999142Y71075D01*
X999350Y70783D01*
X999433Y70492D01*
Y70117D01*
G01Y70492D02*
X999558Y70742D01*
X999767Y70950D01*
X1000017Y71033D01*
X1000267Y70950D01*
X1000475Y70742D01*
X1000600Y70367D01*
X1000558Y69992D01*
X1000392Y69617D01*
G01X998100Y73217D02*
X998642Y73300D01*
X999100Y73425D01*
X999517Y73592D01*
X999975Y73800D01*
X1000600Y74133D01*
Y72467D01*
G01Y76400D02*
X1000517Y76067D01*
X1000308Y75817D01*
X1000058Y75650D01*
X999725Y75525D01*
X999350Y75483D01*
X998975Y75525D01*
X998642Y75650D01*
X998392Y75817D01*
X998183Y76067D01*
X998100Y76400D01*
X998183Y76733D01*
X998392Y76983D01*
X998642Y77150D01*
X998975Y77275D01*
X999350Y77317D01*
X999725Y77275D01*
X1000058Y77150D01*
X1000308Y76983D01*
X1000517Y76733D01*
X1000600Y76400D01*
G01X998100Y79500D02*
X1000600D01*
X1000100Y79000D01*
G01X998100D02*
Y80000D01*
G01X993600Y66267D02*
X996100D01*
Y67308D01*
X995975Y67642D01*
X995808Y67850D01*
X995475Y67933D01*
X995142Y67850D01*
X994933Y67600D01*
X994808Y67308D01*
Y66267D01*
G01Y67308D02*
X993600Y67933D01*
G01X994100Y69283D02*
X993808Y69533D01*
X993642Y69867D01*
X993600Y70242D01*
X993642Y70575D01*
X993850Y70908D01*
X994100Y71117D01*
X994350Y71158D01*
X994642Y71075D01*
X994850Y70783D01*
X994933Y70492D01*
Y70117D01*
G01Y70492D02*
X995058Y70742D01*
X995267Y70950D01*
X995517Y71033D01*
X995767Y70950D01*
X995975Y70742D01*
X996100Y70367D01*
X996058Y69992D01*
X995892Y69617D01*
G01X993600Y73217D02*
X994142Y73300D01*
X994600Y73425D01*
X995017Y73592D01*
X995475Y73800D01*
X996100Y74133D01*
Y72467D01*
G01Y76400D02*
X996017Y76067D01*
X995808Y75817D01*
X995558Y75650D01*
X995225Y75525D01*
X994850Y75483D01*
X994475Y75525D01*
X994142Y75650D01*
X993892Y75817D01*
X993683Y76067D01*
X993600Y76400D01*
X993683Y76733D01*
X993892Y76983D01*
X994142Y77150D01*
X994475Y77275D01*
X994850Y77317D01*
X995225Y77275D01*
X995558Y77150D01*
X995808Y76983D01*
X996017Y76733D01*
X996100Y76400D01*
G01X995683Y78708D02*
X995933Y78958D01*
X996058Y79250D01*
X996100Y79583D01*
X996017Y80000D01*
X995808Y80292D01*
X995558Y80375D01*
X995308Y80333D01*
X995100Y80167D01*
X994683Y79333D01*
X994392Y78958D01*
X993975Y78708D01*
X993600Y78625D01*
Y80375D01*
G01X989100Y66267D02*
X991600D01*
Y67308D01*
X991475Y67642D01*
X991308Y67850D01*
X990975Y67933D01*
X990642Y67850D01*
X990433Y67600D01*
X990308Y67308D01*
Y66267D01*
G01Y67308D02*
X989100Y67933D01*
G01X989600Y69283D02*
X989308Y69533D01*
X989142Y69867D01*
X989100Y70242D01*
X989142Y70575D01*
X989350Y70908D01*
X989600Y71117D01*
X989850Y71158D01*
X990142Y71075D01*
X990350Y70783D01*
X990433Y70492D01*
Y70117D01*
G01Y70492D02*
X990558Y70742D01*
X990767Y70950D01*
X991017Y71033D01*
X991267Y70950D01*
X991475Y70742D01*
X991600Y70367D01*
X991558Y69992D01*
X991392Y69617D01*
G01X989100Y73217D02*
X989642Y73300D01*
X990100Y73425D01*
X990517Y73592D01*
X990975Y73800D01*
X991600Y74133D01*
Y72467D01*
G01Y76400D02*
X991517Y76067D01*
X991308Y75817D01*
X991058Y75650D01*
X990725Y75525D01*
X990350Y75483D01*
X989975Y75525D01*
X989642Y75650D01*
X989392Y75817D01*
X989183Y76067D01*
X989100Y76400D01*
X989183Y76733D01*
X989392Y76983D01*
X989642Y77150D01*
X989975Y77275D01*
X990350Y77317D01*
X990725Y77275D01*
X991058Y77150D01*
X991308Y76983D01*
X991517Y76733D01*
X991600Y76400D01*
G01X989600Y78583D02*
X989308Y78833D01*
X989142Y79167D01*
X989100Y79542D01*
X989142Y79875D01*
X989350Y80208D01*
X989600Y80417D01*
X989850Y80458D01*
X990142Y80375D01*
X990350Y80083D01*
X990433Y79792D01*
Y79417D01*
G01Y79792D02*
X990558Y80042D01*
X990767Y80250D01*
X991017Y80333D01*
X991267Y80250D01*
X991475Y80042D01*
X991600Y79667D01*
X991558Y79292D01*
X991392Y78917D01*
G01X984600Y66267D02*
X987100D01*
Y67308D01*
X986975Y67642D01*
X986808Y67850D01*
X986475Y67933D01*
X986142Y67850D01*
X985933Y67600D01*
X985808Y67308D01*
Y66267D01*
G01Y67308D02*
X984600Y67933D01*
G01X985100Y69283D02*
X984808Y69533D01*
X984642Y69867D01*
X984600Y70242D01*
X984642Y70575D01*
X984850Y70908D01*
X985100Y71117D01*
X985350Y71158D01*
X985642Y71075D01*
X985850Y70783D01*
X985933Y70492D01*
Y70117D01*
G01Y70492D02*
X986058Y70742D01*
X986267Y70950D01*
X986517Y71033D01*
X986767Y70950D01*
X986975Y70742D01*
X987100Y70367D01*
X987058Y69992D01*
X986892Y69617D01*
G01X984600Y73217D02*
X985142Y73300D01*
X985600Y73425D01*
X986017Y73592D01*
X986475Y73800D01*
X987100Y74133D01*
Y72467D01*
G01Y76400D02*
X987017Y76067D01*
X986808Y75817D01*
X986558Y75650D01*
X986225Y75525D01*
X985850Y75483D01*
X985475Y75525D01*
X985142Y75650D01*
X984892Y75817D01*
X984683Y76067D01*
X984600Y76400D01*
X984683Y76733D01*
X984892Y76983D01*
X985142Y77150D01*
X985475Y77275D01*
X985850Y77317D01*
X986225Y77275D01*
X986558Y77150D01*
X986808Y76983D01*
X987017Y76733D01*
X987100Y76400D01*
G01X984600Y80000D02*
X987100D01*
X985308Y78458D01*
Y80542D01*
G01X980100Y66267D02*
X982600D01*
Y67308D01*
X982475Y67642D01*
X982308Y67850D01*
X981975Y67933D01*
X981642Y67850D01*
X981433Y67600D01*
X981308Y67308D01*
Y66267D01*
G01Y67308D02*
X980100Y67933D01*
G01X980600Y69283D02*
X980308Y69533D01*
X980142Y69867D01*
X980100Y70242D01*
X980142Y70575D01*
X980350Y70908D01*
X980600Y71117D01*
X980850Y71158D01*
X981142Y71075D01*
X981350Y70783D01*
X981433Y70492D01*
Y70117D01*
G01Y70492D02*
X981558Y70742D01*
X981767Y70950D01*
X982017Y71033D01*
X982267Y70950D01*
X982475Y70742D01*
X982600Y70367D01*
X982558Y69992D01*
X982392Y69617D01*
G01X980100Y73217D02*
X980642Y73300D01*
X981100Y73425D01*
X981517Y73592D01*
X981975Y73800D01*
X982600Y74133D01*
Y72467D01*
G01Y76400D02*
X982517Y76067D01*
X982308Y75817D01*
X982058Y75650D01*
X981725Y75525D01*
X981350Y75483D01*
X980975Y75525D01*
X980642Y75650D01*
X980392Y75817D01*
X980183Y76067D01*
X980100Y76400D01*
X980183Y76733D01*
X980392Y76983D01*
X980642Y77150D01*
X980975Y77275D01*
X981350Y77317D01*
X981725Y77275D01*
X982058Y77150D01*
X982308Y76983D01*
X982517Y76733D01*
X982600Y76400D01*
G01X980475Y78583D02*
X980267Y78833D01*
X980142Y79125D01*
X980100Y79500D01*
X980183Y79875D01*
X980350Y80167D01*
X980642Y80375D01*
X980975Y80417D01*
X981308Y80333D01*
X981517Y80125D01*
X981683Y79833D01*
X981725Y79542D01*
X981683Y79250D01*
X981517Y78875D01*
X982600Y79000D01*
Y80125D01*
G01X1002600Y67817D02*
X1005100D01*
Y68858D01*
X1004975Y69192D01*
X1004808Y69400D01*
X1004475Y69483D01*
X1004142Y69400D01*
X1003933Y69150D01*
X1003808Y68858D01*
Y67817D01*
G01Y68858D02*
X1002600Y69483D01*
G01Y71750D02*
X1002642Y72042D01*
X1002767Y72375D01*
X1002975Y72583D01*
X1003267Y72667D01*
X1003558Y72583D01*
X1003808Y72333D01*
X1003933Y71958D01*
Y71542D01*
X1004017Y71292D01*
X1004225Y71083D01*
X1004517Y71000D01*
X1004808Y71125D01*
X1005017Y71417D01*
X1005100Y71750D01*
X1005017Y72083D01*
X1004808Y72375D01*
X1004517Y72500D01*
X1004225Y72417D01*
X1004017Y72208D01*
X1003933Y71958D01*
Y71542D01*
X1003808Y71167D01*
X1003558Y70917D01*
X1003267Y70833D01*
X1002975Y70917D01*
X1002767Y71125D01*
X1002642Y71458D01*
X1002600Y71750D01*
G01X1004683Y74058D02*
X1004933Y74308D01*
X1005058Y74600D01*
X1005100Y74933D01*
X1005017Y75350D01*
X1004808Y75642D01*
X1004558Y75725D01*
X1004308Y75683D01*
X1004100Y75517D01*
X1003683Y74683D01*
X1003392Y74308D01*
X1002975Y74058D01*
X1002600Y73975D01*
Y75725D01*
G01Y77950D02*
X1005100D01*
X1004600Y77450D01*
G01X1002600D02*
Y78450D01*
G01X1007100Y67817D02*
X1009600D01*
Y68858D01*
X1009475Y69192D01*
X1009308Y69400D01*
X1008975Y69483D01*
X1008642Y69400D01*
X1008433Y69150D01*
X1008308Y68858D01*
Y67817D01*
G01Y68858D02*
X1007100Y69483D01*
G01Y71750D02*
X1007142Y72042D01*
X1007267Y72375D01*
X1007475Y72583D01*
X1007767Y72667D01*
X1008058Y72583D01*
X1008308Y72333D01*
X1008433Y71958D01*
Y71542D01*
X1008517Y71292D01*
X1008725Y71083D01*
X1009017Y71000D01*
X1009308Y71125D01*
X1009517Y71417D01*
X1009600Y71750D01*
X1009517Y72083D01*
X1009308Y72375D01*
X1009017Y72500D01*
X1008725Y72417D01*
X1008517Y72208D01*
X1008433Y71958D01*
Y71542D01*
X1008308Y71167D01*
X1008058Y70917D01*
X1007767Y70833D01*
X1007475Y70917D01*
X1007267Y71125D01*
X1007142Y71458D01*
X1007100Y71750D01*
G01Y74850D02*
X1009600D01*
X1009100Y74350D01*
G01X1007100D02*
Y75350D01*
G01X1007392Y77242D02*
X1007183Y77533D01*
X1007100Y77867D01*
X1007183Y78200D01*
X1007433Y78492D01*
X1007808Y78700D01*
X1008183Y78783D01*
X1008642D01*
X1009017Y78700D01*
X1009350Y78492D01*
X1009517Y78242D01*
X1009600Y77950D01*
X1009517Y77617D01*
X1009350Y77367D01*
X1009100Y77200D01*
X1008767Y77117D01*
X1008475Y77200D01*
X1008183Y77408D01*
X1008017Y77658D01*
X1007975Y77950D01*
X1008058Y78283D01*
X1008267Y78533D01*
X1008642Y78783D01*
G01X999679Y60590D02*
Y63090D01*
X998638D01*
X998304Y62965D01*
X998096Y62798D01*
X998013Y62465D01*
X998096Y62132D01*
X998346Y61923D01*
X998638Y61798D01*
X999679D01*
G01X998638D02*
X998013Y60590D01*
G01X996538Y61632D02*
X996246Y61923D01*
X995996Y62090D01*
X995663Y62173D01*
X995371Y62090D01*
X995163Y61923D01*
X994996Y61673D01*
X994954Y61382D01*
X994996Y61132D01*
X995163Y60882D01*
X995413Y60673D01*
X995704Y60590D01*
X996038Y60673D01*
X996329Y60923D01*
X996496Y61298D01*
X996538Y61715D01*
X996454Y62257D01*
X996329Y62548D01*
X996121Y62840D01*
X995829Y63048D01*
X995538Y63090D01*
X995246Y63007D01*
X995038Y62798D01*
G01X993354Y60882D02*
X993063Y60673D01*
X992729Y60590D01*
X992396Y60673D01*
X992104Y60923D01*
X991896Y61298D01*
X991813Y61673D01*
Y62132D01*
X991896Y62507D01*
X992104Y62840D01*
X992354Y63007D01*
X992646Y63090D01*
X992979Y63007D01*
X993229Y62840D01*
X993396Y62590D01*
X993479Y62257D01*
X993396Y61965D01*
X993188Y61673D01*
X992938Y61507D01*
X992646Y61465D01*
X992313Y61548D01*
X992063Y61757D01*
X991813Y62132D01*
G01X990463Y61090D02*
X990213Y60798D01*
X989879Y60632D01*
X989504Y60590D01*
X989171Y60632D01*
X988838Y60840D01*
X988629Y61090D01*
X988588Y61340D01*
X988671Y61632D01*
X988963Y61840D01*
X989254Y61923D01*
X989629D01*
G01X989254D02*
X989004Y62048D01*
X988796Y62257D01*
X988713Y62507D01*
X988796Y62757D01*
X989004Y62965D01*
X989379Y63090D01*
X989754Y63048D01*
X990129Y62882D01*
G01X1013291Y49207D02*
X1013541Y49332D01*
X1013833Y49415D01*
X1014166D01*
X1014541Y49290D01*
X1014833Y49082D01*
X1015041Y48832D01*
X1015208Y48415D01*
X1015250Y48040D01*
X1015166Y47665D01*
X1015041Y47415D01*
X1014791Y47165D01*
X1014500Y46998D01*
X1014208Y46915D01*
X1013916D01*
X1013625Y46998D01*
X1013375Y47123D01*
X1013166Y47290D01*
G01X1011108Y46915D02*
Y49415D01*
X1011608Y48915D01*
G01Y46915D02*
X1010608D01*
G01X1008925Y47290D02*
X1008675Y47082D01*
X1008383Y46957D01*
X1008008Y46915D01*
X1007633Y46998D01*
X1007341Y47165D01*
X1007133Y47457D01*
X1007091Y47790D01*
X1007175Y48123D01*
X1007383Y48332D01*
X1007675Y48498D01*
X1007966Y48540D01*
X1008258Y48498D01*
X1008633Y48332D01*
X1008508Y49415D01*
X1007383D01*
G01X1004908Y46915D02*
Y49415D01*
X1005408Y48915D01*
G01Y46915D02*
X1004408D01*
G01X998016Y51800D02*
X998058Y51467D01*
X998224Y51175D01*
X998474Y50925D01*
X998766Y50758D01*
X999099Y50675D01*
X999433D01*
X999766Y50758D01*
X1000058Y50925D01*
X1000308Y51175D01*
X1000474Y51467D01*
X1000516Y51800D01*
X1000474Y52133D01*
X1000308Y52425D01*
X1000058Y52675D01*
X999766Y52842D01*
X999433Y52925D01*
X999099D01*
X998766Y52842D01*
X998474Y52675D01*
X998224Y52425D01*
X998058Y52133D01*
X998016Y51800D01*
G01X998683Y52133D02*
X998016Y52633D01*
G01Y55400D02*
X1000516D01*
X998724Y53858D01*
Y55942D01*
G01X1000516Y58000D02*
X1000433Y57667D01*
X1000224Y57417D01*
X999974Y57250D01*
X999641Y57125D01*
X999266Y57083D01*
X998891Y57125D01*
X998558Y57250D01*
X998308Y57417D01*
X998099Y57667D01*
X998016Y58000D01*
X998099Y58333D01*
X998308Y58583D01*
X998558Y58750D01*
X998891Y58875D01*
X999266Y58917D01*
X999641Y58875D01*
X999974Y58750D01*
X1000224Y58583D01*
X1000433Y58333D01*
X1000516Y58000D01*
G01X978661Y82017D02*
X981161D01*
Y83058D01*
X981036Y83392D01*
X980869Y83600D01*
X980536Y83683D01*
X980203Y83600D01*
X979994Y83350D01*
X979869Y83058D01*
Y82017D01*
G01Y83058D02*
X978661Y83683D01*
G01Y85950D02*
X978703Y86242D01*
X978828Y86575D01*
X979036Y86783D01*
X979328Y86867D01*
X979619Y86783D01*
X979869Y86533D01*
X979994Y86158D01*
Y85742D01*
X980078Y85492D01*
X980286Y85283D01*
X980578Y85200D01*
X980869Y85325D01*
X981078Y85617D01*
X981161Y85950D01*
X981078Y86283D01*
X980869Y86575D01*
X980578Y86700D01*
X980286Y86617D01*
X980078Y86408D01*
X979994Y86158D01*
Y85742D01*
X979869Y85367D01*
X979619Y85117D01*
X979328Y85033D01*
X979036Y85117D01*
X978828Y85325D01*
X978703Y85658D01*
X978661Y85950D01*
G01X980744Y88258D02*
X980994Y88508D01*
X981119Y88800D01*
X981161Y89133D01*
X981078Y89550D01*
X980869Y89842D01*
X980619Y89925D01*
X980369Y89883D01*
X980161Y89717D01*
X979744Y88883D01*
X979453Y88508D01*
X979036Y88258D01*
X978661Y88175D01*
Y89925D01*
G01Y92150D02*
X978703Y92442D01*
X978828Y92775D01*
X979036Y92983D01*
X979328Y93067D01*
X979619Y92983D01*
X979869Y92733D01*
X979994Y92358D01*
Y91942D01*
X980078Y91692D01*
X980286Y91483D01*
X980578Y91400D01*
X980869Y91525D01*
X981078Y91817D01*
X981161Y92150D01*
X981078Y92483D01*
X980869Y92775D01*
X980578Y92900D01*
X980286Y92817D01*
X980078Y92608D01*
X979994Y92358D01*
Y91942D01*
X979869Y91567D01*
X979619Y91317D01*
X979328Y91233D01*
X979036Y91317D01*
X978828Y91525D01*
X978703Y91858D01*
X978661Y92150D01*
G01X983161Y82017D02*
X985661D01*
Y83058D01*
X985536Y83392D01*
X985369Y83600D01*
X985036Y83683D01*
X984703Y83600D01*
X984494Y83350D01*
X984369Y83058D01*
Y82017D01*
G01Y83058D02*
X983161Y83683D01*
G01Y85950D02*
X983203Y86242D01*
X983328Y86575D01*
X983536Y86783D01*
X983828Y86867D01*
X984119Y86783D01*
X984369Y86533D01*
X984494Y86158D01*
Y85742D01*
X984578Y85492D01*
X984786Y85283D01*
X985078Y85200D01*
X985369Y85325D01*
X985578Y85617D01*
X985661Y85950D01*
X985578Y86283D01*
X985369Y86575D01*
X985078Y86700D01*
X984786Y86617D01*
X984578Y86408D01*
X984494Y86158D01*
Y85742D01*
X984369Y85367D01*
X984119Y85117D01*
X983828Y85033D01*
X983536Y85117D01*
X983328Y85325D01*
X983203Y85658D01*
X983161Y85950D01*
G01X985244Y88258D02*
X985494Y88508D01*
X985619Y88800D01*
X985661Y89133D01*
X985578Y89550D01*
X985369Y89842D01*
X985119Y89925D01*
X984869Y89883D01*
X984661Y89717D01*
X984244Y88883D01*
X983953Y88508D01*
X983536Y88258D01*
X983161Y88175D01*
Y89925D01*
G01Y92067D02*
X983703Y92150D01*
X984161Y92275D01*
X984578Y92442D01*
X985036Y92650D01*
X985661Y92983D01*
Y91317D01*
G01X987661Y82017D02*
X990161D01*
Y83058D01*
X990036Y83392D01*
X989869Y83600D01*
X989536Y83683D01*
X989203Y83600D01*
X988994Y83350D01*
X988869Y83058D01*
Y82017D01*
G01Y83058D02*
X987661Y83683D01*
G01Y85950D02*
X987703Y86242D01*
X987828Y86575D01*
X988036Y86783D01*
X988328Y86867D01*
X988619Y86783D01*
X988869Y86533D01*
X988994Y86158D01*
Y85742D01*
X989078Y85492D01*
X989286Y85283D01*
X989578Y85200D01*
X989869Y85325D01*
X990078Y85617D01*
X990161Y85950D01*
X990078Y86283D01*
X989869Y86575D01*
X989578Y86700D01*
X989286Y86617D01*
X989078Y86408D01*
X988994Y86158D01*
Y85742D01*
X988869Y85367D01*
X988619Y85117D01*
X988328Y85033D01*
X988036Y85117D01*
X987828Y85325D01*
X987703Y85658D01*
X987661Y85950D01*
G01X989744Y88258D02*
X989994Y88508D01*
X990119Y88800D01*
X990161Y89133D01*
X990078Y89550D01*
X989869Y89842D01*
X989619Y89925D01*
X989369Y89883D01*
X989161Y89717D01*
X988744Y88883D01*
X988453Y88508D01*
X988036Y88258D01*
X987661Y88175D01*
Y89925D01*
G01X988703Y91358D02*
X988994Y91650D01*
X989161Y91900D01*
X989244Y92233D01*
X989161Y92525D01*
X988994Y92733D01*
X988744Y92900D01*
X988453Y92942D01*
X988203Y92900D01*
X987953Y92733D01*
X987744Y92483D01*
X987661Y92192D01*
X987744Y91858D01*
X987994Y91567D01*
X988369Y91400D01*
X988786Y91358D01*
X989328Y91442D01*
X989619Y91567D01*
X989911Y91775D01*
X990119Y92067D01*
X990161Y92358D01*
X990078Y92650D01*
X989869Y92858D01*
G01X992161Y82017D02*
X994661D01*
Y83058D01*
X994536Y83392D01*
X994369Y83600D01*
X994036Y83683D01*
X993703Y83600D01*
X993494Y83350D01*
X993369Y83058D01*
Y82017D01*
G01Y83058D02*
X992161Y83683D01*
G01Y85950D02*
X992203Y86242D01*
X992328Y86575D01*
X992536Y86783D01*
X992828Y86867D01*
X993119Y86783D01*
X993369Y86533D01*
X993494Y86158D01*
Y85742D01*
X993578Y85492D01*
X993786Y85283D01*
X994078Y85200D01*
X994369Y85325D01*
X994578Y85617D01*
X994661Y85950D01*
X994578Y86283D01*
X994369Y86575D01*
X994078Y86700D01*
X993786Y86617D01*
X993578Y86408D01*
X993494Y86158D01*
Y85742D01*
X993369Y85367D01*
X993119Y85117D01*
X992828Y85033D01*
X992536Y85117D01*
X992328Y85325D01*
X992203Y85658D01*
X992161Y85950D01*
G01X994244Y88258D02*
X994494Y88508D01*
X994619Y88800D01*
X994661Y89133D01*
X994578Y89550D01*
X994369Y89842D01*
X994119Y89925D01*
X993869Y89883D01*
X993661Y89717D01*
X993244Y88883D01*
X992953Y88508D01*
X992536Y88258D01*
X992161Y88175D01*
Y89925D01*
G01X992536Y91233D02*
X992328Y91483D01*
X992203Y91775D01*
X992161Y92150D01*
X992244Y92525D01*
X992411Y92817D01*
X992703Y93025D01*
X993036Y93067D01*
X993369Y92983D01*
X993578Y92775D01*
X993744Y92483D01*
X993786Y92192D01*
X993744Y91900D01*
X993578Y91525D01*
X994661Y91650D01*
Y92775D01*
G01X996661Y82017D02*
X999161D01*
Y83058D01*
X999036Y83392D01*
X998869Y83600D01*
X998536Y83683D01*
X998203Y83600D01*
X997994Y83350D01*
X997869Y83058D01*
Y82017D01*
G01Y83058D02*
X996661Y83683D01*
G01Y85867D02*
X997203Y85950D01*
X997661Y86075D01*
X998078Y86242D01*
X998536Y86450D01*
X999161Y86783D01*
Y85117D01*
G01X996953Y88342D02*
X996744Y88633D01*
X996661Y88967D01*
X996744Y89300D01*
X996994Y89592D01*
X997369Y89800D01*
X997744Y89883D01*
X998203D01*
X998578Y89800D01*
X998911Y89592D01*
X999078Y89342D01*
X999161Y89050D01*
X999078Y88717D01*
X998911Y88467D01*
X998661Y88300D01*
X998328Y88217D01*
X998036Y88300D01*
X997744Y88508D01*
X997578Y88758D01*
X997536Y89050D01*
X997619Y89383D01*
X997828Y89633D01*
X998203Y89883D01*
G01X999161Y92150D02*
X999078Y91817D01*
X998869Y91567D01*
X998619Y91400D01*
X998286Y91275D01*
X997911Y91233D01*
X997536Y91275D01*
X997203Y91400D01*
X996953Y91567D01*
X996744Y91817D01*
X996661Y92150D01*
X996744Y92483D01*
X996953Y92733D01*
X997203Y92900D01*
X997536Y93025D01*
X997911Y93067D01*
X998286Y93025D01*
X998619Y92900D01*
X998869Y92733D01*
X999078Y92483D01*
X999161Y92150D01*
G01X1001161Y82017D02*
X1003661D01*
Y83058D01*
X1003536Y83392D01*
X1003369Y83600D01*
X1003036Y83683D01*
X1002703Y83600D01*
X1002494Y83350D01*
X1002369Y83058D01*
Y82017D01*
G01Y83058D02*
X1001161Y83683D01*
G01Y85867D02*
X1001703Y85950D01*
X1002161Y86075D01*
X1002578Y86242D01*
X1003036Y86450D01*
X1003661Y86783D01*
Y85117D01*
G01X1001161Y89050D02*
X1001203Y89342D01*
X1001328Y89675D01*
X1001536Y89883D01*
X1001828Y89967D01*
X1002119Y89883D01*
X1002369Y89633D01*
X1002494Y89258D01*
Y88842D01*
X1002578Y88592D01*
X1002786Y88383D01*
X1003078Y88300D01*
X1003369Y88425D01*
X1003578Y88717D01*
X1003661Y89050D01*
X1003578Y89383D01*
X1003369Y89675D01*
X1003078Y89800D01*
X1002786Y89717D01*
X1002578Y89508D01*
X1002494Y89258D01*
Y88842D01*
X1002369Y88467D01*
X1002119Y88217D01*
X1001828Y88133D01*
X1001536Y88217D01*
X1001328Y88425D01*
X1001203Y88758D01*
X1001161Y89050D01*
G01X1001453Y91442D02*
X1001244Y91733D01*
X1001161Y92067D01*
X1001244Y92400D01*
X1001494Y92692D01*
X1001869Y92900D01*
X1002244Y92983D01*
X1002703D01*
X1003078Y92900D01*
X1003411Y92692D01*
X1003578Y92442D01*
X1003661Y92150D01*
X1003578Y91817D01*
X1003411Y91567D01*
X1003161Y91400D01*
X1002828Y91317D01*
X1002536Y91400D01*
X1002244Y91608D01*
X1002078Y91858D01*
X1002036Y92150D01*
X1002119Y92483D01*
X1002328Y92733D01*
X1002703Y92983D01*
G01X1005661Y82017D02*
X1008161D01*
Y83058D01*
X1008036Y83392D01*
X1007869Y83600D01*
X1007536Y83683D01*
X1007203Y83600D01*
X1006994Y83350D01*
X1006869Y83058D01*
Y82017D01*
G01Y83058D02*
X1005661Y83683D01*
G01Y85867D02*
X1006203Y85950D01*
X1006661Y86075D01*
X1007078Y86242D01*
X1007536Y86450D01*
X1008161Y86783D01*
Y85117D01*
G01X1005661Y89050D02*
X1005703Y89342D01*
X1005828Y89675D01*
X1006036Y89883D01*
X1006328Y89967D01*
X1006619Y89883D01*
X1006869Y89633D01*
X1006994Y89258D01*
Y88842D01*
X1007078Y88592D01*
X1007286Y88383D01*
X1007578Y88300D01*
X1007869Y88425D01*
X1008078Y88717D01*
X1008161Y89050D01*
X1008078Y89383D01*
X1007869Y89675D01*
X1007578Y89800D01*
X1007286Y89717D01*
X1007078Y89508D01*
X1006994Y89258D01*
Y88842D01*
X1006869Y88467D01*
X1006619Y88217D01*
X1006328Y88133D01*
X1006036Y88217D01*
X1005828Y88425D01*
X1005703Y88758D01*
X1005661Y89050D01*
G01Y92150D02*
X1005703Y92442D01*
X1005828Y92775D01*
X1006036Y92983D01*
X1006328Y93067D01*
X1006619Y92983D01*
X1006869Y92733D01*
X1006994Y92358D01*
Y91942D01*
X1007078Y91692D01*
X1007286Y91483D01*
X1007578Y91400D01*
X1007869Y91525D01*
X1008078Y91817D01*
X1008161Y92150D01*
X1008078Y92483D01*
X1007869Y92775D01*
X1007578Y92900D01*
X1007286Y92817D01*
X1007078Y92608D01*
X1006994Y92358D01*
Y91942D01*
X1006869Y91567D01*
X1006619Y91317D01*
X1006328Y91233D01*
X1006036Y91317D01*
X1005828Y91525D01*
X1005703Y91858D01*
X1005661Y92150D01*
G01X992552Y99100D02*
X988552D01*
Y106500D01*
G01Y99100D02*
X984552D01*
Y106500D01*
G01X1005100Y99100D02*
X1001100D01*
Y106500D01*
G01X1001000Y99100D02*
X997000D01*
Y106500D01*
G01X992700D02*
X996700D01*
Y99100D01*
G01X1006852Y126821D02*
X1007102Y126946D01*
X1007394Y127029D01*
X1007727D01*
X1008102Y126904D01*
X1008394Y126696D01*
X1008602Y126446D01*
X1008769Y126029D01*
X1008811Y125654D01*
X1008727Y125279D01*
X1008602Y125029D01*
X1008352Y124779D01*
X1008061Y124612D01*
X1007769Y124529D01*
X1007477D01*
X1007186Y124612D01*
X1006936Y124737D01*
X1006727Y124904D01*
G01X1005461Y125571D02*
X1005169Y125862D01*
X1004919Y126029D01*
X1004586Y126112D01*
X1004294Y126029D01*
X1004086Y125862D01*
X1003919Y125612D01*
X1003877Y125321D01*
X1003919Y125071D01*
X1004086Y124821D01*
X1004336Y124612D01*
X1004627Y124529D01*
X1004961Y124612D01*
X1005252Y124862D01*
X1005419Y125237D01*
X1005461Y125654D01*
X1005377Y126196D01*
X1005252Y126487D01*
X1005044Y126779D01*
X1004752Y126987D01*
X1004461Y127029D01*
X1004169Y126946D01*
X1003961Y126737D01*
G01X1001569Y127029D02*
X1001902Y126946D01*
X1002152Y126737D01*
X1002319Y126487D01*
X1002444Y126154D01*
X1002486Y125779D01*
X1002444Y125404D01*
X1002319Y125071D01*
X1002152Y124821D01*
X1001902Y124612D01*
X1001569Y124529D01*
X1001236Y124612D01*
X1000986Y124821D01*
X1000819Y125071D01*
X1000694Y125404D01*
X1000652Y125779D01*
X1000694Y126154D01*
X1000819Y126487D01*
X1000986Y126737D01*
X1001236Y126946D01*
X1001569Y127029D01*
G01X999386Y124904D02*
X999136Y124696D01*
X998844Y124571D01*
X998469Y124529D01*
X998094Y124612D01*
X997802Y124779D01*
X997594Y125071D01*
X997552Y125404D01*
X997636Y125737D01*
X997844Y125946D01*
X998136Y126112D01*
X998427Y126154D01*
X998719Y126112D01*
X999094Y125946D01*
X998969Y127029D01*
X997844D01*
G01X979616Y134750D02*
X979741Y134500D01*
X979824Y134208D01*
Y133875D01*
X979699Y133500D01*
X979491Y133208D01*
X979241Y133000D01*
X978824Y132833D01*
X978449Y132791D01*
X978074Y132875D01*
X977824Y133000D01*
X977574Y133250D01*
X977407Y133541D01*
X977324Y133833D01*
Y134125D01*
X977407Y134416D01*
X977532Y134666D01*
X977699Y134875D01*
G01X977324Y137433D02*
X979824D01*
X978032Y135891D01*
Y137975D01*
G01X977324Y140033D02*
X977366Y140325D01*
X977491Y140658D01*
X977699Y140866D01*
X977991Y140950D01*
X978282Y140866D01*
X978532Y140616D01*
X978657Y140241D01*
Y139825D01*
X978741Y139575D01*
X978949Y139366D01*
X979241Y139283D01*
X979532Y139408D01*
X979741Y139700D01*
X979824Y140033D01*
X979741Y140366D01*
X979532Y140658D01*
X979241Y140783D01*
X978949Y140700D01*
X978741Y140491D01*
X978657Y140241D01*
Y139825D01*
X978532Y139450D01*
X978282Y139200D01*
X977991Y139116D01*
X977699Y139200D01*
X977491Y139408D01*
X977366Y139741D01*
X977324Y140033D01*
G01Y143050D02*
X977866Y143133D01*
X978324Y143258D01*
X978741Y143425D01*
X979199Y143633D01*
X979824Y143966D01*
Y142300D01*
G01X980001Y121266D02*
X980126Y121016D01*
X980209Y120724D01*
Y120391D01*
X980084Y120016D01*
X979876Y119724D01*
X979626Y119516D01*
X979209Y119349D01*
X978834Y119307D01*
X978459Y119391D01*
X978209Y119516D01*
X977959Y119766D01*
X977792Y120057D01*
X977709Y120349D01*
Y120641D01*
X977792Y120932D01*
X977917Y121182D01*
X978084Y121391D01*
G01X977709Y123949D02*
X980209D01*
X978417Y122407D01*
Y124491D01*
G01X977709Y126466D02*
X978251Y126549D01*
X978709Y126674D01*
X979126Y126841D01*
X979584Y127049D01*
X980209Y127382D01*
Y125716D01*
G01X977709Y129649D02*
X980209D01*
X979709Y129149D01*
G01X977709D02*
Y130149D01*
G01X988023Y119430D02*
X988148Y119180D01*
X988231Y118888D01*
Y118555D01*
X988106Y118180D01*
X987898Y117888D01*
X987648Y117680D01*
X987231Y117513D01*
X986856Y117471D01*
X986481Y117555D01*
X986231Y117680D01*
X985981Y117930D01*
X985814Y118221D01*
X985731Y118513D01*
Y118805D01*
X985814Y119096D01*
X985939Y119346D01*
X986106Y119555D01*
G01X985731Y122113D02*
X988231D01*
X986439Y120571D01*
Y122655D01*
G01X986773Y123921D02*
X987064Y124213D01*
X987231Y124463D01*
X987314Y124796D01*
X987231Y125088D01*
X987064Y125296D01*
X986814Y125463D01*
X986523Y125505D01*
X986273Y125463D01*
X986023Y125296D01*
X985814Y125046D01*
X985731Y124755D01*
X985814Y124421D01*
X986064Y124130D01*
X986439Y123963D01*
X986856Y123921D01*
X987398Y124005D01*
X987689Y124130D01*
X987981Y124338D01*
X988189Y124630D01*
X988231Y124921D01*
X988148Y125213D01*
X987939Y125421D01*
G01X986023Y127105D02*
X985814Y127396D01*
X985731Y127730D01*
X985814Y128063D01*
X986064Y128355D01*
X986439Y128563D01*
X986814Y128646D01*
X987273D01*
X987648Y128563D01*
X987981Y128355D01*
X988148Y128105D01*
X988231Y127813D01*
X988148Y127480D01*
X987981Y127230D01*
X987731Y127063D01*
X987398Y126980D01*
X987106Y127063D01*
X986814Y127271D01*
X986648Y127521D01*
X986606Y127813D01*
X986689Y128146D01*
X986898Y128396D01*
X987273Y128646D01*
G01X988830Y136989D02*
X986330D01*
G01X988830Y136031D02*
Y137947D01*
G01X986330Y139256D02*
X988830D01*
Y140256D01*
X988705Y140589D01*
X988413Y140839D01*
X988080Y140922D01*
X987747Y140839D01*
X987497Y140631D01*
X987372Y140256D01*
Y139256D01*
G01X988413Y142397D02*
X988663Y142647D01*
X988788Y142939D01*
X988830Y143272D01*
X988747Y143689D01*
X988538Y143981D01*
X988288Y144064D01*
X988038Y144022D01*
X987830Y143856D01*
X987413Y143022D01*
X987122Y142647D01*
X986705Y142397D01*
X986330Y142314D01*
Y144064D01*
G01Y146289D02*
X986372Y146581D01*
X986497Y146914D01*
X986705Y147122D01*
X986997Y147206D01*
X987288Y147122D01*
X987538Y146872D01*
X987663Y146497D01*
Y146081D01*
X987747Y145831D01*
X987955Y145622D01*
X988247Y145539D01*
X988538Y145664D01*
X988747Y145956D01*
X988830Y146289D01*
X988747Y146622D01*
X988538Y146914D01*
X988247Y147039D01*
X987955Y146956D01*
X987747Y146747D01*
X987663Y146497D01*
Y146081D01*
X987538Y145706D01*
X987288Y145456D01*
X986997Y145372D01*
X986705Y145456D01*
X986497Y145664D01*
X986372Y145997D01*
X986330Y146289D01*
G01X988830Y149389D02*
X988747Y149056D01*
X988538Y148806D01*
X988288Y148639D01*
X987955Y148514D01*
X987580Y148472D01*
X987205Y148514D01*
X986872Y148639D01*
X986622Y148806D01*
X986413Y149056D01*
X986330Y149389D01*
X986413Y149722D01*
X986622Y149972D01*
X986872Y150139D01*
X987205Y150264D01*
X987580Y150306D01*
X987955Y150264D01*
X988288Y150139D01*
X988538Y149972D01*
X988747Y149722D01*
X988830Y149389D01*
G01X995198Y131478D02*
X992698D01*
G01X995198Y130520D02*
Y132436D01*
G01X992698Y133745D02*
X995198D01*
Y134745D01*
X995073Y135078D01*
X994781Y135328D01*
X994448Y135411D01*
X994115Y135328D01*
X993865Y135120D01*
X993740Y134745D01*
Y133745D01*
G01X994781Y136886D02*
X995031Y137136D01*
X995156Y137428D01*
X995198Y137761D01*
X995115Y138178D01*
X994906Y138470D01*
X994656Y138553D01*
X994406Y138511D01*
X994198Y138345D01*
X993781Y137511D01*
X993490Y137136D01*
X993073Y136886D01*
X992698Y136803D01*
Y138553D01*
G01Y140695D02*
X993240Y140778D01*
X993698Y140903D01*
X994115Y141070D01*
X994573Y141278D01*
X995198Y141611D01*
Y139945D01*
G01X992990Y143170D02*
X992781Y143461D01*
X992698Y143795D01*
X992781Y144128D01*
X993031Y144420D01*
X993406Y144628D01*
X993781Y144711D01*
X994240D01*
X994615Y144628D01*
X994948Y144420D01*
X995115Y144170D01*
X995198Y143878D01*
X995115Y143545D01*
X994948Y143295D01*
X994698Y143128D01*
X994365Y143045D01*
X994073Y143128D01*
X993781Y143336D01*
X993615Y143586D01*
X993573Y143878D01*
X993656Y144211D01*
X993865Y144461D01*
X994240Y144711D01*
G01X992409Y117127D02*
X989909D01*
G01X992409Y116169D02*
Y118085D01*
G01X989909Y119394D02*
X992409D01*
Y120394D01*
X992284Y120727D01*
X991992Y120977D01*
X991659Y121060D01*
X991326Y120977D01*
X991076Y120769D01*
X990951Y120394D01*
Y119394D01*
G01X991992Y122535D02*
X992242Y122785D01*
X992367Y123077D01*
X992409Y123410D01*
X992326Y123827D01*
X992117Y124119D01*
X991867Y124202D01*
X991617Y124160D01*
X991409Y123994D01*
X990992Y123160D01*
X990701Y122785D01*
X990284Y122535D01*
X989909Y122452D01*
Y124202D01*
G01X992409Y126427D02*
X992326Y126094D01*
X992117Y125844D01*
X991867Y125677D01*
X991534Y125552D01*
X991159Y125510D01*
X990784Y125552D01*
X990451Y125677D01*
X990201Y125844D01*
X989992Y126094D01*
X989909Y126427D01*
X989992Y126760D01*
X990201Y127010D01*
X990451Y127177D01*
X990784Y127302D01*
X991159Y127344D01*
X991534Y127302D01*
X991867Y127177D01*
X992117Y127010D01*
X992326Y126760D01*
X992409Y126427D01*
G01X989909Y129527D02*
X989951Y129819D01*
X990076Y130152D01*
X990284Y130360D01*
X990576Y130444D01*
X990867Y130360D01*
X991117Y130110D01*
X991242Y129735D01*
Y129319D01*
X991326Y129069D01*
X991534Y128860D01*
X991826Y128777D01*
X992117Y128902D01*
X992326Y129194D01*
X992409Y129527D01*
X992326Y129860D01*
X992117Y130152D01*
X991826Y130277D01*
X991534Y130194D01*
X991326Y129985D01*
X991242Y129735D01*
Y129319D01*
X991117Y128944D01*
X990867Y128694D01*
X990576Y128610D01*
X990284Y128694D01*
X990076Y128902D01*
X989951Y129235D01*
X989909Y129527D01*
G01X1016038Y142245D02*
Y139745D01*
G01X1016996Y142245D02*
X1015080D01*
G01X1013771Y139745D02*
Y142245D01*
X1012771D01*
X1012438Y142120D01*
X1012188Y141828D01*
X1012105Y141495D01*
X1012188Y141162D01*
X1012396Y140912D01*
X1012771Y140787D01*
X1013771D01*
G01X1009838Y139745D02*
Y142245D01*
X1010338Y141745D01*
G01Y139745D02*
X1009338D01*
G01X1007530Y140787D02*
X1007238Y141078D01*
X1006988Y141245D01*
X1006655Y141328D01*
X1006363Y141245D01*
X1006155Y141078D01*
X1005988Y140828D01*
X1005946Y140537D01*
X1005988Y140287D01*
X1006155Y140037D01*
X1006405Y139828D01*
X1006696Y139745D01*
X1007030Y139828D01*
X1007321Y140078D01*
X1007488Y140453D01*
X1007530Y140870D01*
X1007446Y141412D01*
X1007321Y141703D01*
X1007113Y141995D01*
X1006821Y142203D01*
X1006530Y142245D01*
X1006238Y142162D01*
X1006030Y141953D01*
G01X1003138Y139745D02*
Y142245D01*
X1004680Y140453D01*
X1002596D01*
G01X1016038Y138086D02*
Y135586D01*
G01X1016996Y138086D02*
X1015080D01*
G01X1013771Y135586D02*
Y138086D01*
X1012771D01*
X1012438Y137961D01*
X1012188Y137669D01*
X1012105Y137336D01*
X1012188Y137003D01*
X1012396Y136753D01*
X1012771Y136628D01*
X1013771D01*
G01X1010630Y137669D02*
X1010380Y137919D01*
X1010088Y138044D01*
X1009755Y138086D01*
X1009338Y138003D01*
X1009046Y137794D01*
X1008963Y137544D01*
X1009005Y137294D01*
X1009171Y137086D01*
X1010005Y136669D01*
X1010380Y136378D01*
X1010630Y135961D01*
X1010713Y135586D01*
X1008963D01*
G01X1007530Y136628D02*
X1007238Y136919D01*
X1006988Y137086D01*
X1006655Y137169D01*
X1006363Y137086D01*
X1006155Y136919D01*
X1005988Y136669D01*
X1005946Y136378D01*
X1005988Y136128D01*
X1006155Y135878D01*
X1006405Y135669D01*
X1006696Y135586D01*
X1007030Y135669D01*
X1007321Y135919D01*
X1007488Y136294D01*
X1007530Y136711D01*
X1007446Y137253D01*
X1007321Y137544D01*
X1007113Y137836D01*
X1006821Y138044D01*
X1006530Y138086D01*
X1006238Y138003D01*
X1006030Y137794D01*
G01X1004430Y137669D02*
X1004180Y137919D01*
X1003888Y138044D01*
X1003555Y138086D01*
X1003138Y138003D01*
X1002846Y137794D01*
X1002763Y137544D01*
X1002805Y137294D01*
X1002971Y137086D01*
X1003805Y136669D01*
X1004180Y136378D01*
X1004430Y135961D01*
X1004513Y135586D01*
X1002763D01*
G01X1013570Y163003D02*
X1013820Y163128D01*
X1014112Y163211D01*
X1014445D01*
X1014820Y163086D01*
X1015112Y162878D01*
X1015320Y162628D01*
X1015487Y162211D01*
X1015529Y161836D01*
X1015445Y161461D01*
X1015320Y161211D01*
X1015070Y160961D01*
X1014779Y160794D01*
X1014487Y160711D01*
X1014195D01*
X1013904Y160794D01*
X1013654Y160919D01*
X1013445Y161086D01*
G01X1010887Y160711D02*
Y163211D01*
X1012429Y161419D01*
X1010345D01*
G01X1008287Y160711D02*
X1007995Y160753D01*
X1007662Y160878D01*
X1007454Y161086D01*
X1007370Y161378D01*
X1007454Y161669D01*
X1007704Y161919D01*
X1008079Y162044D01*
X1008495D01*
X1008745Y162128D01*
X1008954Y162336D01*
X1009037Y162628D01*
X1008912Y162919D01*
X1008620Y163128D01*
X1008287Y163211D01*
X1007954Y163128D01*
X1007662Y162919D01*
X1007537Y162628D01*
X1007620Y162336D01*
X1007829Y162128D01*
X1008079Y162044D01*
X1008495D01*
X1008870Y161919D01*
X1009120Y161669D01*
X1009204Y161378D01*
X1009120Y161086D01*
X1008912Y160878D01*
X1008579Y160753D01*
X1008287Y160711D01*
G01X1006104Y161086D02*
X1005854Y160878D01*
X1005562Y160753D01*
X1005187Y160711D01*
X1004812Y160794D01*
X1004520Y160961D01*
X1004312Y161253D01*
X1004270Y161586D01*
X1004354Y161919D01*
X1004562Y162128D01*
X1004854Y162294D01*
X1005145Y162336D01*
X1005437Y162294D01*
X1005812Y162128D01*
X1005687Y163211D01*
X1004562D01*
G01X1014013Y150221D02*
X1014263Y150346D01*
X1014555Y150429D01*
X1014888D01*
X1015263Y150304D01*
X1015555Y150096D01*
X1015763Y149846D01*
X1015930Y149429D01*
X1015972Y149054D01*
X1015888Y148679D01*
X1015763Y148429D01*
X1015513Y148179D01*
X1015222Y148012D01*
X1014930Y147929D01*
X1014638D01*
X1014347Y148012D01*
X1014097Y148137D01*
X1013888Y148304D01*
G01X1011330Y147929D02*
Y150429D01*
X1012872Y148637D01*
X1010788D01*
G01X1009522Y148971D02*
X1009230Y149262D01*
X1008980Y149429D01*
X1008647Y149512D01*
X1008355Y149429D01*
X1008147Y149262D01*
X1007980Y149012D01*
X1007938Y148721D01*
X1007980Y148471D01*
X1008147Y148221D01*
X1008397Y148012D01*
X1008688Y147929D01*
X1009022Y148012D01*
X1009313Y148262D01*
X1009480Y148637D01*
X1009522Y149054D01*
X1009438Y149596D01*
X1009313Y149887D01*
X1009105Y150179D01*
X1008813Y150387D01*
X1008522Y150429D01*
X1008230Y150346D01*
X1008022Y150137D01*
G01X1005630Y147929D02*
X1005338Y147971D01*
X1005005Y148096D01*
X1004797Y148304D01*
X1004713Y148596D01*
X1004797Y148887D01*
X1005047Y149137D01*
X1005422Y149262D01*
X1005838D01*
X1006088Y149346D01*
X1006297Y149554D01*
X1006380Y149846D01*
X1006255Y150137D01*
X1005963Y150346D01*
X1005630Y150429D01*
X1005297Y150346D01*
X1005005Y150137D01*
X1004880Y149846D01*
X1004963Y149554D01*
X1005172Y149346D01*
X1005422Y149262D01*
X1005838D01*
X1006213Y149137D01*
X1006463Y148887D01*
X1006547Y148596D01*
X1006463Y148304D01*
X1006255Y148096D01*
X1005922Y147971D01*
X1005630Y147929D01*
G01X1008233Y169721D02*
X1008483Y169846D01*
X1008775Y169929D01*
X1009108D01*
X1009483Y169804D01*
X1009775Y169596D01*
X1009983Y169346D01*
X1010150Y168929D01*
X1010192Y168554D01*
X1010108Y168179D01*
X1009983Y167929D01*
X1009733Y167679D01*
X1009442Y167512D01*
X1009150Y167429D01*
X1008858D01*
X1008567Y167512D01*
X1008317Y167637D01*
X1008108Y167804D01*
G01X1006842Y168471D02*
X1006550Y168762D01*
X1006300Y168929D01*
X1005967Y169012D01*
X1005675Y168929D01*
X1005467Y168762D01*
X1005300Y168512D01*
X1005258Y168221D01*
X1005300Y167971D01*
X1005467Y167721D01*
X1005717Y167512D01*
X1006008Y167429D01*
X1006342Y167512D01*
X1006633Y167762D01*
X1006800Y168137D01*
X1006842Y168554D01*
X1006758Y169096D01*
X1006633Y169387D01*
X1006425Y169679D01*
X1006133Y169887D01*
X1005842Y169929D01*
X1005550Y169846D01*
X1005342Y169637D01*
G01X1002950Y167429D02*
Y169929D01*
X1003450Y169429D01*
G01Y167429D02*
X1002450D01*
G01X1000767Y167804D02*
X1000517Y167596D01*
X1000225Y167471D01*
X999850Y167429D01*
X999475Y167512D01*
X999183Y167679D01*
X998975Y167971D01*
X998933Y168304D01*
X999017Y168637D01*
X999225Y168846D01*
X999517Y169012D01*
X999808Y169054D01*
X1000100Y169012D01*
X1000475Y168846D01*
X1000350Y169929D01*
X999225D01*
G01X1008233Y173721D02*
X1008483Y173846D01*
X1008775Y173929D01*
X1009108D01*
X1009483Y173804D01*
X1009775Y173596D01*
X1009983Y173346D01*
X1010150Y172929D01*
X1010192Y172554D01*
X1010108Y172179D01*
X1009983Y171929D01*
X1009733Y171679D01*
X1009442Y171512D01*
X1009150Y171429D01*
X1008858D01*
X1008567Y171512D01*
X1008317Y171637D01*
X1008108Y171804D01*
G01X1006842Y172471D02*
X1006550Y172762D01*
X1006300Y172929D01*
X1005967Y173012D01*
X1005675Y172929D01*
X1005467Y172762D01*
X1005300Y172512D01*
X1005258Y172221D01*
X1005300Y171971D01*
X1005467Y171721D01*
X1005717Y171512D01*
X1006008Y171429D01*
X1006342Y171512D01*
X1006633Y171762D01*
X1006800Y172137D01*
X1006842Y172554D01*
X1006758Y173096D01*
X1006633Y173387D01*
X1006425Y173679D01*
X1006133Y173887D01*
X1005842Y173929D01*
X1005550Y173846D01*
X1005342Y173637D01*
G01X1002950Y171429D02*
Y173929D01*
X1003450Y173429D01*
G01Y171429D02*
X1002450D01*
G01X999350D02*
Y173929D01*
X1000892Y172137D01*
X998808D01*
G01X1008233Y177621D02*
X1008483Y177746D01*
X1008775Y177829D01*
X1009108D01*
X1009483Y177704D01*
X1009775Y177496D01*
X1009983Y177246D01*
X1010150Y176829D01*
X1010192Y176454D01*
X1010108Y176079D01*
X1009983Y175829D01*
X1009733Y175579D01*
X1009442Y175412D01*
X1009150Y175329D01*
X1008858D01*
X1008567Y175412D01*
X1008317Y175537D01*
X1008108Y175704D01*
G01X1006842Y176371D02*
X1006550Y176662D01*
X1006300Y176829D01*
X1005967Y176912D01*
X1005675Y176829D01*
X1005467Y176662D01*
X1005300Y176412D01*
X1005258Y176121D01*
X1005300Y175871D01*
X1005467Y175621D01*
X1005717Y175412D01*
X1006008Y175329D01*
X1006342Y175412D01*
X1006633Y175662D01*
X1006800Y176037D01*
X1006842Y176454D01*
X1006758Y176996D01*
X1006633Y177287D01*
X1006425Y177579D01*
X1006133Y177787D01*
X1005842Y177829D01*
X1005550Y177746D01*
X1005342Y177537D01*
G01X1002950Y175329D02*
Y177829D01*
X1003450Y177329D01*
G01Y175329D02*
X1002450D01*
G01X1000767Y175829D02*
X1000517Y175537D01*
X1000183Y175371D01*
X999808Y175329D01*
X999475Y175371D01*
X999142Y175579D01*
X998933Y175829D01*
X998892Y176079D01*
X998975Y176371D01*
X999267Y176579D01*
X999558Y176662D01*
X999933D01*
G01X999558D02*
X999308Y176787D01*
X999100Y176996D01*
X999017Y177246D01*
X999100Y177496D01*
X999308Y177704D01*
X999683Y177829D01*
X1000058Y177787D01*
X1000433Y177621D01*
G01X1007026Y158579D02*
X1007276Y158704D01*
X1007568Y158787D01*
X1007901D01*
X1008276Y158662D01*
X1008568Y158454D01*
X1008776Y158204D01*
X1008943Y157787D01*
X1008985Y157412D01*
X1008901Y157037D01*
X1008776Y156787D01*
X1008526Y156537D01*
X1008235Y156370D01*
X1007943Y156287D01*
X1007651D01*
X1007360Y156370D01*
X1007110Y156495D01*
X1006901Y156662D01*
G01X1004343Y156287D02*
Y158787D01*
X1005885Y156995D01*
X1003801D01*
G01X1001743Y156287D02*
X1001451Y156329D01*
X1001118Y156454D01*
X1000910Y156662D01*
X1000826Y156954D01*
X1000910Y157245D01*
X1001160Y157495D01*
X1001535Y157620D01*
X1001951D01*
X1002201Y157704D01*
X1002410Y157912D01*
X1002493Y158204D01*
X1002368Y158495D01*
X1002076Y158704D01*
X1001743Y158787D01*
X1001410Y158704D01*
X1001118Y158495D01*
X1000993Y158204D01*
X1001076Y157912D01*
X1001285Y157704D01*
X1001535Y157620D01*
X1001951D01*
X1002326Y157495D01*
X1002576Y157245D01*
X1002660Y156954D01*
X1002576Y156662D01*
X1002368Y156454D01*
X1002035Y156329D01*
X1001743Y156287D01*
G01X999435Y157329D02*
X999143Y157620D01*
X998893Y157787D01*
X998560Y157870D01*
X998268Y157787D01*
X998060Y157620D01*
X997893Y157370D01*
X997851Y157079D01*
X997893Y156829D01*
X998060Y156579D01*
X998310Y156370D01*
X998601Y156287D01*
X998935Y156370D01*
X999226Y156620D01*
X999393Y156995D01*
X999435Y157412D01*
X999351Y157954D01*
X999226Y158245D01*
X999018Y158537D01*
X998726Y158745D01*
X998435Y158787D01*
X998143Y158704D01*
X997935Y158495D01*
G01X985133Y166392D02*
X985383Y166517D01*
X985675Y166600D01*
X986008D01*
X986383Y166475D01*
X986675Y166267D01*
X986883Y166017D01*
X987050Y165600D01*
X987092Y165225D01*
X987008Y164850D01*
X986883Y164600D01*
X986633Y164350D01*
X986342Y164183D01*
X986050Y164100D01*
X985758D01*
X985467Y164183D01*
X985217Y164308D01*
X985008Y164475D01*
G01X982450Y164100D02*
Y166600D01*
X983992Y164808D01*
X981908D01*
G01X980767Y164475D02*
X980517Y164267D01*
X980225Y164142D01*
X979850Y164100D01*
X979475Y164183D01*
X979183Y164350D01*
X978975Y164642D01*
X978933Y164975D01*
X979017Y165308D01*
X979225Y165517D01*
X979517Y165683D01*
X979808Y165725D01*
X980100Y165683D01*
X980475Y165517D01*
X980350Y166600D01*
X979225D01*
G01X976833Y164100D02*
X976750Y164642D01*
X976625Y165100D01*
X976458Y165517D01*
X976250Y165975D01*
X975917Y166600D01*
X977583D01*
G01X988333Y170492D02*
X988583Y170617D01*
X988875Y170700D01*
X989208D01*
X989583Y170575D01*
X989875Y170367D01*
X990083Y170117D01*
X990250Y169700D01*
X990292Y169325D01*
X990208Y168950D01*
X990083Y168700D01*
X989833Y168450D01*
X989542Y168283D01*
X989250Y168200D01*
X988958D01*
X988667Y168283D01*
X988417Y168408D01*
X988208Y168575D01*
G01X985650Y168200D02*
Y170700D01*
X987192Y168908D01*
X985108D01*
G01X983967Y168575D02*
X983717Y168367D01*
X983425Y168242D01*
X983050Y168200D01*
X982675Y168283D01*
X982383Y168450D01*
X982175Y168742D01*
X982133Y169075D01*
X982217Y169408D01*
X982425Y169617D01*
X982717Y169783D01*
X983008Y169825D01*
X983300Y169783D01*
X983675Y169617D01*
X983550Y170700D01*
X982425D01*
G01X980867Y168700D02*
X980617Y168408D01*
X980283Y168242D01*
X979908Y168200D01*
X979575Y168242D01*
X979242Y168450D01*
X979033Y168700D01*
X978992Y168950D01*
X979075Y169242D01*
X979367Y169450D01*
X979658Y169533D01*
X980033D01*
G01X979658D02*
X979408Y169658D01*
X979200Y169867D01*
X979117Y170117D01*
X979200Y170367D01*
X979408Y170575D01*
X979783Y170700D01*
X980158Y170658D01*
X980533Y170492D01*
G01X986733Y174392D02*
X986983Y174517D01*
X987275Y174600D01*
X987608D01*
X987983Y174475D01*
X988275Y174267D01*
X988483Y174017D01*
X988650Y173600D01*
X988692Y173225D01*
X988608Y172850D01*
X988483Y172600D01*
X988233Y172350D01*
X987942Y172183D01*
X987650Y172100D01*
X987358D01*
X987067Y172183D01*
X986817Y172308D01*
X986608Y172475D01*
G01X984050Y172100D02*
Y174600D01*
X985592Y172808D01*
X983508D01*
G01X980950Y172100D02*
Y174600D01*
X982492Y172808D01*
X980408D01*
G01X979058Y172392D02*
X978767Y172183D01*
X978433Y172100D01*
X978100Y172183D01*
X977808Y172433D01*
X977600Y172808D01*
X977517Y173183D01*
Y173642D01*
X977600Y174017D01*
X977808Y174350D01*
X978058Y174517D01*
X978350Y174600D01*
X978683Y174517D01*
X978933Y174350D01*
X979100Y174100D01*
X979183Y173767D01*
X979100Y173475D01*
X978892Y173183D01*
X978642Y173017D01*
X978350Y172975D01*
X978017Y173058D01*
X977767Y173267D01*
X977517Y173642D01*
G01X1015861Y146225D02*
Y143725D01*
G01X1016819Y146225D02*
X1014903D01*
G01X1013594Y143725D02*
Y146225D01*
X1012594D01*
X1012261Y146100D01*
X1012011Y145808D01*
X1011928Y145475D01*
X1012011Y145142D01*
X1012219Y144892D01*
X1012594Y144767D01*
X1013594D01*
G01X1010453Y145808D02*
X1010203Y146058D01*
X1009911Y146183D01*
X1009578Y146225D01*
X1009161Y146142D01*
X1008869Y145933D01*
X1008786Y145683D01*
X1008828Y145433D01*
X1008994Y145225D01*
X1009828Y144808D01*
X1010203Y144517D01*
X1010453Y144100D01*
X1010536Y143725D01*
X1008786D01*
G01X1006561D02*
Y146225D01*
X1007061Y145725D01*
G01Y143725D02*
X1006061D01*
G01X1003461Y146225D02*
X1003794Y146142D01*
X1004044Y145933D01*
X1004211Y145683D01*
X1004336Y145350D01*
X1004378Y144975D01*
X1004336Y144600D01*
X1004211Y144267D01*
X1004044Y144017D01*
X1003794Y143808D01*
X1003461Y143725D01*
X1003128Y143808D01*
X1002878Y144017D01*
X1002711Y144267D01*
X1002586Y144600D01*
X1002544Y144975D01*
X1002586Y145350D01*
X1002711Y145683D01*
X1002878Y145933D01*
X1003128Y146142D01*
X1003461Y146225D01*
G01X1015331Y154409D02*
Y151909D01*
G01X1016289Y154409D02*
X1014373D01*
G01X1013064Y151909D02*
Y154409D01*
X1012064D01*
X1011731Y154284D01*
X1011481Y153992D01*
X1011398Y153659D01*
X1011481Y153326D01*
X1011689Y153076D01*
X1012064Y152951D01*
X1013064D01*
G01X1009131Y151909D02*
Y154409D01*
X1009631Y153909D01*
G01Y151909D02*
X1008631D01*
G01X1006739Y152201D02*
X1006448Y151992D01*
X1006114Y151909D01*
X1005781Y151992D01*
X1005489Y152242D01*
X1005281Y152617D01*
X1005198Y152992D01*
Y153451D01*
X1005281Y153826D01*
X1005489Y154159D01*
X1005739Y154326D01*
X1006031Y154409D01*
X1006364Y154326D01*
X1006614Y154159D01*
X1006781Y153909D01*
X1006864Y153576D01*
X1006781Y153284D01*
X1006573Y152992D01*
X1006323Y152826D01*
X1006031Y152784D01*
X1005698Y152867D01*
X1005448Y153076D01*
X1005198Y153451D01*
G01X1003723Y153992D02*
X1003473Y154242D01*
X1003181Y154367D01*
X1002848Y154409D01*
X1002431Y154326D01*
X1002139Y154117D01*
X1002056Y153867D01*
X1002098Y153617D01*
X1002264Y153409D01*
X1003098Y152992D01*
X1003473Y152701D01*
X1003723Y152284D01*
X1003806Y151909D01*
X1002056D01*
G01X989039Y151815D02*
X985039D01*
Y159215D01*
G01X1008233Y181521D02*
X1008483Y181646D01*
X1008775Y181729D01*
X1009108D01*
X1009483Y181604D01*
X1009775Y181396D01*
X1009983Y181146D01*
X1010150Y180729D01*
X1010192Y180354D01*
X1010108Y179979D01*
X1009983Y179729D01*
X1009733Y179479D01*
X1009442Y179312D01*
X1009150Y179229D01*
X1008858D01*
X1008567Y179312D01*
X1008317Y179437D01*
X1008108Y179604D01*
G01X1006842Y180271D02*
X1006550Y180562D01*
X1006300Y180729D01*
X1005967Y180812D01*
X1005675Y180729D01*
X1005467Y180562D01*
X1005300Y180312D01*
X1005258Y180021D01*
X1005300Y179771D01*
X1005467Y179521D01*
X1005717Y179312D01*
X1006008Y179229D01*
X1006342Y179312D01*
X1006633Y179562D01*
X1006800Y179937D01*
X1006842Y180354D01*
X1006758Y180896D01*
X1006633Y181187D01*
X1006425Y181479D01*
X1006133Y181687D01*
X1005842Y181729D01*
X1005550Y181646D01*
X1005342Y181437D01*
G01X1002950Y179229D02*
Y181729D01*
X1003450Y181229D01*
G01Y179229D02*
X1002450D01*
G01X1000642Y181312D02*
X1000392Y181562D01*
X1000100Y181687D01*
X999767Y181729D01*
X999350Y181646D01*
X999058Y181437D01*
X998975Y181187D01*
X999017Y180937D01*
X999183Y180729D01*
X1000017Y180312D01*
X1000392Y180021D01*
X1000642Y179604D01*
X1000725Y179229D01*
X998975D01*
G01X988707Y190101D02*
X988957Y190226D01*
X989249Y190309D01*
X989582D01*
X989957Y190184D01*
X990249Y189976D01*
X990457Y189726D01*
X990624Y189309D01*
X990666Y188934D01*
X990582Y188559D01*
X990457Y188309D01*
X990207Y188059D01*
X989916Y187892D01*
X989624Y187809D01*
X989332D01*
X989041Y187892D01*
X988791Y188017D01*
X988582Y188184D01*
G01X987316Y188851D02*
X987024Y189142D01*
X986774Y189309D01*
X986441Y189392D01*
X986149Y189309D01*
X985941Y189142D01*
X985774Y188892D01*
X985732Y188601D01*
X985774Y188351D01*
X985941Y188101D01*
X986191Y187892D01*
X986482Y187809D01*
X986816Y187892D01*
X987107Y188142D01*
X987274Y188517D01*
X987316Y188934D01*
X987232Y189476D01*
X987107Y189767D01*
X986899Y190059D01*
X986607Y190267D01*
X986316Y190309D01*
X986024Y190226D01*
X985816Y190017D01*
G01X983424Y187809D02*
Y190309D01*
X983924Y189809D01*
G01Y187809D02*
X982924D01*
G01X980324D02*
Y190309D01*
X980824Y189809D01*
G01Y187809D02*
X979824D01*
G01X1014739Y185738D02*
X1014989Y185863D01*
X1015281Y185946D01*
X1015614D01*
X1015989Y185821D01*
X1016281Y185613D01*
X1016489Y185363D01*
X1016656Y184946D01*
X1016698Y184571D01*
X1016614Y184196D01*
X1016489Y183946D01*
X1016239Y183696D01*
X1015948Y183529D01*
X1015656Y183446D01*
X1015364D01*
X1015073Y183529D01*
X1014823Y183654D01*
X1014614Y183821D01*
G01X1013348Y184488D02*
X1013056Y184779D01*
X1012806Y184946D01*
X1012473Y185029D01*
X1012181Y184946D01*
X1011973Y184779D01*
X1011806Y184529D01*
X1011764Y184238D01*
X1011806Y183988D01*
X1011973Y183738D01*
X1012223Y183529D01*
X1012514Y183446D01*
X1012848Y183529D01*
X1013139Y183779D01*
X1013306Y184154D01*
X1013348Y184571D01*
X1013264Y185113D01*
X1013139Y185404D01*
X1012931Y185696D01*
X1012639Y185904D01*
X1012348Y185946D01*
X1012056Y185863D01*
X1011848Y185654D01*
G01X1009456Y183446D02*
Y185946D01*
X1009956Y185446D01*
G01Y183446D02*
X1008956D01*
G01X1006356Y185946D02*
X1006689Y185863D01*
X1006939Y185654D01*
X1007106Y185404D01*
X1007231Y185071D01*
X1007273Y184696D01*
X1007231Y184321D01*
X1007106Y183988D01*
X1006939Y183738D01*
X1006689Y183529D01*
X1006356Y183446D01*
X1006023Y183529D01*
X1005773Y183738D01*
X1005606Y183988D01*
X1005481Y184321D01*
X1005439Y184696D01*
X1005481Y185071D01*
X1005606Y185404D01*
X1005773Y185654D01*
X1006023Y185863D01*
X1006356Y185946D01*
G01X1015074Y189542D02*
X1015324Y189667D01*
X1015616Y189750D01*
X1015949D01*
X1016324Y189625D01*
X1016616Y189417D01*
X1016824Y189167D01*
X1016991Y188750D01*
X1017033Y188375D01*
X1016949Y188000D01*
X1016824Y187750D01*
X1016574Y187500D01*
X1016283Y187333D01*
X1015991Y187250D01*
X1015699D01*
X1015408Y187333D01*
X1015158Y187458D01*
X1014949Y187625D01*
G01X1013683Y188292D02*
X1013391Y188583D01*
X1013141Y188750D01*
X1012808Y188833D01*
X1012516Y188750D01*
X1012308Y188583D01*
X1012141Y188333D01*
X1012099Y188042D01*
X1012141Y187792D01*
X1012308Y187542D01*
X1012558Y187333D01*
X1012849Y187250D01*
X1013183Y187333D01*
X1013474Y187583D01*
X1013641Y187958D01*
X1013683Y188375D01*
X1013599Y188917D01*
X1013474Y189208D01*
X1013266Y189500D01*
X1012974Y189708D01*
X1012683Y189750D01*
X1012391Y189667D01*
X1012183Y189458D01*
G01X1009791Y189750D02*
X1010124Y189667D01*
X1010374Y189458D01*
X1010541Y189208D01*
X1010666Y188875D01*
X1010708Y188500D01*
X1010666Y188125D01*
X1010541Y187792D01*
X1010374Y187542D01*
X1010124Y187333D01*
X1009791Y187250D01*
X1009458Y187333D01*
X1009208Y187542D01*
X1009041Y187792D01*
X1008916Y188125D01*
X1008874Y188500D01*
X1008916Y188875D01*
X1009041Y189208D01*
X1009208Y189458D01*
X1009458Y189667D01*
X1009791Y189750D01*
G01X1007399Y187542D02*
X1007108Y187333D01*
X1006774Y187250D01*
X1006441Y187333D01*
X1006149Y187583D01*
X1005941Y187958D01*
X1005858Y188333D01*
Y188792D01*
X1005941Y189167D01*
X1006149Y189500D01*
X1006399Y189667D01*
X1006691Y189750D01*
X1007024Y189667D01*
X1007274Y189500D01*
X1007441Y189250D01*
X1007524Y188917D01*
X1007441Y188625D01*
X1007233Y188333D01*
X1006983Y188167D01*
X1006691Y188125D01*
X1006358Y188208D01*
X1006108Y188417D01*
X1005858Y188792D01*
G01X1008233Y193821D02*
X1008483Y193946D01*
X1008775Y194029D01*
X1009108D01*
X1009483Y193904D01*
X1009775Y193696D01*
X1009983Y193446D01*
X1010150Y193029D01*
X1010192Y192654D01*
X1010108Y192279D01*
X1009983Y192029D01*
X1009733Y191779D01*
X1009442Y191612D01*
X1009150Y191529D01*
X1008858D01*
X1008567Y191612D01*
X1008317Y191737D01*
X1008108Y191904D01*
G01X1006842Y192571D02*
X1006550Y192862D01*
X1006300Y193029D01*
X1005967Y193112D01*
X1005675Y193029D01*
X1005467Y192862D01*
X1005300Y192612D01*
X1005258Y192321D01*
X1005300Y192071D01*
X1005467Y191821D01*
X1005717Y191612D01*
X1006008Y191529D01*
X1006342Y191612D01*
X1006633Y191862D01*
X1006800Y192237D01*
X1006842Y192654D01*
X1006758Y193196D01*
X1006633Y193487D01*
X1006425Y193779D01*
X1006133Y193987D01*
X1005842Y194029D01*
X1005550Y193946D01*
X1005342Y193737D01*
G01X1002950Y194029D02*
X1003283Y193946D01*
X1003533Y193737D01*
X1003700Y193487D01*
X1003825Y193154D01*
X1003867Y192779D01*
X1003825Y192404D01*
X1003700Y192071D01*
X1003533Y191821D01*
X1003283Y191612D01*
X1002950Y191529D01*
X1002617Y191612D01*
X1002367Y191821D01*
X1002200Y192071D01*
X1002075Y192404D01*
X1002033Y192779D01*
X1002075Y193154D01*
X1002200Y193487D01*
X1002367Y193737D01*
X1002617Y193946D01*
X1002950Y194029D01*
G01X999850Y191529D02*
X999558Y191571D01*
X999225Y191696D01*
X999017Y191904D01*
X998933Y192196D01*
X999017Y192487D01*
X999267Y192737D01*
X999642Y192862D01*
X1000058D01*
X1000308Y192946D01*
X1000517Y193154D01*
X1000600Y193446D01*
X1000475Y193737D01*
X1000183Y193946D01*
X999850Y194029D01*
X999517Y193946D01*
X999225Y193737D01*
X999100Y193446D01*
X999183Y193154D01*
X999392Y192946D01*
X999642Y192862D01*
X1000058D01*
X1000433Y192737D01*
X1000683Y192487D01*
X1000767Y192196D01*
X1000683Y191904D01*
X1000475Y191696D01*
X1000142Y191571D01*
X999850Y191529D01*
G01X988533Y182192D02*
X988783Y182317D01*
X989075Y182400D01*
X989408D01*
X989783Y182275D01*
X990075Y182067D01*
X990283Y181817D01*
X990450Y181400D01*
X990492Y181025D01*
X990408Y180650D01*
X990283Y180400D01*
X990033Y180150D01*
X989742Y179983D01*
X989450Y179900D01*
X989158D01*
X988867Y179983D01*
X988617Y180108D01*
X988408Y180275D01*
G01X987267D02*
X987017Y180067D01*
X986725Y179942D01*
X986350Y179900D01*
X985975Y179983D01*
X985683Y180150D01*
X985475Y180442D01*
X985433Y180775D01*
X985517Y181108D01*
X985725Y181317D01*
X986017Y181483D01*
X986308Y181525D01*
X986600Y181483D01*
X986975Y181317D01*
X986850Y182400D01*
X985725D01*
G01X983958Y180192D02*
X983667Y179983D01*
X983333Y179900D01*
X983000Y179983D01*
X982708Y180233D01*
X982500Y180608D01*
X982417Y180983D01*
Y181442D01*
X982500Y181817D01*
X982708Y182150D01*
X982958Y182317D01*
X983250Y182400D01*
X983583Y182317D01*
X983833Y182150D01*
X984000Y181900D01*
X984083Y181567D01*
X984000Y181275D01*
X983792Y180983D01*
X983542Y180817D01*
X983250Y180775D01*
X982917Y180858D01*
X982667Y181067D01*
X982417Y181442D01*
G01X980942Y180942D02*
X980650Y181233D01*
X980400Y181400D01*
X980067Y181483D01*
X979775Y181400D01*
X979567Y181233D01*
X979400Y180983D01*
X979358Y180692D01*
X979400Y180442D01*
X979567Y180192D01*
X979817Y179983D01*
X980108Y179900D01*
X980442Y179983D01*
X980733Y180233D01*
X980900Y180608D01*
X980942Y181025D01*
X980858Y181567D01*
X980733Y181858D01*
X980525Y182150D01*
X980233Y182358D01*
X979942Y182400D01*
X979650Y182317D01*
X979442Y182108D01*
G01X1008233Y205621D02*
X1008483Y205746D01*
X1008775Y205829D01*
X1009108D01*
X1009483Y205704D01*
X1009775Y205496D01*
X1009983Y205246D01*
X1010150Y204829D01*
X1010192Y204454D01*
X1010108Y204079D01*
X1009983Y203829D01*
X1009733Y203579D01*
X1009442Y203412D01*
X1009150Y203329D01*
X1008858D01*
X1008567Y203412D01*
X1008317Y203537D01*
X1008108Y203704D01*
G01X1006967D02*
X1006717Y203496D01*
X1006425Y203371D01*
X1006050Y203329D01*
X1005675Y203412D01*
X1005383Y203579D01*
X1005175Y203871D01*
X1005133Y204204D01*
X1005217Y204537D01*
X1005425Y204746D01*
X1005717Y204912D01*
X1006008Y204954D01*
X1006300Y204912D01*
X1006675Y204746D01*
X1006550Y205829D01*
X1005425D01*
G01X1002950Y203329D02*
X1002658Y203371D01*
X1002325Y203496D01*
X1002117Y203704D01*
X1002033Y203996D01*
X1002117Y204287D01*
X1002367Y204537D01*
X1002742Y204662D01*
X1003158D01*
X1003408Y204746D01*
X1003617Y204954D01*
X1003700Y205246D01*
X1003575Y205537D01*
X1003283Y205746D01*
X1002950Y205829D01*
X1002617Y205746D01*
X1002325Y205537D01*
X1002200Y205246D01*
X1002283Y204954D01*
X1002492Y204746D01*
X1002742Y204662D01*
X1003158D01*
X1003533Y204537D01*
X1003783Y204287D01*
X1003867Y203996D01*
X1003783Y203704D01*
X1003575Y203496D01*
X1003242Y203371D01*
X1002950Y203329D01*
G01X1000642Y205412D02*
X1000392Y205662D01*
X1000100Y205787D01*
X999767Y205829D01*
X999350Y205746D01*
X999058Y205537D01*
X998975Y205287D01*
X999017Y205037D01*
X999183Y204829D01*
X1000017Y204412D01*
X1000392Y204121D01*
X1000642Y203704D01*
X1000725Y203329D01*
X998975D01*
G01X1008233Y209521D02*
X1008483Y209646D01*
X1008775Y209729D01*
X1009108D01*
X1009483Y209604D01*
X1009775Y209396D01*
X1009983Y209146D01*
X1010150Y208729D01*
X1010192Y208354D01*
X1010108Y207979D01*
X1009983Y207729D01*
X1009733Y207479D01*
X1009442Y207312D01*
X1009150Y207229D01*
X1008858D01*
X1008567Y207312D01*
X1008317Y207437D01*
X1008108Y207604D01*
G01X1006967D02*
X1006717Y207396D01*
X1006425Y207271D01*
X1006050Y207229D01*
X1005675Y207312D01*
X1005383Y207479D01*
X1005175Y207771D01*
X1005133Y208104D01*
X1005217Y208437D01*
X1005425Y208646D01*
X1005717Y208812D01*
X1006008Y208854D01*
X1006300Y208812D01*
X1006675Y208646D01*
X1006550Y209729D01*
X1005425D01*
G01X1002950Y207229D02*
X1002658Y207271D01*
X1002325Y207396D01*
X1002117Y207604D01*
X1002033Y207896D01*
X1002117Y208187D01*
X1002367Y208437D01*
X1002742Y208562D01*
X1003158D01*
X1003408Y208646D01*
X1003617Y208854D01*
X1003700Y209146D01*
X1003575Y209437D01*
X1003283Y209646D01*
X1002950Y209729D01*
X1002617Y209646D01*
X1002325Y209437D01*
X1002200Y209146D01*
X1002283Y208854D01*
X1002492Y208646D01*
X1002742Y208562D01*
X1003158D01*
X1003533Y208437D01*
X1003783Y208187D01*
X1003867Y207896D01*
X1003783Y207604D01*
X1003575Y207396D01*
X1003242Y207271D01*
X1002950Y207229D01*
G01X999850D02*
Y209729D01*
X1000350Y209229D01*
G01Y207229D02*
X999350D01*
G01X1008233Y197721D02*
X1008483Y197846D01*
X1008775Y197929D01*
X1009108D01*
X1009483Y197804D01*
X1009775Y197596D01*
X1009983Y197346D01*
X1010150Y196929D01*
X1010192Y196554D01*
X1010108Y196179D01*
X1009983Y195929D01*
X1009733Y195679D01*
X1009442Y195512D01*
X1009150Y195429D01*
X1008858D01*
X1008567Y195512D01*
X1008317Y195637D01*
X1008108Y195804D01*
G01X1006967D02*
X1006717Y195596D01*
X1006425Y195471D01*
X1006050Y195429D01*
X1005675Y195512D01*
X1005383Y195679D01*
X1005175Y195971D01*
X1005133Y196304D01*
X1005217Y196637D01*
X1005425Y196846D01*
X1005717Y197012D01*
X1006008Y197054D01*
X1006300Y197012D01*
X1006675Y196846D01*
X1006550Y197929D01*
X1005425D01*
G01X1003867Y195804D02*
X1003617Y195596D01*
X1003325Y195471D01*
X1002950Y195429D01*
X1002575Y195512D01*
X1002283Y195679D01*
X1002075Y195971D01*
X1002033Y196304D01*
X1002117Y196637D01*
X1002325Y196846D01*
X1002617Y197012D01*
X1002908Y197054D01*
X1003200Y197012D01*
X1003575Y196846D01*
X1003450Y197929D01*
X1002325D01*
G01X999850Y195429D02*
Y197929D01*
X1000350Y197429D01*
G01Y195429D02*
X999350D01*
G01X1008233Y201621D02*
X1008483Y201746D01*
X1008775Y201829D01*
X1009108D01*
X1009483Y201704D01*
X1009775Y201496D01*
X1009983Y201246D01*
X1010150Y200829D01*
X1010192Y200454D01*
X1010108Y200079D01*
X1009983Y199829D01*
X1009733Y199579D01*
X1009442Y199412D01*
X1009150Y199329D01*
X1008858D01*
X1008567Y199412D01*
X1008317Y199537D01*
X1008108Y199704D01*
G01X1006967D02*
X1006717Y199496D01*
X1006425Y199371D01*
X1006050Y199329D01*
X1005675Y199412D01*
X1005383Y199579D01*
X1005175Y199871D01*
X1005133Y200204D01*
X1005217Y200537D01*
X1005425Y200746D01*
X1005717Y200912D01*
X1006008Y200954D01*
X1006300Y200912D01*
X1006675Y200746D01*
X1006550Y201829D01*
X1005425D01*
G01X1003867Y199704D02*
X1003617Y199496D01*
X1003325Y199371D01*
X1002950Y199329D01*
X1002575Y199412D01*
X1002283Y199579D01*
X1002075Y199871D01*
X1002033Y200204D01*
X1002117Y200537D01*
X1002325Y200746D01*
X1002617Y200912D01*
X1002908Y200954D01*
X1003200Y200912D01*
X1003575Y200746D01*
X1003450Y201829D01*
X1002325D01*
G01X999850D02*
X1000183Y201746D01*
X1000433Y201537D01*
X1000600Y201287D01*
X1000725Y200954D01*
X1000767Y200579D01*
X1000725Y200204D01*
X1000600Y199871D01*
X1000433Y199621D01*
X1000183Y199412D01*
X999850Y199329D01*
X999517Y199412D01*
X999267Y199621D01*
X999100Y199871D01*
X998975Y200204D01*
X998933Y200579D01*
X998975Y200954D01*
X999100Y201287D01*
X999267Y201537D01*
X999517Y201746D01*
X999850Y201829D01*
G01X988233Y197792D02*
X988483Y197917D01*
X988775Y198000D01*
X989108D01*
X989483Y197875D01*
X989775Y197667D01*
X989983Y197417D01*
X990150Y197000D01*
X990192Y196625D01*
X990108Y196250D01*
X989983Y196000D01*
X989733Y195750D01*
X989442Y195583D01*
X989150Y195500D01*
X988858D01*
X988567Y195583D01*
X988317Y195708D01*
X988108Y195875D01*
G01X985550Y195500D02*
Y198000D01*
X987092Y196208D01*
X985008D01*
G01X983658Y195792D02*
X983367Y195583D01*
X983033Y195500D01*
X982700Y195583D01*
X982408Y195833D01*
X982200Y196208D01*
X982117Y196583D01*
Y197042D01*
X982200Y197417D01*
X982408Y197750D01*
X982658Y197917D01*
X982950Y198000D01*
X983283Y197917D01*
X983533Y197750D01*
X983700Y197500D01*
X983783Y197167D01*
X983700Y196875D01*
X983492Y196583D01*
X983242Y196417D01*
X982950Y196375D01*
X982617Y196458D01*
X982367Y196667D01*
X982117Y197042D01*
G01X979933Y195500D02*
X979850Y196042D01*
X979725Y196500D01*
X979558Y196917D01*
X979350Y197375D01*
X979017Y198000D01*
X980683D01*
G01X988233Y201792D02*
X988483Y201917D01*
X988775Y202000D01*
X989108D01*
X989483Y201875D01*
X989775Y201667D01*
X989983Y201417D01*
X990150Y201000D01*
X990192Y200625D01*
X990108Y200250D01*
X989983Y200000D01*
X989733Y199750D01*
X989442Y199583D01*
X989150Y199500D01*
X988858D01*
X988567Y199583D01*
X988317Y199708D01*
X988108Y199875D01*
G01X985550Y199500D02*
Y202000D01*
X987092Y200208D01*
X985008D01*
G01X982450Y199500D02*
Y202000D01*
X983992Y200208D01*
X981908D01*
G01X980767Y199875D02*
X980517Y199667D01*
X980225Y199542D01*
X979850Y199500D01*
X979475Y199583D01*
X979183Y199750D01*
X978975Y200042D01*
X978933Y200375D01*
X979017Y200708D01*
X979225Y200917D01*
X979517Y201083D01*
X979808Y201125D01*
X980100Y201083D01*
X980475Y200917D01*
X980350Y202000D01*
X979225D01*
G01X986733Y206292D02*
X986983Y206417D01*
X987275Y206500D01*
X987608D01*
X987983Y206375D01*
X988275Y206167D01*
X988483Y205917D01*
X988650Y205500D01*
X988692Y205125D01*
X988608Y204750D01*
X988483Y204500D01*
X988233Y204250D01*
X987942Y204083D01*
X987650Y204000D01*
X987358D01*
X987067Y204083D01*
X986817Y204208D01*
X986608Y204375D01*
G01X984050Y204000D02*
Y206500D01*
X985592Y204708D01*
X983508D01*
G01X980950Y204000D02*
Y206500D01*
X982492Y204708D01*
X980408D01*
G01X979142Y206083D02*
X978892Y206333D01*
X978600Y206458D01*
X978267Y206500D01*
X977850Y206417D01*
X977558Y206208D01*
X977475Y205958D01*
X977517Y205708D01*
X977683Y205500D01*
X978517Y205083D01*
X978892Y204792D01*
X979142Y204375D01*
X979225Y204000D01*
X977475D01*
G01X1008233Y221321D02*
X1008483Y221446D01*
X1008775Y221529D01*
X1009108D01*
X1009483Y221404D01*
X1009775Y221196D01*
X1009983Y220946D01*
X1010150Y220529D01*
X1010192Y220154D01*
X1010108Y219779D01*
X1009983Y219529D01*
X1009733Y219279D01*
X1009442Y219112D01*
X1009150Y219029D01*
X1008858D01*
X1008567Y219112D01*
X1008317Y219237D01*
X1008108Y219404D01*
G01X1006842Y220071D02*
X1006550Y220362D01*
X1006300Y220529D01*
X1005967Y220612D01*
X1005675Y220529D01*
X1005467Y220362D01*
X1005300Y220112D01*
X1005258Y219821D01*
X1005300Y219571D01*
X1005467Y219321D01*
X1005717Y219112D01*
X1006008Y219029D01*
X1006342Y219112D01*
X1006633Y219362D01*
X1006800Y219737D01*
X1006842Y220154D01*
X1006758Y220696D01*
X1006633Y220987D01*
X1006425Y221279D01*
X1006133Y221487D01*
X1005842Y221529D01*
X1005550Y221446D01*
X1005342Y221237D01*
G01X1002950Y221529D02*
X1003283Y221446D01*
X1003533Y221237D01*
X1003700Y220987D01*
X1003825Y220654D01*
X1003867Y220279D01*
X1003825Y219904D01*
X1003700Y219571D01*
X1003533Y219321D01*
X1003283Y219112D01*
X1002950Y219029D01*
X1002617Y219112D01*
X1002367Y219321D01*
X1002200Y219571D01*
X1002075Y219904D01*
X1002033Y220279D01*
X1002075Y220654D01*
X1002200Y220987D01*
X1002367Y221237D01*
X1002617Y221446D01*
X1002950Y221529D01*
G01X999933Y219029D02*
X999850Y219571D01*
X999725Y220029D01*
X999558Y220446D01*
X999350Y220904D01*
X999017Y221529D01*
X1000683D01*
G01X989298Y242767D02*
X989423Y242517D01*
X989506Y242225D01*
Y241892D01*
X989381Y241517D01*
X989173Y241225D01*
X988923Y241017D01*
X988506Y240850D01*
X988131Y240808D01*
X987756Y240892D01*
X987506Y241017D01*
X987256Y241267D01*
X987089Y241558D01*
X987006Y241850D01*
Y242142D01*
X987089Y242433D01*
X987214Y242683D01*
X987381Y242892D01*
G01X988048Y244158D02*
X988339Y244450D01*
X988506Y244700D01*
X988589Y245033D01*
X988506Y245325D01*
X988339Y245533D01*
X988089Y245700D01*
X987798Y245742D01*
X987548Y245700D01*
X987298Y245533D01*
X987089Y245283D01*
X987006Y244992D01*
X987089Y244658D01*
X987339Y244367D01*
X987714Y244200D01*
X988131Y244158D01*
X988673Y244242D01*
X988964Y244367D01*
X989256Y244575D01*
X989464Y244867D01*
X989506Y245158D01*
X989423Y245450D01*
X989214Y245658D01*
G01X989506Y248050D02*
X989423Y247717D01*
X989214Y247467D01*
X988964Y247300D01*
X988631Y247175D01*
X988256Y247133D01*
X987881Y247175D01*
X987548Y247300D01*
X987298Y247467D01*
X987089Y247717D01*
X987006Y248050D01*
X987089Y248383D01*
X987298Y248633D01*
X987548Y248800D01*
X987881Y248925D01*
X988256Y248967D01*
X988631Y248925D01*
X988964Y248800D01*
X989214Y248633D01*
X989423Y248383D01*
X989506Y248050D01*
G01X987506Y250233D02*
X987214Y250483D01*
X987048Y250817D01*
X987006Y251192D01*
X987048Y251525D01*
X987256Y251858D01*
X987506Y252067D01*
X987756Y252108D01*
X988048Y252025D01*
X988256Y251733D01*
X988339Y251442D01*
Y251067D01*
G01Y251442D02*
X988464Y251692D01*
X988673Y251900D01*
X988923Y251983D01*
X989173Y251900D01*
X989381Y251692D01*
X989506Y251317D01*
X989464Y250942D01*
X989298Y250567D01*
G01X993253Y242767D02*
X993378Y242517D01*
X993461Y242225D01*
Y241892D01*
X993336Y241517D01*
X993128Y241225D01*
X992878Y241017D01*
X992461Y240850D01*
X992086Y240808D01*
X991711Y240892D01*
X991461Y241017D01*
X991211Y241267D01*
X991044Y241558D01*
X990961Y241850D01*
Y242142D01*
X991044Y242433D01*
X991169Y242683D01*
X991336Y242892D01*
G01X992003Y244158D02*
X992294Y244450D01*
X992461Y244700D01*
X992544Y245033D01*
X992461Y245325D01*
X992294Y245533D01*
X992044Y245700D01*
X991753Y245742D01*
X991503Y245700D01*
X991253Y245533D01*
X991044Y245283D01*
X990961Y244992D01*
X991044Y244658D01*
X991294Y244367D01*
X991669Y244200D01*
X992086Y244158D01*
X992628Y244242D01*
X992919Y244367D01*
X993211Y244575D01*
X993419Y244867D01*
X993461Y245158D01*
X993378Y245450D01*
X993169Y245658D01*
G01X993461Y248050D02*
X993378Y247717D01*
X993169Y247467D01*
X992919Y247300D01*
X992586Y247175D01*
X992211Y247133D01*
X991836Y247175D01*
X991503Y247300D01*
X991253Y247467D01*
X991044Y247717D01*
X990961Y248050D01*
X991044Y248383D01*
X991253Y248633D01*
X991503Y248800D01*
X991836Y248925D01*
X992211Y248967D01*
X992586Y248925D01*
X992919Y248800D01*
X993169Y248633D01*
X993378Y248383D01*
X993461Y248050D01*
G01X993044Y250358D02*
X993294Y250608D01*
X993419Y250900D01*
X993461Y251233D01*
X993378Y251650D01*
X993169Y251942D01*
X992919Y252025D01*
X992669Y251983D01*
X992461Y251817D01*
X992044Y250983D01*
X991753Y250608D01*
X991336Y250358D01*
X990961Y250275D01*
Y252025D01*
G01X997213Y242767D02*
X997338Y242517D01*
X997421Y242225D01*
Y241892D01*
X997296Y241517D01*
X997088Y241225D01*
X996838Y241017D01*
X996421Y240850D01*
X996046Y240808D01*
X995671Y240892D01*
X995421Y241017D01*
X995171Y241267D01*
X995004Y241558D01*
X994921Y241850D01*
Y242142D01*
X995004Y242433D01*
X995129Y242683D01*
X995296Y242892D01*
G01X995963Y244158D02*
X996254Y244450D01*
X996421Y244700D01*
X996504Y245033D01*
X996421Y245325D01*
X996254Y245533D01*
X996004Y245700D01*
X995713Y245742D01*
X995463Y245700D01*
X995213Y245533D01*
X995004Y245283D01*
X994921Y244992D01*
X995004Y244658D01*
X995254Y244367D01*
X995629Y244200D01*
X996046Y244158D01*
X996588Y244242D01*
X996879Y244367D01*
X997171Y244575D01*
X997379Y244867D01*
X997421Y245158D01*
X997338Y245450D01*
X997129Y245658D01*
G01X997421Y248050D02*
X997338Y247717D01*
X997129Y247467D01*
X996879Y247300D01*
X996546Y247175D01*
X996171Y247133D01*
X995796Y247175D01*
X995463Y247300D01*
X995213Y247467D01*
X995004Y247717D01*
X994921Y248050D01*
X995004Y248383D01*
X995213Y248633D01*
X995463Y248800D01*
X995796Y248925D01*
X996171Y248967D01*
X996546Y248925D01*
X996879Y248800D01*
X997129Y248633D01*
X997338Y248383D01*
X997421Y248050D01*
G01X994921Y251150D02*
X997421D01*
X996921Y250650D01*
G01X994921D02*
Y251650D01*
G01X1001150Y242767D02*
X1001275Y242517D01*
X1001358Y242225D01*
Y241892D01*
X1001233Y241517D01*
X1001025Y241225D01*
X1000775Y241017D01*
X1000358Y240850D01*
X999983Y240808D01*
X999608Y240892D01*
X999358Y241017D01*
X999108Y241267D01*
X998941Y241558D01*
X998858Y241850D01*
Y242142D01*
X998941Y242433D01*
X999066Y242683D01*
X999233Y242892D01*
G01X999900Y244158D02*
X1000191Y244450D01*
X1000358Y244700D01*
X1000441Y245033D01*
X1000358Y245325D01*
X1000191Y245533D01*
X999941Y245700D01*
X999650Y245742D01*
X999400Y245700D01*
X999150Y245533D01*
X998941Y245283D01*
X998858Y244992D01*
X998941Y244658D01*
X999191Y244367D01*
X999566Y244200D01*
X999983Y244158D01*
X1000525Y244242D01*
X1000816Y244367D01*
X1001108Y244575D01*
X1001316Y244867D01*
X1001358Y245158D01*
X1001275Y245450D01*
X1001066Y245658D01*
G01X1001358Y248050D02*
X1001275Y247717D01*
X1001066Y247467D01*
X1000816Y247300D01*
X1000483Y247175D01*
X1000108Y247133D01*
X999733Y247175D01*
X999400Y247300D01*
X999150Y247467D01*
X998941Y247717D01*
X998858Y248050D01*
X998941Y248383D01*
X999150Y248633D01*
X999400Y248800D01*
X999733Y248925D01*
X1000108Y248967D01*
X1000483Y248925D01*
X1000816Y248800D01*
X1001066Y248633D01*
X1001275Y248383D01*
X1001358Y248050D01*
G01Y251150D02*
X1001275Y250817D01*
X1001066Y250567D01*
X1000816Y250400D01*
X1000483Y250275D01*
X1000108Y250233D01*
X999733Y250275D01*
X999400Y250400D01*
X999150Y250567D01*
X998941Y250817D01*
X998858Y251150D01*
X998941Y251483D01*
X999150Y251733D01*
X999400Y251900D01*
X999733Y252025D01*
X1000108Y252067D01*
X1000483Y252025D01*
X1000816Y251900D01*
X1001066Y251733D01*
X1001275Y251483D01*
X1001358Y251150D01*
G01X1005053Y242767D02*
X1005178Y242517D01*
X1005261Y242225D01*
Y241892D01*
X1005136Y241517D01*
X1004928Y241225D01*
X1004678Y241017D01*
X1004261Y240850D01*
X1003886Y240808D01*
X1003511Y240892D01*
X1003261Y241017D01*
X1003011Y241267D01*
X1002844Y241558D01*
X1002761Y241850D01*
Y242142D01*
X1002844Y242433D01*
X1002969Y242683D01*
X1003136Y242892D01*
G01Y244033D02*
X1002928Y244283D01*
X1002803Y244575D01*
X1002761Y244950D01*
X1002844Y245325D01*
X1003011Y245617D01*
X1003303Y245825D01*
X1003636Y245867D01*
X1003969Y245783D01*
X1004178Y245575D01*
X1004344Y245283D01*
X1004386Y244992D01*
X1004344Y244700D01*
X1004178Y244325D01*
X1005261Y244450D01*
Y245575D01*
G01X1003053Y247342D02*
X1002844Y247633D01*
X1002761Y247967D01*
X1002844Y248300D01*
X1003094Y248592D01*
X1003469Y248800D01*
X1003844Y248883D01*
X1004303D01*
X1004678Y248800D01*
X1005011Y248592D01*
X1005178Y248342D01*
X1005261Y248050D01*
X1005178Y247717D01*
X1005011Y247467D01*
X1004761Y247300D01*
X1004428Y247217D01*
X1004136Y247300D01*
X1003844Y247508D01*
X1003678Y247758D01*
X1003636Y248050D01*
X1003719Y248383D01*
X1003928Y248633D01*
X1004303Y248883D01*
G01X1003053Y250442D02*
X1002844Y250733D01*
X1002761Y251067D01*
X1002844Y251400D01*
X1003094Y251692D01*
X1003469Y251900D01*
X1003844Y251983D01*
X1004303D01*
X1004678Y251900D01*
X1005011Y251692D01*
X1005178Y251442D01*
X1005261Y251150D01*
X1005178Y250817D01*
X1005011Y250567D01*
X1004761Y250400D01*
X1004428Y250317D01*
X1004136Y250400D01*
X1003844Y250608D01*
X1003678Y250858D01*
X1003636Y251150D01*
X1003719Y251483D01*
X1003928Y251733D01*
X1004303Y251983D01*
G01X1015733Y237792D02*
X1015983Y237917D01*
X1016275Y238000D01*
X1016608D01*
X1016983Y237875D01*
X1017275Y237667D01*
X1017483Y237417D01*
X1017650Y237000D01*
X1017692Y236625D01*
X1017608Y236250D01*
X1017483Y236000D01*
X1017233Y235750D01*
X1016942Y235583D01*
X1016650Y235500D01*
X1016358D01*
X1016067Y235583D01*
X1015817Y235708D01*
X1015608Y235875D01*
G01X1014467D02*
X1014217Y235667D01*
X1013925Y235542D01*
X1013550Y235500D01*
X1013175Y235583D01*
X1012883Y235750D01*
X1012675Y236042D01*
X1012633Y236375D01*
X1012717Y236708D01*
X1012925Y236917D01*
X1013217Y237083D01*
X1013508Y237125D01*
X1013800Y237083D01*
X1014175Y236917D01*
X1014050Y238000D01*
X1012925D01*
G01X1011158Y235792D02*
X1010867Y235583D01*
X1010533Y235500D01*
X1010200Y235583D01*
X1009908Y235833D01*
X1009700Y236208D01*
X1009617Y236583D01*
Y237042D01*
X1009700Y237417D01*
X1009908Y237750D01*
X1010158Y237917D01*
X1010450Y238000D01*
X1010783Y237917D01*
X1011033Y237750D01*
X1011200Y237500D01*
X1011283Y237167D01*
X1011200Y236875D01*
X1010992Y236583D01*
X1010742Y236417D01*
X1010450Y236375D01*
X1010117Y236458D01*
X1009867Y236667D01*
X1009617Y237042D01*
G01X1007433Y235500D02*
X1007350Y236042D01*
X1007225Y236500D01*
X1007058Y236917D01*
X1006850Y237375D01*
X1006517Y238000D01*
X1008183D01*
G01X1008233Y225321D02*
X1008483Y225446D01*
X1008775Y225529D01*
X1009108D01*
X1009483Y225404D01*
X1009775Y225196D01*
X1009983Y224946D01*
X1010150Y224529D01*
X1010192Y224154D01*
X1010108Y223779D01*
X1009983Y223529D01*
X1009733Y223279D01*
X1009442Y223112D01*
X1009150Y223029D01*
X1008858D01*
X1008567Y223112D01*
X1008317Y223237D01*
X1008108Y223404D01*
G01X1006967D02*
X1006717Y223196D01*
X1006425Y223071D01*
X1006050Y223029D01*
X1005675Y223112D01*
X1005383Y223279D01*
X1005175Y223571D01*
X1005133Y223904D01*
X1005217Y224237D01*
X1005425Y224446D01*
X1005717Y224612D01*
X1006008Y224654D01*
X1006300Y224612D01*
X1006675Y224446D01*
X1006550Y225529D01*
X1005425D01*
G01X1002950Y223029D02*
X1002658Y223071D01*
X1002325Y223196D01*
X1002117Y223404D01*
X1002033Y223696D01*
X1002117Y223987D01*
X1002367Y224237D01*
X1002742Y224362D01*
X1003158D01*
X1003408Y224446D01*
X1003617Y224654D01*
X1003700Y224946D01*
X1003575Y225237D01*
X1003283Y225446D01*
X1002950Y225529D01*
X1002617Y225446D01*
X1002325Y225237D01*
X1002200Y224946D01*
X1002283Y224654D01*
X1002492Y224446D01*
X1002742Y224362D01*
X1003158D01*
X1003533Y224237D01*
X1003783Y223987D01*
X1003867Y223696D01*
X1003783Y223404D01*
X1003575Y223196D01*
X1003242Y223071D01*
X1002950Y223029D01*
G01X999933D02*
X999850Y223571D01*
X999725Y224029D01*
X999558Y224446D01*
X999350Y224904D01*
X999017Y225529D01*
X1000683D01*
G01X1008233Y213471D02*
X1008483Y213596D01*
X1008775Y213679D01*
X1009108D01*
X1009483Y213554D01*
X1009775Y213346D01*
X1009983Y213096D01*
X1010150Y212679D01*
X1010192Y212304D01*
X1010108Y211929D01*
X1009983Y211679D01*
X1009733Y211429D01*
X1009442Y211262D01*
X1009150Y211179D01*
X1008858D01*
X1008567Y211262D01*
X1008317Y211387D01*
X1008108Y211554D01*
G01X1006967D02*
X1006717Y211346D01*
X1006425Y211221D01*
X1006050Y211179D01*
X1005675Y211262D01*
X1005383Y211429D01*
X1005175Y211721D01*
X1005133Y212054D01*
X1005217Y212387D01*
X1005425Y212596D01*
X1005717Y212762D01*
X1006008Y212804D01*
X1006300Y212762D01*
X1006675Y212596D01*
X1006550Y213679D01*
X1005425D01*
G01X1002950Y211179D02*
X1002658Y211221D01*
X1002325Y211346D01*
X1002117Y211554D01*
X1002033Y211846D01*
X1002117Y212137D01*
X1002367Y212387D01*
X1002742Y212512D01*
X1003158D01*
X1003408Y212596D01*
X1003617Y212804D01*
X1003700Y213096D01*
X1003575Y213387D01*
X1003283Y213596D01*
X1002950Y213679D01*
X1002617Y213596D01*
X1002325Y213387D01*
X1002200Y213096D01*
X1002283Y212804D01*
X1002492Y212596D01*
X1002742Y212512D01*
X1003158D01*
X1003533Y212387D01*
X1003783Y212137D01*
X1003867Y211846D01*
X1003783Y211554D01*
X1003575Y211346D01*
X1003242Y211221D01*
X1002950Y211179D01*
G01X999850Y213679D02*
X1000183Y213596D01*
X1000433Y213387D01*
X1000600Y213137D01*
X1000725Y212804D01*
X1000767Y212429D01*
X1000725Y212054D01*
X1000600Y211721D01*
X1000433Y211471D01*
X1000183Y211262D01*
X999850Y211179D01*
X999517Y211262D01*
X999267Y211471D01*
X999100Y211721D01*
X998975Y212054D01*
X998933Y212429D01*
X998975Y212804D01*
X999100Y213137D01*
X999267Y213387D01*
X999517Y213596D01*
X999850Y213679D01*
G01X1008233Y217421D02*
X1008483Y217546D01*
X1008775Y217629D01*
X1009108D01*
X1009483Y217504D01*
X1009775Y217296D01*
X1009983Y217046D01*
X1010150Y216629D01*
X1010192Y216254D01*
X1010108Y215879D01*
X1009983Y215629D01*
X1009733Y215379D01*
X1009442Y215212D01*
X1009150Y215129D01*
X1008858D01*
X1008567Y215212D01*
X1008317Y215337D01*
X1008108Y215504D01*
G01X1006967D02*
X1006717Y215296D01*
X1006425Y215171D01*
X1006050Y215129D01*
X1005675Y215212D01*
X1005383Y215379D01*
X1005175Y215671D01*
X1005133Y216004D01*
X1005217Y216337D01*
X1005425Y216546D01*
X1005717Y216712D01*
X1006008Y216754D01*
X1006300Y216712D01*
X1006675Y216546D01*
X1006550Y217629D01*
X1005425D01*
G01X1003033Y215129D02*
X1002950Y215671D01*
X1002825Y216129D01*
X1002658Y216546D01*
X1002450Y217004D01*
X1002117Y217629D01*
X1003783D01*
G01X1000558Y215421D02*
X1000267Y215212D01*
X999933Y215129D01*
X999600Y215212D01*
X999308Y215462D01*
X999100Y215837D01*
X999017Y216212D01*
Y216671D01*
X999100Y217046D01*
X999308Y217379D01*
X999558Y217546D01*
X999850Y217629D01*
X1000183Y217546D01*
X1000433Y217379D01*
X1000600Y217129D01*
X1000683Y216796D01*
X1000600Y216504D01*
X1000392Y216212D01*
X1000142Y216046D01*
X999850Y216004D01*
X999517Y216087D01*
X999267Y216296D01*
X999017Y216671D01*
G01X1008233Y233153D02*
X1008483Y233278D01*
X1008775Y233361D01*
X1009108D01*
X1009483Y233236D01*
X1009775Y233028D01*
X1009983Y232778D01*
X1010150Y232361D01*
X1010192Y231986D01*
X1010108Y231611D01*
X1009983Y231361D01*
X1009733Y231111D01*
X1009442Y230944D01*
X1009150Y230861D01*
X1008858D01*
X1008567Y230944D01*
X1008317Y231069D01*
X1008108Y231236D01*
G01X1006967D02*
X1006717Y231028D01*
X1006425Y230903D01*
X1006050Y230861D01*
X1005675Y230944D01*
X1005383Y231111D01*
X1005175Y231403D01*
X1005133Y231736D01*
X1005217Y232069D01*
X1005425Y232278D01*
X1005717Y232444D01*
X1006008Y232486D01*
X1006300Y232444D01*
X1006675Y232278D01*
X1006550Y233361D01*
X1005425D01*
G01X1003033Y230861D02*
X1002950Y231403D01*
X1002825Y231861D01*
X1002658Y232278D01*
X1002450Y232736D01*
X1002117Y233361D01*
X1003783D01*
G01X999850Y230861D02*
X999558Y230903D01*
X999225Y231028D01*
X999017Y231236D01*
X998933Y231528D01*
X999017Y231819D01*
X999267Y232069D01*
X999642Y232194D01*
X1000058D01*
X1000308Y232278D01*
X1000517Y232486D01*
X1000600Y232778D01*
X1000475Y233069D01*
X1000183Y233278D01*
X999850Y233361D01*
X999517Y233278D01*
X999225Y233069D01*
X999100Y232778D01*
X999183Y232486D01*
X999392Y232278D01*
X999642Y232194D01*
X1000058D01*
X1000433Y232069D01*
X1000683Y231819D01*
X1000767Y231528D01*
X1000683Y231236D01*
X1000475Y231028D01*
X1000142Y230903D01*
X999850Y230861D01*
G01X1008233Y229221D02*
X1008483Y229346D01*
X1008775Y229429D01*
X1009108D01*
X1009483Y229304D01*
X1009775Y229096D01*
X1009983Y228846D01*
X1010150Y228429D01*
X1010192Y228054D01*
X1010108Y227679D01*
X1009983Y227429D01*
X1009733Y227179D01*
X1009442Y227012D01*
X1009150Y226929D01*
X1008858D01*
X1008567Y227012D01*
X1008317Y227137D01*
X1008108Y227304D01*
G01X1006967D02*
X1006717Y227096D01*
X1006425Y226971D01*
X1006050Y226929D01*
X1005675Y227012D01*
X1005383Y227179D01*
X1005175Y227471D01*
X1005133Y227804D01*
X1005217Y228137D01*
X1005425Y228346D01*
X1005717Y228512D01*
X1006008Y228554D01*
X1006300Y228512D01*
X1006675Y228346D01*
X1006550Y229429D01*
X1005425D01*
G01X1002450Y226929D02*
Y229429D01*
X1003992Y227637D01*
X1001908D01*
G01X999850Y226929D02*
X999558Y226971D01*
X999225Y227096D01*
X999017Y227304D01*
X998933Y227596D01*
X999017Y227887D01*
X999267Y228137D01*
X999642Y228262D01*
X1000058D01*
X1000308Y228346D01*
X1000517Y228554D01*
X1000600Y228846D01*
X1000475Y229137D01*
X1000183Y229346D01*
X999850Y229429D01*
X999517Y229346D01*
X999225Y229137D01*
X999100Y228846D01*
X999183Y228554D01*
X999392Y228346D01*
X999642Y228262D01*
X1000058D01*
X1000433Y228137D01*
X1000683Y227887D01*
X1000767Y227596D01*
X1000683Y227304D01*
X1000475Y227096D01*
X1000142Y226971D01*
X999850Y226929D01*
G01X987233Y221292D02*
X987483Y221417D01*
X987775Y221500D01*
X988108D01*
X988483Y221375D01*
X988775Y221167D01*
X988983Y220917D01*
X989150Y220500D01*
X989192Y220125D01*
X989108Y219750D01*
X988983Y219500D01*
X988733Y219250D01*
X988442Y219083D01*
X988150Y219000D01*
X987858D01*
X987567Y219083D01*
X987317Y219208D01*
X987108Y219375D01*
G01X984550Y219000D02*
Y221500D01*
X986092Y219708D01*
X984008D01*
G01X981950Y219000D02*
X981658Y219042D01*
X981325Y219167D01*
X981117Y219375D01*
X981033Y219667D01*
X981117Y219958D01*
X981367Y220208D01*
X981742Y220333D01*
X982158D01*
X982408Y220417D01*
X982617Y220625D01*
X982700Y220917D01*
X982575Y221208D01*
X982283Y221417D01*
X981950Y221500D01*
X981617Y221417D01*
X981325Y221208D01*
X981200Y220917D01*
X981283Y220625D01*
X981492Y220417D01*
X981742Y220333D01*
X982158D01*
X982533Y220208D01*
X982783Y219958D01*
X982867Y219667D01*
X982783Y219375D01*
X982575Y219167D01*
X982242Y219042D01*
X981950Y219000D01*
G01X978850D02*
X978558Y219042D01*
X978225Y219167D01*
X978017Y219375D01*
X977933Y219667D01*
X978017Y219958D01*
X978267Y220208D01*
X978642Y220333D01*
X979058D01*
X979308Y220417D01*
X979517Y220625D01*
X979600Y220917D01*
X979475Y221208D01*
X979183Y221417D01*
X978850Y221500D01*
X978517Y221417D01*
X978225Y221208D01*
X978100Y220917D01*
X978183Y220625D01*
X978392Y220417D01*
X978642Y220333D01*
X979058D01*
X979433Y220208D01*
X979683Y219958D01*
X979767Y219667D01*
X979683Y219375D01*
X979475Y219167D01*
X979142Y219042D01*
X978850Y219000D01*
G01X984183Y213792D02*
X984433Y213917D01*
X984725Y214000D01*
X985058D01*
X985433Y213875D01*
X985725Y213667D01*
X985933Y213417D01*
X986100Y213000D01*
X986142Y212625D01*
X986058Y212250D01*
X985933Y212000D01*
X985683Y211750D01*
X985392Y211583D01*
X985100Y211500D01*
X984808D01*
X984517Y211583D01*
X984267Y211708D01*
X984058Y211875D01*
G01X982917Y212000D02*
X982667Y211708D01*
X982333Y211542D01*
X981958Y211500D01*
X981625Y211542D01*
X981292Y211750D01*
X981083Y212000D01*
X981042Y212250D01*
X981125Y212542D01*
X981417Y212750D01*
X981708Y212833D01*
X982083D01*
G01X981708D02*
X981458Y212958D01*
X981250Y213167D01*
X981167Y213417D01*
X981250Y213667D01*
X981458Y213875D01*
X981833Y214000D01*
X982208Y213958D01*
X982583Y213792D01*
G01X978983Y211500D02*
X978900Y212042D01*
X978775Y212500D01*
X978608Y212917D01*
X978400Y213375D01*
X978067Y214000D01*
X979733D01*
G01X987733Y268453D02*
X987983Y268578D01*
X988275Y268661D01*
X988608D01*
X988983Y268536D01*
X989275Y268328D01*
X989483Y268078D01*
X989650Y267661D01*
X989692Y267286D01*
X989608Y266911D01*
X989483Y266661D01*
X989233Y266411D01*
X988942Y266244D01*
X988650Y266161D01*
X988358D01*
X988067Y266244D01*
X987817Y266369D01*
X987608Y266536D01*
G01X986467D02*
X986217Y266328D01*
X985925Y266203D01*
X985550Y266161D01*
X985175Y266244D01*
X984883Y266411D01*
X984675Y266703D01*
X984633Y267036D01*
X984717Y267369D01*
X984925Y267578D01*
X985217Y267744D01*
X985508Y267786D01*
X985800Y267744D01*
X986175Y267578D01*
X986050Y268661D01*
X984925D01*
G01X982450D02*
X982783Y268578D01*
X983033Y268369D01*
X983200Y268119D01*
X983325Y267786D01*
X983367Y267411D01*
X983325Y267036D01*
X983200Y266703D01*
X983033Y266453D01*
X982783Y266244D01*
X982450Y266161D01*
X982117Y266244D01*
X981867Y266453D01*
X981700Y266703D01*
X981575Y267036D01*
X981533Y267411D01*
X981575Y267786D01*
X981700Y268119D01*
X981867Y268369D01*
X982117Y268578D01*
X982450Y268661D01*
G01X979433Y266161D02*
X979350Y266703D01*
X979225Y267161D01*
X979058Y267578D01*
X978850Y268036D01*
X978517Y268661D01*
X980183D01*
G01X987733Y276453D02*
X987983Y276578D01*
X988275Y276661D01*
X988608D01*
X988983Y276536D01*
X989275Y276328D01*
X989483Y276078D01*
X989650Y275661D01*
X989692Y275286D01*
X989608Y274911D01*
X989483Y274661D01*
X989233Y274411D01*
X988942Y274244D01*
X988650Y274161D01*
X988358D01*
X988067Y274244D01*
X987817Y274369D01*
X987608Y274536D01*
G01X985050Y274161D02*
Y276661D01*
X986592Y274869D01*
X984508D01*
G01X983158Y274453D02*
X982867Y274244D01*
X982533Y274161D01*
X982200Y274244D01*
X981908Y274494D01*
X981700Y274869D01*
X981617Y275244D01*
Y275703D01*
X981700Y276078D01*
X981908Y276411D01*
X982158Y276578D01*
X982450Y276661D01*
X982783Y276578D01*
X983033Y276411D01*
X983200Y276161D01*
X983283Y275828D01*
X983200Y275536D01*
X982992Y275244D01*
X982742Y275078D01*
X982450Y275036D01*
X982117Y275119D01*
X981867Y275328D01*
X981617Y275703D01*
G01X980267Y274536D02*
X980017Y274328D01*
X979725Y274203D01*
X979350Y274161D01*
X978975Y274244D01*
X978683Y274411D01*
X978475Y274703D01*
X978433Y275036D01*
X978517Y275369D01*
X978725Y275578D01*
X979017Y275744D01*
X979308Y275786D01*
X979600Y275744D01*
X979975Y275578D01*
X979850Y276661D01*
X978725D01*
G01X988181Y287207D02*
X988431Y287332D01*
X988723Y287415D01*
X989056D01*
X989431Y287290D01*
X989723Y287082D01*
X989931Y286832D01*
X990098Y286415D01*
X990140Y286040D01*
X990056Y285665D01*
X989931Y285415D01*
X989681Y285165D01*
X989390Y284998D01*
X989098Y284915D01*
X988806D01*
X988515Y284998D01*
X988265Y285123D01*
X988056Y285290D01*
G01X986915D02*
X986665Y285082D01*
X986373Y284957D01*
X985998Y284915D01*
X985623Y284998D01*
X985331Y285165D01*
X985123Y285457D01*
X985081Y285790D01*
X985165Y286123D01*
X985373Y286332D01*
X985665Y286498D01*
X985956Y286540D01*
X986248Y286498D01*
X986623Y286332D01*
X986498Y287415D01*
X985373D01*
G01X982898Y284915D02*
Y287415D01*
X983398Y286915D01*
G01Y284915D02*
X982398D01*
G01X979881D02*
X979798Y285457D01*
X979673Y285915D01*
X979506Y286332D01*
X979298Y286790D01*
X978965Y287415D01*
X980631D01*
G01X1039863Y948D02*
Y4948D01*
X1047263D01*
G01X1032281Y842D02*
Y4842D01*
X1039681D01*
G01X1042140Y5563D02*
X1038140D01*
Y12963D01*
G01X1037830Y5519D02*
X1033830D01*
Y12919D01*
G01X1046147Y8390D02*
X1042147D01*
Y15790D01*
G01X1042161Y23268D02*
X1046161D01*
Y15868D01*
G01X1048900Y38615D02*
Y34615D01*
X1041500D01*
G01X1020379Y33670D02*
X1021379Y34670D01*
G01X1019379D02*
X1020379Y33670D01*
G01X1022579Y34670D02*
X1018179D01*
G01X1022579Y19870D02*
Y34670D01*
G01X1018179Y19870D02*
X1022579D01*
G01X1018179Y34670D02*
Y19870D01*
G01X1011600Y67817D02*
X1014100D01*
Y68858D01*
X1013975Y69192D01*
X1013808Y69400D01*
X1013475Y69483D01*
X1013142Y69400D01*
X1012933Y69150D01*
X1012808Y68858D01*
Y67817D01*
G01Y68858D02*
X1011600Y69483D01*
G01Y71750D02*
X1011642Y72042D01*
X1011767Y72375D01*
X1011975Y72583D01*
X1012267Y72667D01*
X1012558Y72583D01*
X1012808Y72333D01*
X1012933Y71958D01*
Y71542D01*
X1013017Y71292D01*
X1013225Y71083D01*
X1013517Y71000D01*
X1013808Y71125D01*
X1014017Y71417D01*
X1014100Y71750D01*
X1014017Y72083D01*
X1013808Y72375D01*
X1013517Y72500D01*
X1013225Y72417D01*
X1013017Y72208D01*
X1012933Y71958D01*
Y71542D01*
X1012808Y71167D01*
X1012558Y70917D01*
X1012267Y70833D01*
X1011975Y70917D01*
X1011767Y71125D01*
X1011642Y71458D01*
X1011600Y71750D01*
G01Y74850D02*
X1014100D01*
X1013600Y74350D01*
G01X1011600D02*
Y75350D01*
G01Y77867D02*
X1012142Y77950D01*
X1012600Y78075D01*
X1013017Y78242D01*
X1013475Y78450D01*
X1014100Y78783D01*
Y77117D01*
G01X1025100Y67817D02*
X1027600D01*
Y68858D01*
X1027475Y69192D01*
X1027308Y69400D01*
X1026975Y69483D01*
X1026642Y69400D01*
X1026433Y69150D01*
X1026308Y68858D01*
Y67817D01*
G01Y68858D02*
X1025100Y69483D01*
G01Y71750D02*
X1025142Y72042D01*
X1025267Y72375D01*
X1025475Y72583D01*
X1025767Y72667D01*
X1026058Y72583D01*
X1026308Y72333D01*
X1026433Y71958D01*
Y71542D01*
X1026517Y71292D01*
X1026725Y71083D01*
X1027017Y71000D01*
X1027308Y71125D01*
X1027517Y71417D01*
X1027600Y71750D01*
X1027517Y72083D01*
X1027308Y72375D01*
X1027017Y72500D01*
X1026725Y72417D01*
X1026517Y72208D01*
X1026433Y71958D01*
Y71542D01*
X1026308Y71167D01*
X1026058Y70917D01*
X1025767Y70833D01*
X1025475Y70917D01*
X1025267Y71125D01*
X1025142Y71458D01*
X1025100Y71750D01*
G01Y74850D02*
X1027600D01*
X1027100Y74350D01*
G01X1025100D02*
Y75350D01*
G01X1025475Y77033D02*
X1025267Y77283D01*
X1025142Y77575D01*
X1025100Y77950D01*
X1025183Y78325D01*
X1025350Y78617D01*
X1025642Y78825D01*
X1025975Y78867D01*
X1026308Y78783D01*
X1026517Y78575D01*
X1026683Y78283D01*
X1026725Y77992D01*
X1026683Y77700D01*
X1026517Y77325D01*
X1027600Y77450D01*
Y78575D01*
G01X1020600Y67817D02*
X1023100D01*
Y68858D01*
X1022975Y69192D01*
X1022808Y69400D01*
X1022475Y69483D01*
X1022142Y69400D01*
X1021933Y69150D01*
X1021808Y68858D01*
Y67817D01*
G01Y68858D02*
X1020600Y69483D01*
G01Y71750D02*
X1020642Y72042D01*
X1020767Y72375D01*
X1020975Y72583D01*
X1021267Y72667D01*
X1021558Y72583D01*
X1021808Y72333D01*
X1021933Y71958D01*
Y71542D01*
X1022017Y71292D01*
X1022225Y71083D01*
X1022517Y71000D01*
X1022808Y71125D01*
X1023017Y71417D01*
X1023100Y71750D01*
X1023017Y72083D01*
X1022808Y72375D01*
X1022517Y72500D01*
X1022225Y72417D01*
X1022017Y72208D01*
X1021933Y71958D01*
Y71542D01*
X1021808Y71167D01*
X1021558Y70917D01*
X1021267Y70833D01*
X1020975Y70917D01*
X1020767Y71125D01*
X1020642Y71458D01*
X1020600Y71750D01*
G01Y74850D02*
X1023100D01*
X1022600Y74350D01*
G01X1020600D02*
Y75350D01*
G01X1021100Y77033D02*
X1020808Y77283D01*
X1020642Y77617D01*
X1020600Y77992D01*
X1020642Y78325D01*
X1020850Y78658D01*
X1021100Y78867D01*
X1021350Y78908D01*
X1021642Y78825D01*
X1021850Y78533D01*
X1021933Y78242D01*
Y77867D01*
G01Y78242D02*
X1022058Y78492D01*
X1022267Y78700D01*
X1022517Y78783D01*
X1022767Y78700D01*
X1022975Y78492D01*
X1023100Y78117D01*
X1023058Y77742D01*
X1022892Y77367D01*
G01X1043100Y67817D02*
X1045600D01*
Y68858D01*
X1045475Y69192D01*
X1045308Y69400D01*
X1044975Y69483D01*
X1044642Y69400D01*
X1044433Y69150D01*
X1044308Y68858D01*
Y67817D01*
G01Y68858D02*
X1043100Y69483D01*
G01Y71750D02*
X1043142Y72042D01*
X1043267Y72375D01*
X1043475Y72583D01*
X1043767Y72667D01*
X1044058Y72583D01*
X1044308Y72333D01*
X1044433Y71958D01*
Y71542D01*
X1044517Y71292D01*
X1044725Y71083D01*
X1045017Y71000D01*
X1045308Y71125D01*
X1045517Y71417D01*
X1045600Y71750D01*
X1045517Y72083D01*
X1045308Y72375D01*
X1045017Y72500D01*
X1044725Y72417D01*
X1044517Y72208D01*
X1044433Y71958D01*
Y71542D01*
X1044308Y71167D01*
X1044058Y70917D01*
X1043767Y70833D01*
X1043475Y70917D01*
X1043267Y71125D01*
X1043142Y71458D01*
X1043100Y71750D01*
G01Y74850D02*
X1045600D01*
X1045100Y74350D01*
G01X1043100D02*
Y75350D01*
G01Y77950D02*
X1045600D01*
X1045100Y77450D01*
G01X1043100D02*
Y78450D01*
G01X1016100Y67817D02*
X1018600D01*
Y68858D01*
X1018475Y69192D01*
X1018308Y69400D01*
X1017975Y69483D01*
X1017642Y69400D01*
X1017433Y69150D01*
X1017308Y68858D01*
Y67817D01*
G01Y68858D02*
X1016100Y69483D01*
G01Y71750D02*
X1016142Y72042D01*
X1016267Y72375D01*
X1016475Y72583D01*
X1016767Y72667D01*
X1017058Y72583D01*
X1017308Y72333D01*
X1017433Y71958D01*
Y71542D01*
X1017517Y71292D01*
X1017725Y71083D01*
X1018017Y71000D01*
X1018308Y71125D01*
X1018517Y71417D01*
X1018600Y71750D01*
X1018517Y72083D01*
X1018308Y72375D01*
X1018017Y72500D01*
X1017725Y72417D01*
X1017517Y72208D01*
X1017433Y71958D01*
Y71542D01*
X1017308Y71167D01*
X1017058Y70917D01*
X1016767Y70833D01*
X1016475Y70917D01*
X1016267Y71125D01*
X1016142Y71458D01*
X1016100Y71750D01*
G01X1018600Y74850D02*
X1018517Y74517D01*
X1018308Y74267D01*
X1018058Y74100D01*
X1017725Y73975D01*
X1017350Y73933D01*
X1016975Y73975D01*
X1016642Y74100D01*
X1016392Y74267D01*
X1016183Y74517D01*
X1016100Y74850D01*
X1016183Y75183D01*
X1016392Y75433D01*
X1016642Y75600D01*
X1016975Y75725D01*
X1017350Y75767D01*
X1017725Y75725D01*
X1018058Y75600D01*
X1018308Y75433D01*
X1018517Y75183D01*
X1018600Y74850D01*
G01X1016392Y77242D02*
X1016183Y77533D01*
X1016100Y77867D01*
X1016183Y78200D01*
X1016433Y78492D01*
X1016808Y78700D01*
X1017183Y78783D01*
X1017642D01*
X1018017Y78700D01*
X1018350Y78492D01*
X1018517Y78242D01*
X1018600Y77950D01*
X1018517Y77617D01*
X1018350Y77367D01*
X1018100Y77200D01*
X1017767Y77117D01*
X1017475Y77200D01*
X1017183Y77408D01*
X1017017Y77658D01*
X1016975Y77950D01*
X1017058Y78283D01*
X1017267Y78533D01*
X1017642Y78783D01*
G01X1038600Y67817D02*
X1041100D01*
Y68858D01*
X1040975Y69192D01*
X1040808Y69400D01*
X1040475Y69483D01*
X1040142Y69400D01*
X1039933Y69150D01*
X1039808Y68858D01*
Y67817D01*
G01Y68858D02*
X1038600Y69483D01*
G01Y71750D02*
X1038642Y72042D01*
X1038767Y72375D01*
X1038975Y72583D01*
X1039267Y72667D01*
X1039558Y72583D01*
X1039808Y72333D01*
X1039933Y71958D01*
Y71542D01*
X1040017Y71292D01*
X1040225Y71083D01*
X1040517Y71000D01*
X1040808Y71125D01*
X1041017Y71417D01*
X1041100Y71750D01*
X1041017Y72083D01*
X1040808Y72375D01*
X1040517Y72500D01*
X1040225Y72417D01*
X1040017Y72208D01*
X1039933Y71958D01*
Y71542D01*
X1039808Y71167D01*
X1039558Y70917D01*
X1039267Y70833D01*
X1038975Y70917D01*
X1038767Y71125D01*
X1038642Y71458D01*
X1038600Y71750D01*
G01X1041100Y74850D02*
X1041017Y74517D01*
X1040808Y74267D01*
X1040558Y74100D01*
X1040225Y73975D01*
X1039850Y73933D01*
X1039475Y73975D01*
X1039142Y74100D01*
X1038892Y74267D01*
X1038683Y74517D01*
X1038600Y74850D01*
X1038683Y75183D01*
X1038892Y75433D01*
X1039142Y75600D01*
X1039475Y75725D01*
X1039850Y75767D01*
X1040225Y75725D01*
X1040558Y75600D01*
X1040808Y75433D01*
X1041017Y75183D01*
X1041100Y74850D01*
G01X1038600Y77867D02*
X1039142Y77950D01*
X1039600Y78075D01*
X1040017Y78242D01*
X1040475Y78450D01*
X1041100Y78783D01*
Y77117D01*
G01X1029600Y67817D02*
X1032100D01*
Y68858D01*
X1031975Y69192D01*
X1031808Y69400D01*
X1031475Y69483D01*
X1031142Y69400D01*
X1030933Y69150D01*
X1030808Y68858D01*
Y67817D01*
G01Y68858D02*
X1029600Y69483D01*
G01Y71667D02*
X1030142Y71750D01*
X1030600Y71875D01*
X1031017Y72042D01*
X1031475Y72250D01*
X1032100Y72583D01*
Y70917D01*
G01X1029892Y74142D02*
X1029683Y74433D01*
X1029600Y74767D01*
X1029683Y75100D01*
X1029933Y75392D01*
X1030308Y75600D01*
X1030683Y75683D01*
X1031142D01*
X1031517Y75600D01*
X1031850Y75392D01*
X1032017Y75142D01*
X1032100Y74850D01*
X1032017Y74517D01*
X1031850Y74267D01*
X1031600Y74100D01*
X1031267Y74017D01*
X1030975Y74100D01*
X1030683Y74308D01*
X1030517Y74558D01*
X1030475Y74850D01*
X1030558Y75183D01*
X1030767Y75433D01*
X1031142Y75683D01*
G01X1029600Y77867D02*
X1030142Y77950D01*
X1030600Y78075D01*
X1031017Y78242D01*
X1031475Y78450D01*
X1032100Y78783D01*
Y77117D01*
G01X1034100Y67817D02*
X1036600D01*
Y68858D01*
X1036475Y69192D01*
X1036308Y69400D01*
X1035975Y69483D01*
X1035642Y69400D01*
X1035433Y69150D01*
X1035308Y68858D01*
Y67817D01*
G01Y68858D02*
X1034100Y69483D01*
G01Y71667D02*
X1034642Y71750D01*
X1035100Y71875D01*
X1035517Y72042D01*
X1035975Y72250D01*
X1036600Y72583D01*
Y70917D01*
G01X1034392Y74142D02*
X1034183Y74433D01*
X1034100Y74767D01*
X1034183Y75100D01*
X1034433Y75392D01*
X1034808Y75600D01*
X1035183Y75683D01*
X1035642D01*
X1036017Y75600D01*
X1036350Y75392D01*
X1036517Y75142D01*
X1036600Y74850D01*
X1036517Y74517D01*
X1036350Y74267D01*
X1036100Y74100D01*
X1035767Y74017D01*
X1035475Y74100D01*
X1035183Y74308D01*
X1035017Y74558D01*
X1034975Y74850D01*
X1035058Y75183D01*
X1035267Y75433D01*
X1035642Y75683D01*
G01X1034475Y77033D02*
X1034267Y77283D01*
X1034142Y77575D01*
X1034100Y77950D01*
X1034183Y78325D01*
X1034350Y78617D01*
X1034642Y78825D01*
X1034975Y78867D01*
X1035308Y78783D01*
X1035517Y78575D01*
X1035683Y78283D01*
X1035725Y77992D01*
X1035683Y77700D01*
X1035517Y77325D01*
X1036600Y77450D01*
Y78575D01*
G01X1022546Y59597D02*
Y55597D01*
X1015146D01*
G01X1022844Y45065D02*
Y43273D01*
X1022677Y42898D01*
X1022344Y42648D01*
X1021927Y42565D01*
X1021510Y42648D01*
X1021177Y42898D01*
X1021010Y43273D01*
Y45065D01*
G01X1018827Y42565D02*
Y45065D01*
X1019327Y44565D01*
G01Y42565D02*
X1018327D01*
G01X1016644Y42940D02*
X1016394Y42732D01*
X1016102Y42607D01*
X1015727Y42565D01*
X1015352Y42648D01*
X1015060Y42815D01*
X1014852Y43107D01*
X1014810Y43440D01*
X1014894Y43773D01*
X1015102Y43982D01*
X1015394Y44148D01*
X1015685Y44190D01*
X1015977Y44148D01*
X1016352Y43982D01*
X1016227Y45065D01*
X1015102D01*
G01X1023500Y46900D02*
Y60900D01*
G01X1036500Y46900D02*
X1023500D01*
G01X1036500Y60900D02*
Y46900D01*
G01X1023500Y60900D02*
X1036500D01*
G01X1041600Y97967D02*
Y95467D01*
G01X1042558Y97967D02*
X1040642D01*
G01X1039333Y95467D02*
Y97967D01*
X1038333D01*
X1038000Y97842D01*
X1037750Y97550D01*
X1037667Y97217D01*
X1037750Y96884D01*
X1037958Y96634D01*
X1038333Y96509D01*
X1039333D01*
G01X1036192Y97550D02*
X1035942Y97800D01*
X1035650Y97925D01*
X1035317Y97967D01*
X1034900Y97884D01*
X1034608Y97675D01*
X1034525Y97425D01*
X1034567Y97175D01*
X1034733Y96967D01*
X1035567Y96550D01*
X1035942Y96259D01*
X1036192Y95842D01*
X1036275Y95467D01*
X1034525D01*
G01X1032300D02*
X1032008Y95509D01*
X1031675Y95634D01*
X1031467Y95842D01*
X1031383Y96134D01*
X1031467Y96425D01*
X1031717Y96675D01*
X1032092Y96800D01*
X1032508D01*
X1032758Y96884D01*
X1032967Y97092D01*
X1033050Y97384D01*
X1032925Y97675D01*
X1032633Y97884D01*
X1032300Y97967D01*
X1031967Y97884D01*
X1031675Y97675D01*
X1031550Y97384D01*
X1031633Y97092D01*
X1031842Y96884D01*
X1032092Y96800D01*
X1032508D01*
X1032883Y96675D01*
X1033133Y96425D01*
X1033217Y96134D01*
X1033133Y95842D01*
X1032925Y95634D01*
X1032592Y95509D01*
X1032300Y95467D01*
G01X1029283D02*
X1029200Y96009D01*
X1029075Y96467D01*
X1028908Y96884D01*
X1028700Y97342D01*
X1028367Y97967D01*
X1030033D01*
G01X1039216Y102524D02*
Y100024D01*
G01X1040174Y102524D02*
X1038258D01*
G01X1036949Y100024D02*
Y102524D01*
X1035949D01*
X1035616Y102399D01*
X1035366Y102107D01*
X1035283Y101774D01*
X1035366Y101441D01*
X1035574Y101191D01*
X1035949Y101066D01*
X1036949D01*
G01X1033808Y102107D02*
X1033558Y102357D01*
X1033266Y102482D01*
X1032933Y102524D01*
X1032516Y102441D01*
X1032224Y102232D01*
X1032141Y101982D01*
X1032183Y101732D01*
X1032349Y101524D01*
X1033183Y101107D01*
X1033558Y100816D01*
X1033808Y100399D01*
X1033891Y100024D01*
X1032141D01*
G01X1029916D02*
X1029624Y100066D01*
X1029291Y100191D01*
X1029083Y100399D01*
X1028999Y100691D01*
X1029083Y100982D01*
X1029333Y101232D01*
X1029708Y101357D01*
X1030124D01*
X1030374Y101441D01*
X1030583Y101649D01*
X1030666Y101941D01*
X1030541Y102232D01*
X1030249Y102441D01*
X1029916Y102524D01*
X1029583Y102441D01*
X1029291Y102232D01*
X1029166Y101941D01*
X1029249Y101649D01*
X1029458Y101441D01*
X1029708Y101357D01*
X1030124D01*
X1030499Y101232D01*
X1030749Y100982D01*
X1030833Y100691D01*
X1030749Y100399D01*
X1030541Y100191D01*
X1030208Y100066D01*
X1029916Y100024D01*
G01X1027608Y101066D02*
X1027316Y101357D01*
X1027066Y101524D01*
X1026733Y101607D01*
X1026441Y101524D01*
X1026233Y101357D01*
X1026066Y101107D01*
X1026024Y100816D01*
X1026066Y100566D01*
X1026233Y100316D01*
X1026483Y100107D01*
X1026774Y100024D01*
X1027108Y100107D01*
X1027399Y100357D01*
X1027566Y100732D01*
X1027608Y101149D01*
X1027524Y101691D01*
X1027399Y101982D01*
X1027191Y102274D01*
X1026899Y102482D01*
X1026608Y102524D01*
X1026316Y102441D01*
X1026108Y102232D01*
G01X1024207Y105939D02*
Y103439D01*
G01X1025165Y105939D02*
X1023249D01*
G01X1021940Y103439D02*
Y105939D01*
X1020940D01*
X1020607Y105814D01*
X1020357Y105522D01*
X1020274Y105189D01*
X1020357Y104856D01*
X1020565Y104606D01*
X1020940Y104481D01*
X1021940D01*
G01X1018924Y103939D02*
X1018674Y103647D01*
X1018340Y103481D01*
X1017965Y103439D01*
X1017632Y103481D01*
X1017299Y103689D01*
X1017090Y103939D01*
X1017049Y104189D01*
X1017132Y104481D01*
X1017424Y104689D01*
X1017715Y104772D01*
X1018090D01*
G01X1017715D02*
X1017465Y104897D01*
X1017257Y105106D01*
X1017174Y105356D01*
X1017257Y105606D01*
X1017465Y105814D01*
X1017840Y105939D01*
X1018215Y105897D01*
X1018590Y105731D01*
G01X1014907Y105939D02*
X1015240Y105856D01*
X1015490Y105647D01*
X1015657Y105397D01*
X1015782Y105064D01*
X1015824Y104689D01*
X1015782Y104314D01*
X1015657Y103981D01*
X1015490Y103731D01*
X1015240Y103522D01*
X1014907Y103439D01*
X1014574Y103522D01*
X1014324Y103731D01*
X1014157Y103981D01*
X1014032Y104314D01*
X1013990Y104689D01*
X1014032Y105064D01*
X1014157Y105397D01*
X1014324Y105647D01*
X1014574Y105856D01*
X1014907Y105939D01*
G01X1011307Y103439D02*
Y105939D01*
X1012849Y104147D01*
X1010765D01*
G01X1023677Y98021D02*
Y95521D01*
G01X1024635Y98021D02*
X1022719D01*
G01X1021410Y95521D02*
Y98021D01*
X1020410D01*
X1020077Y97896D01*
X1019827Y97604D01*
X1019744Y97271D01*
X1019827Y96938D01*
X1020035Y96688D01*
X1020410Y96563D01*
X1021410D01*
G01X1018394Y96021D02*
X1018144Y95729D01*
X1017810Y95563D01*
X1017435Y95521D01*
X1017102Y95563D01*
X1016769Y95771D01*
X1016560Y96021D01*
X1016519Y96271D01*
X1016602Y96563D01*
X1016894Y96771D01*
X1017185Y96854D01*
X1017560D01*
G01X1017185D02*
X1016935Y96979D01*
X1016727Y97188D01*
X1016644Y97438D01*
X1016727Y97688D01*
X1016935Y97896D01*
X1017310Y98021D01*
X1017685Y97979D01*
X1018060Y97813D01*
G01X1014377Y98021D02*
X1014710Y97938D01*
X1014960Y97729D01*
X1015127Y97479D01*
X1015252Y97146D01*
X1015294Y96771D01*
X1015252Y96396D01*
X1015127Y96063D01*
X1014960Y95813D01*
X1014710Y95604D01*
X1014377Y95521D01*
X1014044Y95604D01*
X1013794Y95813D01*
X1013627Y96063D01*
X1013502Y96396D01*
X1013460Y96771D01*
X1013502Y97146D01*
X1013627Y97479D01*
X1013794Y97729D01*
X1014044Y97938D01*
X1014377Y98021D01*
G01X1012194Y96021D02*
X1011944Y95729D01*
X1011610Y95563D01*
X1011235Y95521D01*
X1010902Y95563D01*
X1010569Y95771D01*
X1010360Y96021D01*
X1010319Y96271D01*
X1010402Y96563D01*
X1010694Y96771D01*
X1010985Y96854D01*
X1011360D01*
G01X1010985D02*
X1010735Y96979D01*
X1010527Y97188D01*
X1010444Y97438D01*
X1010527Y97688D01*
X1010735Y97896D01*
X1011110Y98021D01*
X1011485Y97979D01*
X1011860Y97813D01*
G01X1037161Y82017D02*
X1039661D01*
Y83058D01*
X1039536Y83392D01*
X1039369Y83600D01*
X1039036Y83683D01*
X1038703Y83600D01*
X1038494Y83350D01*
X1038369Y83058D01*
Y82017D01*
G01Y83058D02*
X1037161Y83683D01*
G01Y85950D02*
X1037203Y86242D01*
X1037328Y86575D01*
X1037536Y86783D01*
X1037828Y86867D01*
X1038119Y86783D01*
X1038369Y86533D01*
X1038494Y86158D01*
Y85742D01*
X1038578Y85492D01*
X1038786Y85283D01*
X1039078Y85200D01*
X1039369Y85325D01*
X1039578Y85617D01*
X1039661Y85950D01*
X1039578Y86283D01*
X1039369Y86575D01*
X1039078Y86700D01*
X1038786Y86617D01*
X1038578Y86408D01*
X1038494Y86158D01*
Y85742D01*
X1038369Y85367D01*
X1038119Y85117D01*
X1037828Y85033D01*
X1037536Y85117D01*
X1037328Y85325D01*
X1037203Y85658D01*
X1037161Y85950D01*
G01Y89050D02*
X1039661D01*
X1039161Y88550D01*
G01X1037161D02*
Y89550D01*
G01X1039661Y92150D02*
X1039578Y91817D01*
X1039369Y91567D01*
X1039119Y91400D01*
X1038786Y91275D01*
X1038411Y91233D01*
X1038036Y91275D01*
X1037703Y91400D01*
X1037453Y91567D01*
X1037244Y91817D01*
X1037161Y92150D01*
X1037244Y92483D01*
X1037453Y92733D01*
X1037703Y92900D01*
X1038036Y93025D01*
X1038411Y93067D01*
X1038786Y93025D01*
X1039119Y92900D01*
X1039369Y92733D01*
X1039578Y92483D01*
X1039661Y92150D01*
G01X1032661Y82017D02*
X1035161D01*
Y83058D01*
X1035036Y83392D01*
X1034869Y83600D01*
X1034536Y83683D01*
X1034203Y83600D01*
X1033994Y83350D01*
X1033869Y83058D01*
Y82017D01*
G01Y83058D02*
X1032661Y83683D01*
G01Y85867D02*
X1033203Y85950D01*
X1033661Y86075D01*
X1034078Y86242D01*
X1034536Y86450D01*
X1035161Y86783D01*
Y85117D01*
G01X1032953Y88342D02*
X1032744Y88633D01*
X1032661Y88967D01*
X1032744Y89300D01*
X1032994Y89592D01*
X1033369Y89800D01*
X1033744Y89883D01*
X1034203D01*
X1034578Y89800D01*
X1034911Y89592D01*
X1035078Y89342D01*
X1035161Y89050D01*
X1035078Y88717D01*
X1034911Y88467D01*
X1034661Y88300D01*
X1034328Y88217D01*
X1034036Y88300D01*
X1033744Y88508D01*
X1033578Y88758D01*
X1033536Y89050D01*
X1033619Y89383D01*
X1033828Y89633D01*
X1034203Y89883D01*
G01X1032661Y92150D02*
X1032703Y92442D01*
X1032828Y92775D01*
X1033036Y92983D01*
X1033328Y93067D01*
X1033619Y92983D01*
X1033869Y92733D01*
X1033994Y92358D01*
Y91942D01*
X1034078Y91692D01*
X1034286Y91483D01*
X1034578Y91400D01*
X1034869Y91525D01*
X1035078Y91817D01*
X1035161Y92150D01*
X1035078Y92483D01*
X1034869Y92775D01*
X1034578Y92900D01*
X1034286Y92817D01*
X1034078Y92608D01*
X1033994Y92358D01*
Y91942D01*
X1033869Y91567D01*
X1033619Y91317D01*
X1033328Y91233D01*
X1033036Y91317D01*
X1032828Y91525D01*
X1032703Y91858D01*
X1032661Y92150D01*
G01X1028161Y82017D02*
X1030661D01*
Y83058D01*
X1030536Y83392D01*
X1030369Y83600D01*
X1030036Y83683D01*
X1029703Y83600D01*
X1029494Y83350D01*
X1029369Y83058D01*
Y82017D01*
G01Y83058D02*
X1028161Y83683D01*
G01Y85867D02*
X1028703Y85950D01*
X1029161Y86075D01*
X1029578Y86242D01*
X1030036Y86450D01*
X1030661Y86783D01*
Y85117D01*
G01X1028453Y88342D02*
X1028244Y88633D01*
X1028161Y88967D01*
X1028244Y89300D01*
X1028494Y89592D01*
X1028869Y89800D01*
X1029244Y89883D01*
X1029703D01*
X1030078Y89800D01*
X1030411Y89592D01*
X1030578Y89342D01*
X1030661Y89050D01*
X1030578Y88717D01*
X1030411Y88467D01*
X1030161Y88300D01*
X1029828Y88217D01*
X1029536Y88300D01*
X1029244Y88508D01*
X1029078Y88758D01*
X1029036Y89050D01*
X1029119Y89383D01*
X1029328Y89633D01*
X1029703Y89883D01*
G01X1028161Y92650D02*
X1030661D01*
X1028869Y91108D01*
Y93192D01*
G01X1019161Y82017D02*
X1021661D01*
Y83058D01*
X1021536Y83392D01*
X1021369Y83600D01*
X1021036Y83683D01*
X1020703Y83600D01*
X1020494Y83350D01*
X1020369Y83058D01*
Y82017D01*
G01Y83058D02*
X1019161Y83683D01*
G01Y85867D02*
X1019703Y85950D01*
X1020161Y86075D01*
X1020578Y86242D01*
X1021036Y86450D01*
X1021661Y86783D01*
Y85117D01*
G01X1019161Y89050D02*
X1019203Y89342D01*
X1019328Y89675D01*
X1019536Y89883D01*
X1019828Y89967D01*
X1020119Y89883D01*
X1020369Y89633D01*
X1020494Y89258D01*
Y88842D01*
X1020578Y88592D01*
X1020786Y88383D01*
X1021078Y88300D01*
X1021369Y88425D01*
X1021578Y88717D01*
X1021661Y89050D01*
X1021578Y89383D01*
X1021369Y89675D01*
X1021078Y89800D01*
X1020786Y89717D01*
X1020578Y89508D01*
X1020494Y89258D01*
Y88842D01*
X1020369Y88467D01*
X1020119Y88217D01*
X1019828Y88133D01*
X1019536Y88217D01*
X1019328Y88425D01*
X1019203Y88758D01*
X1019161Y89050D01*
G01Y92067D02*
X1019703Y92150D01*
X1020161Y92275D01*
X1020578Y92442D01*
X1021036Y92650D01*
X1021661Y92983D01*
Y91317D01*
G01X1014661Y82017D02*
X1017161D01*
Y83058D01*
X1017036Y83392D01*
X1016869Y83600D01*
X1016536Y83683D01*
X1016203Y83600D01*
X1015994Y83350D01*
X1015869Y83058D01*
Y82017D01*
G01Y83058D02*
X1014661Y83683D01*
G01Y85867D02*
X1015203Y85950D01*
X1015661Y86075D01*
X1016078Y86242D01*
X1016536Y86450D01*
X1017161Y86783D01*
Y85117D01*
G01X1014661Y89050D02*
X1014703Y89342D01*
X1014828Y89675D01*
X1015036Y89883D01*
X1015328Y89967D01*
X1015619Y89883D01*
X1015869Y89633D01*
X1015994Y89258D01*
Y88842D01*
X1016078Y88592D01*
X1016286Y88383D01*
X1016578Y88300D01*
X1016869Y88425D01*
X1017078Y88717D01*
X1017161Y89050D01*
X1017078Y89383D01*
X1016869Y89675D01*
X1016578Y89800D01*
X1016286Y89717D01*
X1016078Y89508D01*
X1015994Y89258D01*
Y88842D01*
X1015869Y88467D01*
X1015619Y88217D01*
X1015328Y88133D01*
X1015036Y88217D01*
X1014828Y88425D01*
X1014703Y88758D01*
X1014661Y89050D01*
G01X1015703Y91358D02*
X1015994Y91650D01*
X1016161Y91900D01*
X1016244Y92233D01*
X1016161Y92525D01*
X1015994Y92733D01*
X1015744Y92900D01*
X1015453Y92942D01*
X1015203Y92900D01*
X1014953Y92733D01*
X1014744Y92483D01*
X1014661Y92192D01*
X1014744Y91858D01*
X1014994Y91567D01*
X1015369Y91400D01*
X1015786Y91358D01*
X1016328Y91442D01*
X1016619Y91567D01*
X1016911Y91775D01*
X1017119Y92067D01*
X1017161Y92358D01*
X1017078Y92650D01*
X1016869Y92858D01*
G01X1010161Y82017D02*
X1012661D01*
Y83058D01*
X1012536Y83392D01*
X1012369Y83600D01*
X1012036Y83683D01*
X1011703Y83600D01*
X1011494Y83350D01*
X1011369Y83058D01*
Y82017D01*
G01Y83058D02*
X1010161Y83683D01*
G01Y85867D02*
X1010703Y85950D01*
X1011161Y86075D01*
X1011578Y86242D01*
X1012036Y86450D01*
X1012661Y86783D01*
Y85117D01*
G01X1010161Y89050D02*
X1010203Y89342D01*
X1010328Y89675D01*
X1010536Y89883D01*
X1010828Y89967D01*
X1011119Y89883D01*
X1011369Y89633D01*
X1011494Y89258D01*
Y88842D01*
X1011578Y88592D01*
X1011786Y88383D01*
X1012078Y88300D01*
X1012369Y88425D01*
X1012578Y88717D01*
X1012661Y89050D01*
X1012578Y89383D01*
X1012369Y89675D01*
X1012078Y89800D01*
X1011786Y89717D01*
X1011578Y89508D01*
X1011494Y89258D01*
Y88842D01*
X1011369Y88467D01*
X1011119Y88217D01*
X1010828Y88133D01*
X1010536Y88217D01*
X1010328Y88425D01*
X1010203Y88758D01*
X1010161Y89050D01*
G01Y92650D02*
X1012661D01*
X1010869Y91108D01*
Y93192D01*
G01X1023661Y82017D02*
X1026161D01*
Y83058D01*
X1026036Y83392D01*
X1025869Y83600D01*
X1025536Y83683D01*
X1025203Y83600D01*
X1024994Y83350D01*
X1024869Y83058D01*
Y82017D01*
G01Y83058D02*
X1023661Y83683D01*
G01Y85867D02*
X1024203Y85950D01*
X1024661Y86075D01*
X1025078Y86242D01*
X1025536Y86450D01*
X1026161Y86783D01*
Y85117D01*
G01X1023661Y89050D02*
X1023703Y89342D01*
X1023828Y89675D01*
X1024036Y89883D01*
X1024328Y89967D01*
X1024619Y89883D01*
X1024869Y89633D01*
X1024994Y89258D01*
Y88842D01*
X1025078Y88592D01*
X1025286Y88383D01*
X1025578Y88300D01*
X1025869Y88425D01*
X1026078Y88717D01*
X1026161Y89050D01*
X1026078Y89383D01*
X1025869Y89675D01*
X1025578Y89800D01*
X1025286Y89717D01*
X1025078Y89508D01*
X1024994Y89258D01*
Y88842D01*
X1024869Y88467D01*
X1024619Y88217D01*
X1024328Y88133D01*
X1024036Y88217D01*
X1023828Y88425D01*
X1023703Y88758D01*
X1023661Y89050D01*
G01X1025744Y91358D02*
X1025994Y91608D01*
X1026119Y91900D01*
X1026161Y92233D01*
X1026078Y92650D01*
X1025869Y92942D01*
X1025619Y93025D01*
X1025369Y92983D01*
X1025161Y92817D01*
X1024744Y91983D01*
X1024453Y91608D01*
X1024036Y91358D01*
X1023661Y91275D01*
Y93025D01*
G01X1041661Y82017D02*
X1044161D01*
Y83058D01*
X1044036Y83392D01*
X1043869Y83600D01*
X1043536Y83683D01*
X1043203Y83600D01*
X1042994Y83350D01*
X1042869Y83058D01*
Y82017D01*
G01Y83058D02*
X1041661Y83683D01*
G01Y85867D02*
X1042203Y85950D01*
X1042661Y86075D01*
X1043078Y86242D01*
X1043536Y86450D01*
X1044161Y86783D01*
Y85117D01*
G01X1041661Y89050D02*
X1041703Y89342D01*
X1041828Y89675D01*
X1042036Y89883D01*
X1042328Y89967D01*
X1042619Y89883D01*
X1042869Y89633D01*
X1042994Y89258D01*
Y88842D01*
X1043078Y88592D01*
X1043286Y88383D01*
X1043578Y88300D01*
X1043869Y88425D01*
X1044078Y88717D01*
X1044161Y89050D01*
X1044078Y89383D01*
X1043869Y89675D01*
X1043578Y89800D01*
X1043286Y89717D01*
X1043078Y89508D01*
X1042994Y89258D01*
Y88842D01*
X1042869Y88467D01*
X1042619Y88217D01*
X1042328Y88133D01*
X1042036Y88217D01*
X1041828Y88425D01*
X1041703Y88758D01*
X1041661Y89050D01*
G01X1044161Y92150D02*
X1044078Y91817D01*
X1043869Y91567D01*
X1043619Y91400D01*
X1043286Y91275D01*
X1042911Y91233D01*
X1042536Y91275D01*
X1042203Y91400D01*
X1041953Y91567D01*
X1041744Y91817D01*
X1041661Y92150D01*
X1041744Y92483D01*
X1041953Y92733D01*
X1042203Y92900D01*
X1042536Y93025D01*
X1042911Y93067D01*
X1043286Y93025D01*
X1043619Y92900D01*
X1043869Y92733D01*
X1044078Y92483D01*
X1044161Y92150D01*
G01X1031696Y137822D02*
Y135322D01*
G01X1032654Y137822D02*
X1030738D01*
G01X1029429Y135322D02*
Y137822D01*
X1028429D01*
X1028096Y137697D01*
X1027846Y137405D01*
X1027763Y137072D01*
X1027846Y136739D01*
X1028054Y136489D01*
X1028429Y136364D01*
X1029429D01*
G01X1026288Y137405D02*
X1026038Y137655D01*
X1025746Y137780D01*
X1025413Y137822D01*
X1024996Y137739D01*
X1024704Y137530D01*
X1024621Y137280D01*
X1024663Y137030D01*
X1024829Y136822D01*
X1025663Y136405D01*
X1026038Y136114D01*
X1026288Y135697D01*
X1026371Y135322D01*
X1024621D01*
G01X1023104Y135614D02*
X1022813Y135405D01*
X1022479Y135322D01*
X1022146Y135405D01*
X1021854Y135655D01*
X1021646Y136030D01*
X1021563Y136405D01*
Y136864D01*
X1021646Y137239D01*
X1021854Y137572D01*
X1022104Y137739D01*
X1022396Y137822D01*
X1022729Y137739D01*
X1022979Y137572D01*
X1023146Y137322D01*
X1023229Y136989D01*
X1023146Y136697D01*
X1022938Y136405D01*
X1022688Y136239D01*
X1022396Y136197D01*
X1022063Y136280D01*
X1021813Y136489D01*
X1021563Y136864D01*
G01X1018796Y135322D02*
Y137822D01*
X1020338Y136030D01*
X1018254D01*
G01X1031696Y142510D02*
Y140010D01*
G01X1032654Y142510D02*
X1030738D01*
G01X1029429Y140010D02*
Y142510D01*
X1028429D01*
X1028096Y142385D01*
X1027846Y142093D01*
X1027763Y141760D01*
X1027846Y141427D01*
X1028054Y141177D01*
X1028429Y141052D01*
X1029429D01*
G01X1026288Y142093D02*
X1026038Y142343D01*
X1025746Y142468D01*
X1025413Y142510D01*
X1024996Y142427D01*
X1024704Y142218D01*
X1024621Y141968D01*
X1024663Y141718D01*
X1024829Y141510D01*
X1025663Y141093D01*
X1026038Y140802D01*
X1026288Y140385D01*
X1026371Y140010D01*
X1024621D01*
G01X1023104Y140302D02*
X1022813Y140093D01*
X1022479Y140010D01*
X1022146Y140093D01*
X1021854Y140343D01*
X1021646Y140718D01*
X1021563Y141093D01*
Y141552D01*
X1021646Y141927D01*
X1021854Y142260D01*
X1022104Y142427D01*
X1022396Y142510D01*
X1022729Y142427D01*
X1022979Y142260D01*
X1023146Y142010D01*
X1023229Y141677D01*
X1023146Y141385D01*
X1022938Y141093D01*
X1022688Y140927D01*
X1022396Y140885D01*
X1022063Y140968D01*
X1021813Y141177D01*
X1021563Y141552D01*
G01X1019296Y142510D02*
X1019629Y142427D01*
X1019879Y142218D01*
X1020046Y141968D01*
X1020171Y141635D01*
X1020213Y141260D01*
X1020171Y140885D01*
X1020046Y140552D01*
X1019879Y140302D01*
X1019629Y140093D01*
X1019296Y140010D01*
X1018963Y140093D01*
X1018713Y140302D01*
X1018546Y140552D01*
X1018421Y140885D01*
X1018379Y141260D01*
X1018421Y141635D01*
X1018546Y141968D01*
X1018713Y142218D01*
X1018963Y142427D01*
X1019296Y142510D01*
G01X1021358Y167075D02*
X1021608Y167200D01*
X1021900Y167283D01*
X1022233D01*
X1022608Y167158D01*
X1022900Y166950D01*
X1023108Y166700D01*
X1023275Y166283D01*
X1023317Y165908D01*
X1023233Y165533D01*
X1023108Y165283D01*
X1022858Y165033D01*
X1022567Y164866D01*
X1022275Y164783D01*
X1021983D01*
X1021692Y164866D01*
X1021442Y164991D01*
X1021233Y165158D01*
G01X1020092D02*
X1019842Y164950D01*
X1019550Y164825D01*
X1019175Y164783D01*
X1018800Y164866D01*
X1018508Y165033D01*
X1018300Y165325D01*
X1018258Y165658D01*
X1018342Y165991D01*
X1018550Y166200D01*
X1018842Y166366D01*
X1019133Y166408D01*
X1019425Y166366D01*
X1019800Y166200D01*
X1019675Y167283D01*
X1018550D01*
G01X1016075Y164783D02*
X1015783Y164825D01*
X1015450Y164950D01*
X1015242Y165158D01*
X1015158Y165450D01*
X1015242Y165741D01*
X1015492Y165991D01*
X1015867Y166116D01*
X1016283D01*
X1016533Y166200D01*
X1016742Y166408D01*
X1016825Y166700D01*
X1016700Y166991D01*
X1016408Y167200D01*
X1016075Y167283D01*
X1015742Y167200D01*
X1015450Y166991D01*
X1015325Y166700D01*
X1015408Y166408D01*
X1015617Y166200D01*
X1015867Y166116D01*
X1016283D01*
X1016658Y165991D01*
X1016908Y165741D01*
X1016992Y165450D01*
X1016908Y165158D01*
X1016700Y164950D01*
X1016367Y164825D01*
X1016075Y164783D01*
G01X1012975D02*
X1012683Y164825D01*
X1012350Y164950D01*
X1012142Y165158D01*
X1012058Y165450D01*
X1012142Y165741D01*
X1012392Y165991D01*
X1012767Y166116D01*
X1013183D01*
X1013433Y166200D01*
X1013642Y166408D01*
X1013725Y166700D01*
X1013600Y166991D01*
X1013308Y167200D01*
X1012975Y167283D01*
X1012642Y167200D01*
X1012350Y166991D01*
X1012225Y166700D01*
X1012308Y166408D01*
X1012517Y166200D01*
X1012767Y166116D01*
X1013183D01*
X1013558Y165991D01*
X1013808Y165741D01*
X1013892Y165450D01*
X1013808Y165158D01*
X1013600Y164950D01*
X1013267Y164825D01*
X1012975Y164783D01*
G01X1026221Y163003D02*
X1026471Y163128D01*
X1026763Y163211D01*
X1027096D01*
X1027471Y163086D01*
X1027763Y162878D01*
X1027971Y162628D01*
X1028138Y162211D01*
X1028180Y161836D01*
X1028096Y161461D01*
X1027971Y161211D01*
X1027721Y160961D01*
X1027430Y160794D01*
X1027138Y160711D01*
X1026846D01*
X1026555Y160794D01*
X1026305Y160919D01*
X1026096Y161086D01*
G01X1023538Y160711D02*
Y163211D01*
X1025080Y161419D01*
X1022996D01*
G01X1021646Y161003D02*
X1021355Y160794D01*
X1021021Y160711D01*
X1020688Y160794D01*
X1020396Y161044D01*
X1020188Y161419D01*
X1020105Y161794D01*
Y162253D01*
X1020188Y162628D01*
X1020396Y162961D01*
X1020646Y163128D01*
X1020938Y163211D01*
X1021271Y163128D01*
X1021521Y162961D01*
X1021688Y162711D01*
X1021771Y162378D01*
X1021688Y162086D01*
X1021480Y161794D01*
X1021230Y161628D01*
X1020938Y161586D01*
X1020605Y161669D01*
X1020355Y161878D01*
X1020105Y162253D01*
G01X1017838Y160711D02*
X1017546Y160753D01*
X1017213Y160878D01*
X1017005Y161086D01*
X1016921Y161378D01*
X1017005Y161669D01*
X1017255Y161919D01*
X1017630Y162044D01*
X1018046D01*
X1018296Y162128D01*
X1018505Y162336D01*
X1018588Y162628D01*
X1018463Y162919D01*
X1018171Y163128D01*
X1017838Y163211D01*
X1017505Y163128D01*
X1017213Y162919D01*
X1017088Y162628D01*
X1017171Y162336D01*
X1017380Y162128D01*
X1017630Y162044D01*
X1018046D01*
X1018421Y161919D01*
X1018671Y161669D01*
X1018755Y161378D01*
X1018671Y161086D01*
X1018463Y160878D01*
X1018130Y160753D01*
X1017838Y160711D01*
G01X1041338Y158610D02*
Y156110D01*
G01X1042296Y158610D02*
X1040380D01*
G01X1039071Y156110D02*
Y158610D01*
X1038071D01*
X1037738Y158485D01*
X1037488Y158193D01*
X1037405Y157860D01*
X1037488Y157527D01*
X1037696Y157277D01*
X1038071Y157152D01*
X1039071D01*
G01X1035930Y158193D02*
X1035680Y158443D01*
X1035388Y158568D01*
X1035055Y158610D01*
X1034638Y158527D01*
X1034346Y158318D01*
X1034263Y158068D01*
X1034305Y157818D01*
X1034471Y157610D01*
X1035305Y157193D01*
X1035680Y156902D01*
X1035930Y156485D01*
X1036013Y156110D01*
X1034263D01*
G01X1032038D02*
X1031746Y156152D01*
X1031413Y156277D01*
X1031205Y156485D01*
X1031121Y156777D01*
X1031205Y157068D01*
X1031455Y157318D01*
X1031830Y157443D01*
X1032246D01*
X1032496Y157527D01*
X1032705Y157735D01*
X1032788Y158027D01*
X1032663Y158318D01*
X1032371Y158527D01*
X1032038Y158610D01*
X1031705Y158527D01*
X1031413Y158318D01*
X1031288Y158027D01*
X1031371Y157735D01*
X1031580Y157527D01*
X1031830Y157443D01*
X1032246D01*
X1032621Y157318D01*
X1032871Y157068D01*
X1032955Y156777D01*
X1032871Y156485D01*
X1032663Y156277D01*
X1032330Y156152D01*
X1032038Y156110D01*
G01X1029646Y156402D02*
X1029355Y156193D01*
X1029021Y156110D01*
X1028688Y156193D01*
X1028396Y156443D01*
X1028188Y156818D01*
X1028105Y157193D01*
Y157652D01*
X1028188Y158027D01*
X1028396Y158360D01*
X1028646Y158527D01*
X1028938Y158610D01*
X1029271Y158527D01*
X1029521Y158360D01*
X1029688Y158110D01*
X1029771Y157777D01*
X1029688Y157485D01*
X1029480Y157193D01*
X1029230Y157027D01*
X1028938Y156985D01*
X1028605Y157068D01*
X1028355Y157277D01*
X1028105Y157652D01*
G01X1031077Y150031D02*
Y147531D01*
G01X1032035Y150031D02*
X1030119D01*
G01X1028810Y147531D02*
Y150031D01*
X1027810D01*
X1027477Y149906D01*
X1027227Y149614D01*
X1027144Y149281D01*
X1027227Y148948D01*
X1027435Y148698D01*
X1027810Y148573D01*
X1028810D01*
G01X1025669Y149614D02*
X1025419Y149864D01*
X1025127Y149989D01*
X1024794Y150031D01*
X1024377Y149948D01*
X1024085Y149739D01*
X1024002Y149489D01*
X1024044Y149239D01*
X1024210Y149031D01*
X1025044Y148614D01*
X1025419Y148323D01*
X1025669Y147906D01*
X1025752Y147531D01*
X1024002D01*
G01X1022569Y148573D02*
X1022277Y148864D01*
X1022027Y149031D01*
X1021694Y149114D01*
X1021402Y149031D01*
X1021194Y148864D01*
X1021027Y148614D01*
X1020985Y148323D01*
X1021027Y148073D01*
X1021194Y147823D01*
X1021444Y147614D01*
X1021735Y147531D01*
X1022069Y147614D01*
X1022360Y147864D01*
X1022527Y148239D01*
X1022569Y148656D01*
X1022485Y149198D01*
X1022360Y149489D01*
X1022152Y149781D01*
X1021860Y149989D01*
X1021569Y150031D01*
X1021277Y149948D01*
X1021069Y149739D01*
G01X1019594Y147906D02*
X1019344Y147698D01*
X1019052Y147573D01*
X1018677Y147531D01*
X1018302Y147614D01*
X1018010Y147781D01*
X1017802Y148073D01*
X1017760Y148406D01*
X1017844Y148739D01*
X1018052Y148948D01*
X1018344Y149114D01*
X1018635Y149156D01*
X1018927Y149114D01*
X1019302Y148948D01*
X1019177Y150031D01*
X1018052D01*
G01X1047001Y154187D02*
Y151687D01*
G01X1047959Y154187D02*
X1046043D01*
G01X1044734Y151687D02*
Y154187D01*
X1043734D01*
X1043401Y154062D01*
X1043151Y153770D01*
X1043068Y153437D01*
X1043151Y153104D01*
X1043359Y152854D01*
X1043734Y152729D01*
X1044734D01*
G01X1041718Y152187D02*
X1041468Y151895D01*
X1041134Y151729D01*
X1040759Y151687D01*
X1040426Y151729D01*
X1040093Y151937D01*
X1039884Y152187D01*
X1039843Y152437D01*
X1039926Y152729D01*
X1040218Y152937D01*
X1040509Y153020D01*
X1040884D01*
G01X1040509D02*
X1040259Y153145D01*
X1040051Y153354D01*
X1039968Y153604D01*
X1040051Y153854D01*
X1040259Y154062D01*
X1040634Y154187D01*
X1041009Y154145D01*
X1041384Y153979D01*
G01X1037701Y154187D02*
X1038034Y154104D01*
X1038284Y153895D01*
X1038451Y153645D01*
X1038576Y153312D01*
X1038618Y152937D01*
X1038576Y152562D01*
X1038451Y152229D01*
X1038284Y151979D01*
X1038034Y151770D01*
X1037701Y151687D01*
X1037368Y151770D01*
X1037118Y151979D01*
X1036951Y152229D01*
X1036826Y152562D01*
X1036784Y152937D01*
X1036826Y153312D01*
X1036951Y153645D01*
X1037118Y153895D01*
X1037368Y154104D01*
X1037701Y154187D01*
G01X1034601D02*
X1034934Y154104D01*
X1035184Y153895D01*
X1035351Y153645D01*
X1035476Y153312D01*
X1035518Y152937D01*
X1035476Y152562D01*
X1035351Y152229D01*
X1035184Y151979D01*
X1034934Y151770D01*
X1034601Y151687D01*
X1034268Y151770D01*
X1034018Y151979D01*
X1033851Y152229D01*
X1033726Y152562D01*
X1033684Y152937D01*
X1033726Y153312D01*
X1033851Y153645D01*
X1034018Y153895D01*
X1034268Y154104D01*
X1034601Y154187D01*
G01X1046780Y149852D02*
Y147352D01*
G01X1047738Y149852D02*
X1045822D01*
G01X1044513Y147352D02*
Y149852D01*
X1043513D01*
X1043180Y149727D01*
X1042930Y149435D01*
X1042847Y149102D01*
X1042930Y148769D01*
X1043138Y148519D01*
X1043513Y148394D01*
X1044513D01*
G01X1041497Y147852D02*
X1041247Y147560D01*
X1040913Y147394D01*
X1040538Y147352D01*
X1040205Y147394D01*
X1039872Y147602D01*
X1039663Y147852D01*
X1039622Y148102D01*
X1039705Y148394D01*
X1039997Y148602D01*
X1040288Y148685D01*
X1040663D01*
G01X1040288D02*
X1040038Y148810D01*
X1039830Y149019D01*
X1039747Y149269D01*
X1039830Y149519D01*
X1040038Y149727D01*
X1040413Y149852D01*
X1040788Y149810D01*
X1041163Y149644D01*
G01X1037480Y147352D02*
Y149852D01*
X1037980Y149352D01*
G01Y147352D02*
X1036980D01*
G01X1034380Y149852D02*
X1034713Y149769D01*
X1034963Y149560D01*
X1035130Y149310D01*
X1035255Y148977D01*
X1035297Y148602D01*
X1035255Y148227D01*
X1035130Y147894D01*
X1034963Y147644D01*
X1034713Y147435D01*
X1034380Y147352D01*
X1034047Y147435D01*
X1033797Y147644D01*
X1033630Y147894D01*
X1033505Y148227D01*
X1033463Y148602D01*
X1033505Y148977D01*
X1033630Y149310D01*
X1033797Y149560D01*
X1034047Y149769D01*
X1034380Y149852D01*
G01X1031520Y146402D02*
Y143902D01*
G01X1032478Y146402D02*
X1030562D01*
G01X1029253Y143902D02*
Y146402D01*
X1028253D01*
X1027920Y146277D01*
X1027670Y145985D01*
X1027587Y145652D01*
X1027670Y145319D01*
X1027878Y145069D01*
X1028253Y144944D01*
X1029253D01*
G01X1026112Y145985D02*
X1025862Y146235D01*
X1025570Y146360D01*
X1025237Y146402D01*
X1024820Y146319D01*
X1024528Y146110D01*
X1024445Y145860D01*
X1024487Y145610D01*
X1024653Y145402D01*
X1025487Y144985D01*
X1025862Y144694D01*
X1026112Y144277D01*
X1026195Y143902D01*
X1024445D01*
G01X1022220D02*
X1021928Y143944D01*
X1021595Y144069D01*
X1021387Y144277D01*
X1021303Y144569D01*
X1021387Y144860D01*
X1021637Y145110D01*
X1022012Y145235D01*
X1022428D01*
X1022678Y145319D01*
X1022887Y145527D01*
X1022970Y145819D01*
X1022845Y146110D01*
X1022553Y146319D01*
X1022220Y146402D01*
X1021887Y146319D01*
X1021595Y146110D01*
X1021470Y145819D01*
X1021553Y145527D01*
X1021762Y145319D01*
X1022012Y145235D01*
X1022428D01*
X1022803Y145110D01*
X1023053Y144860D01*
X1023137Y144569D01*
X1023053Y144277D01*
X1022845Y144069D01*
X1022512Y143944D01*
X1022220Y143902D01*
G01X1019912Y145985D02*
X1019662Y146235D01*
X1019370Y146360D01*
X1019037Y146402D01*
X1018620Y146319D01*
X1018328Y146110D01*
X1018245Y145860D01*
X1018287Y145610D01*
X1018453Y145402D01*
X1019287Y144985D01*
X1019662Y144694D01*
X1019912Y144277D01*
X1019995Y143902D01*
X1018245D01*
G01X1043372Y163034D02*
Y160534D01*
G01X1044330Y163034D02*
X1042414D01*
G01X1041105Y160534D02*
Y163034D01*
X1040105D01*
X1039772Y162909D01*
X1039522Y162617D01*
X1039439Y162284D01*
X1039522Y161951D01*
X1039730Y161701D01*
X1040105Y161576D01*
X1041105D01*
G01X1037964Y162617D02*
X1037714Y162867D01*
X1037422Y162992D01*
X1037089Y163034D01*
X1036672Y162951D01*
X1036380Y162742D01*
X1036297Y162492D01*
X1036339Y162242D01*
X1036505Y162034D01*
X1037339Y161617D01*
X1037714Y161326D01*
X1037964Y160909D01*
X1038047Y160534D01*
X1036297D01*
G01X1034864Y161576D02*
X1034572Y161867D01*
X1034322Y162034D01*
X1033989Y162117D01*
X1033697Y162034D01*
X1033489Y161867D01*
X1033322Y161617D01*
X1033280Y161326D01*
X1033322Y161076D01*
X1033489Y160826D01*
X1033739Y160617D01*
X1034030Y160534D01*
X1034364Y160617D01*
X1034655Y160867D01*
X1034822Y161242D01*
X1034864Y161659D01*
X1034780Y162201D01*
X1034655Y162492D01*
X1034447Y162784D01*
X1034155Y162992D01*
X1033864Y163034D01*
X1033572Y162951D01*
X1033364Y162742D01*
G01X1030472Y160534D02*
Y163034D01*
X1032014Y161242D01*
X1029930D01*
G01X1031033Y154365D02*
Y151865D01*
G01X1031991Y154365D02*
X1030075D01*
G01X1028766Y151865D02*
Y154365D01*
X1027766D01*
X1027433Y154240D01*
X1027183Y153948D01*
X1027100Y153615D01*
X1027183Y153282D01*
X1027391Y153032D01*
X1027766Y152907D01*
X1028766D01*
G01X1025625Y153948D02*
X1025375Y154198D01*
X1025083Y154323D01*
X1024750Y154365D01*
X1024333Y154282D01*
X1024041Y154073D01*
X1023958Y153823D01*
X1024000Y153573D01*
X1024166Y153365D01*
X1025000Y152948D01*
X1025375Y152657D01*
X1025625Y152240D01*
X1025708Y151865D01*
X1023958D01*
G01X1022650Y152365D02*
X1022400Y152073D01*
X1022066Y151907D01*
X1021691Y151865D01*
X1021358Y151907D01*
X1021025Y152115D01*
X1020816Y152365D01*
X1020775Y152615D01*
X1020858Y152907D01*
X1021150Y153115D01*
X1021441Y153198D01*
X1021816D01*
G01X1021441D02*
X1021191Y153323D01*
X1020983Y153532D01*
X1020900Y153782D01*
X1020983Y154032D01*
X1021191Y154240D01*
X1021566Y154365D01*
X1021941Y154323D01*
X1022316Y154157D01*
G01X1019341Y152157D02*
X1019050Y151948D01*
X1018716Y151865D01*
X1018383Y151948D01*
X1018091Y152198D01*
X1017883Y152573D01*
X1017800Y152948D01*
Y153407D01*
X1017883Y153782D01*
X1018091Y154115D01*
X1018341Y154282D01*
X1018633Y154365D01*
X1018966Y154282D01*
X1019216Y154115D01*
X1019383Y153865D01*
X1019466Y153532D01*
X1019383Y153240D01*
X1019175Y152948D01*
X1018925Y152782D01*
X1018633Y152740D01*
X1018300Y152823D01*
X1018050Y153032D01*
X1017800Y153407D01*
G01X1024531Y158787D02*
Y156287D01*
G01X1025489Y158787D02*
X1023573D01*
G01X1022264Y156287D02*
Y158787D01*
X1021264D01*
X1020931Y158662D01*
X1020681Y158370D01*
X1020598Y158037D01*
X1020681Y157704D01*
X1020889Y157454D01*
X1021264Y157329D01*
X1022264D01*
G01X1019123Y158370D02*
X1018873Y158620D01*
X1018581Y158745D01*
X1018248Y158787D01*
X1017831Y158704D01*
X1017539Y158495D01*
X1017456Y158245D01*
X1017498Y157995D01*
X1017664Y157787D01*
X1018498Y157370D01*
X1018873Y157079D01*
X1019123Y156662D01*
X1019206Y156287D01*
X1017456D01*
G01X1016148Y156787D02*
X1015898Y156495D01*
X1015564Y156329D01*
X1015189Y156287D01*
X1014856Y156329D01*
X1014523Y156537D01*
X1014314Y156787D01*
X1014273Y157037D01*
X1014356Y157329D01*
X1014648Y157537D01*
X1014939Y157620D01*
X1015314D01*
G01X1014939D02*
X1014689Y157745D01*
X1014481Y157954D01*
X1014398Y158204D01*
X1014481Y158454D01*
X1014689Y158662D01*
X1015064Y158787D01*
X1015439Y158745D01*
X1015814Y158579D01*
G01X1012131Y156287D02*
X1011839Y156329D01*
X1011506Y156454D01*
X1011298Y156662D01*
X1011214Y156954D01*
X1011298Y157245D01*
X1011548Y157495D01*
X1011923Y157620D01*
X1012339D01*
X1012589Y157704D01*
X1012798Y157912D01*
X1012881Y158204D01*
X1012756Y158495D01*
X1012464Y158704D01*
X1012131Y158787D01*
X1011798Y158704D01*
X1011506Y158495D01*
X1011381Y158204D01*
X1011464Y157912D01*
X1011673Y157704D01*
X1011923Y157620D01*
X1012339D01*
X1012714Y157495D01*
X1012964Y157245D01*
X1013048Y156954D01*
X1012964Y156662D01*
X1012756Y156454D01*
X1012423Y156329D01*
X1012131Y156287D01*
G01X1072100Y1500D02*
Y5500D01*
X1079500D01*
G01X1072100Y5600D02*
Y9600D01*
X1079500D01*
G01X1069000Y-14133D02*
X1071500D01*
Y-13092D01*
X1071375Y-12758D01*
X1071208Y-12550D01*
X1070875Y-12467D01*
X1070542Y-12550D01*
X1070333Y-12800D01*
X1070208Y-13092D01*
Y-14133D01*
G01Y-13092D02*
X1069000Y-12467D01*
G01X1071083Y-10992D02*
X1071333Y-10742D01*
X1071458Y-10450D01*
X1071500Y-10117D01*
X1071417Y-9700D01*
X1071208Y-9408D01*
X1070958Y-9325D01*
X1070708Y-9367D01*
X1070500Y-9533D01*
X1070083Y-10367D01*
X1069792Y-10742D01*
X1069375Y-10992D01*
X1069000Y-11075D01*
Y-9325D01*
G01X1069292Y-7808D02*
X1069083Y-7517D01*
X1069000Y-7183D01*
X1069083Y-6850D01*
X1069333Y-6558D01*
X1069708Y-6350D01*
X1070083Y-6267D01*
X1070542D01*
X1070917Y-6350D01*
X1071250Y-6558D01*
X1071417Y-6808D01*
X1071500Y-7100D01*
X1071417Y-7433D01*
X1071250Y-7683D01*
X1071000Y-7850D01*
X1070667Y-7933D01*
X1070375Y-7850D01*
X1070083Y-7642D01*
X1069917Y-7392D01*
X1069875Y-7100D01*
X1069958Y-6767D01*
X1070167Y-6517D01*
X1070542Y-6267D01*
G01X1071500Y-4000D02*
X1071417Y-4333D01*
X1071208Y-4583D01*
X1070958Y-4750D01*
X1070625Y-4875D01*
X1070250Y-4917D01*
X1069875Y-4875D01*
X1069542Y-4750D01*
X1069292Y-4583D01*
X1069083Y-4333D01*
X1069000Y-4000D01*
X1069083Y-3667D01*
X1069292Y-3417D01*
X1069542Y-3250D01*
X1069875Y-3125D01*
X1070250Y-3083D01*
X1070625Y-3125D01*
X1070958Y-3250D01*
X1071208Y-3417D01*
X1071417Y-3667D01*
X1071500Y-4000D01*
G01X1069000Y-983D02*
X1069542Y-900D01*
X1070000Y-775D01*
X1070417Y-608D01*
X1070875Y-400D01*
X1071500Y-67D01*
Y-1733D01*
G01X1067700Y10000D02*
X1071700D01*
Y2600D01*
G01X1051161Y6407D02*
X1047161D01*
Y13807D01*
G01X1072200Y10400D02*
Y14400D01*
X1079600D01*
G01X1046712Y16357D02*
Y20357D01*
X1054112D01*
G01X1075250Y27050D02*
X1071250D01*
Y34450D01*
G01X1067800Y34500D02*
Y38500D01*
X1075200D01*
G01X1063300Y22500D02*
Y26500D01*
X1070700D01*
G01X1048950Y31165D02*
X1044950D01*
Y38565D01*
G01X1053450Y31165D02*
X1049450D01*
Y38565D01*
G01X1067800Y30500D02*
Y34500D01*
X1075200D01*
G01X1063300Y18500D02*
Y22500D01*
X1070700D01*
G01X1057436Y26785D02*
X1059936D01*
Y27826D01*
X1059811Y28160D01*
X1059644Y28368D01*
X1059311Y28451D01*
X1058978Y28368D01*
X1058769Y28118D01*
X1058644Y27826D01*
Y26785D01*
G01Y27826D02*
X1057436Y28451D01*
G01X1057936Y29801D02*
X1057644Y30051D01*
X1057478Y30385D01*
X1057436Y30760D01*
X1057478Y31093D01*
X1057686Y31426D01*
X1057936Y31635D01*
X1058186Y31676D01*
X1058478Y31593D01*
X1058686Y31301D01*
X1058769Y31010D01*
Y30635D01*
G01Y31010D02*
X1058894Y31260D01*
X1059103Y31468D01*
X1059353Y31551D01*
X1059603Y31468D01*
X1059811Y31260D01*
X1059936Y30885D01*
X1059894Y30510D01*
X1059728Y30135D01*
G01X1057436Y33735D02*
X1057978Y33818D01*
X1058436Y33943D01*
X1058853Y34110D01*
X1059311Y34318D01*
X1059936Y34651D01*
Y32985D01*
G01X1057436Y36918D02*
X1059936D01*
X1059436Y36418D01*
G01X1057436D02*
Y37418D01*
G01X1066750Y29950D02*
X1070750D01*
Y22550D01*
G01X1071250Y41950D02*
X1075250D01*
Y34550D01*
G01X1070750Y15050D02*
X1066750D01*
Y22450D01*
G01X1063475Y46273D02*
X1067475D01*
Y38873D01*
G01X1049500Y34615D02*
Y38615D01*
X1056900D01*
G01X1047830Y71712D02*
X1050330D01*
Y72753D01*
X1050205Y73087D01*
X1050038Y73295D01*
X1049705Y73378D01*
X1049372Y73295D01*
X1049163Y73045D01*
X1049038Y72753D01*
Y71712D01*
G01Y72753D02*
X1047830Y73378D01*
G01Y75562D02*
X1048372Y75645D01*
X1048830Y75770D01*
X1049247Y75937D01*
X1049705Y76145D01*
X1050330Y76478D01*
Y74812D01*
G01X1048122Y78037D02*
X1047913Y78328D01*
X1047830Y78662D01*
X1047913Y78995D01*
X1048163Y79287D01*
X1048538Y79495D01*
X1048913Y79578D01*
X1049372D01*
X1049747Y79495D01*
X1050080Y79287D01*
X1050247Y79037D01*
X1050330Y78745D01*
X1050247Y78412D01*
X1050080Y78162D01*
X1049830Y77995D01*
X1049497Y77912D01*
X1049205Y77995D01*
X1048913Y78203D01*
X1048747Y78453D01*
X1048705Y78745D01*
X1048788Y79078D01*
X1048997Y79328D01*
X1049372Y79578D01*
G01X1049913Y81053D02*
X1050163Y81303D01*
X1050288Y81595D01*
X1050330Y81928D01*
X1050247Y82345D01*
X1050038Y82637D01*
X1049788Y82720D01*
X1049538Y82678D01*
X1049330Y82512D01*
X1048913Y81678D01*
X1048622Y81303D01*
X1048205Y81053D01*
X1047830Y80970D01*
Y82720D01*
G01X1088958Y49923D02*
Y52423D01*
X1087917D01*
X1087583Y52298D01*
X1087375Y52131D01*
X1087292Y51798D01*
X1087375Y51465D01*
X1087625Y51256D01*
X1087917Y51131D01*
X1088958D01*
G01X1087917D02*
X1087292Y49923D01*
G01X1085817Y52006D02*
X1085567Y52256D01*
X1085275Y52381D01*
X1084942Y52423D01*
X1084525Y52340D01*
X1084233Y52131D01*
X1084150Y51881D01*
X1084192Y51631D01*
X1084358Y51423D01*
X1085192Y51006D01*
X1085567Y50715D01*
X1085817Y50298D01*
X1085900Y49923D01*
X1084150D01*
G01X1082633Y50215D02*
X1082342Y50006D01*
X1082008Y49923D01*
X1081675Y50006D01*
X1081383Y50256D01*
X1081175Y50631D01*
X1081092Y51006D01*
Y51465D01*
X1081175Y51840D01*
X1081383Y52173D01*
X1081633Y52340D01*
X1081925Y52423D01*
X1082258Y52340D01*
X1082508Y52173D01*
X1082675Y51923D01*
X1082758Y51590D01*
X1082675Y51298D01*
X1082467Y51006D01*
X1082217Y50840D01*
X1081925Y50798D01*
X1081592Y50881D01*
X1081342Y51090D01*
X1081092Y51465D01*
G01X1079617Y50965D02*
X1079325Y51256D01*
X1079075Y51423D01*
X1078742Y51506D01*
X1078450Y51423D01*
X1078242Y51256D01*
X1078075Y51006D01*
X1078033Y50715D01*
X1078075Y50465D01*
X1078242Y50215D01*
X1078492Y50006D01*
X1078783Y49923D01*
X1079117Y50006D01*
X1079408Y50256D01*
X1079575Y50631D01*
X1079617Y51048D01*
X1079533Y51590D01*
X1079408Y51881D01*
X1079200Y52173D01*
X1078908Y52381D01*
X1078617Y52423D01*
X1078325Y52340D01*
X1078117Y52131D01*
G01X1076517Y52006D02*
X1076267Y52256D01*
X1075975Y52381D01*
X1075642Y52423D01*
X1075225Y52340D01*
X1074933Y52131D01*
X1074850Y51881D01*
X1074892Y51631D01*
X1075058Y51423D01*
X1075892Y51006D01*
X1076267Y50715D01*
X1076517Y50298D01*
X1076600Y49923D01*
X1074850D01*
G01X1060025Y46823D02*
Y50823D01*
X1067425D01*
G01X1088958Y45423D02*
Y47923D01*
X1087917D01*
X1087583Y47798D01*
X1087375Y47631D01*
X1087292Y47298D01*
X1087375Y46965D01*
X1087625Y46756D01*
X1087917Y46631D01*
X1088958D01*
G01X1087917D02*
X1087292Y45423D01*
G01X1085817Y47506D02*
X1085567Y47756D01*
X1085275Y47881D01*
X1084942Y47923D01*
X1084525Y47840D01*
X1084233Y47631D01*
X1084150Y47381D01*
X1084192Y47131D01*
X1084358Y46923D01*
X1085192Y46506D01*
X1085567Y46215D01*
X1085817Y45798D01*
X1085900Y45423D01*
X1084150D01*
G01X1082633Y45715D02*
X1082342Y45506D01*
X1082008Y45423D01*
X1081675Y45506D01*
X1081383Y45756D01*
X1081175Y46131D01*
X1081092Y46506D01*
Y46965D01*
X1081175Y47340D01*
X1081383Y47673D01*
X1081633Y47840D01*
X1081925Y47923D01*
X1082258Y47840D01*
X1082508Y47673D01*
X1082675Y47423D01*
X1082758Y47090D01*
X1082675Y46798D01*
X1082467Y46506D01*
X1082217Y46340D01*
X1081925Y46298D01*
X1081592Y46381D01*
X1081342Y46590D01*
X1081092Y46965D01*
G01X1079617Y46465D02*
X1079325Y46756D01*
X1079075Y46923D01*
X1078742Y47006D01*
X1078450Y46923D01*
X1078242Y46756D01*
X1078075Y46506D01*
X1078033Y46215D01*
X1078075Y45965D01*
X1078242Y45715D01*
X1078492Y45506D01*
X1078783Y45423D01*
X1079117Y45506D01*
X1079408Y45756D01*
X1079575Y46131D01*
X1079617Y46548D01*
X1079533Y47090D01*
X1079408Y47381D01*
X1079200Y47673D01*
X1078908Y47881D01*
X1078617Y47923D01*
X1078325Y47840D01*
X1078117Y47631D01*
G01X1076642Y45923D02*
X1076392Y45631D01*
X1076058Y45465D01*
X1075683Y45423D01*
X1075350Y45465D01*
X1075017Y45673D01*
X1074808Y45923D01*
X1074767Y46173D01*
X1074850Y46465D01*
X1075142Y46673D01*
X1075433Y46756D01*
X1075808D01*
G01X1075433D02*
X1075183Y46881D01*
X1074975Y47090D01*
X1074892Y47340D01*
X1074975Y47590D01*
X1075183Y47798D01*
X1075558Y47923D01*
X1075933Y47881D01*
X1076308Y47715D01*
G01X1060025Y42323D02*
Y46323D01*
X1067425D01*
G01X1065896Y73113D02*
X1068396D01*
Y74154D01*
X1068271Y74488D01*
X1068104Y74696D01*
X1067771Y74779D01*
X1067438Y74696D01*
X1067229Y74446D01*
X1067104Y74154D01*
Y73113D01*
G01Y74154D02*
X1065896Y74779D01*
G01X1067979Y76254D02*
X1068229Y76504D01*
X1068354Y76796D01*
X1068396Y77129D01*
X1068313Y77546D01*
X1068104Y77838D01*
X1067854Y77921D01*
X1067604Y77879D01*
X1067396Y77713D01*
X1066979Y76879D01*
X1066688Y76504D01*
X1066271Y76254D01*
X1065896Y76171D01*
Y77921D01*
G01X1066188Y79438D02*
X1065979Y79729D01*
X1065896Y80063D01*
X1065979Y80396D01*
X1066229Y80688D01*
X1066604Y80896D01*
X1066979Y80979D01*
X1067438D01*
X1067813Y80896D01*
X1068146Y80688D01*
X1068313Y80438D01*
X1068396Y80146D01*
X1068313Y79813D01*
X1068146Y79563D01*
X1067896Y79396D01*
X1067563Y79313D01*
X1067271Y79396D01*
X1066979Y79604D01*
X1066813Y79854D01*
X1066771Y80146D01*
X1066854Y80479D01*
X1067063Y80729D01*
X1067438Y80979D01*
G01X1066938Y82454D02*
X1067229Y82746D01*
X1067396Y82996D01*
X1067479Y83329D01*
X1067396Y83621D01*
X1067229Y83829D01*
X1066979Y83996D01*
X1066688Y84038D01*
X1066438Y83996D01*
X1066188Y83829D01*
X1065979Y83579D01*
X1065896Y83288D01*
X1065979Y82954D01*
X1066229Y82663D01*
X1066604Y82496D01*
X1067021Y82454D01*
X1067563Y82538D01*
X1067854Y82663D01*
X1068146Y82871D01*
X1068354Y83163D01*
X1068396Y83454D01*
X1068313Y83746D01*
X1068104Y83954D01*
G01X1066938Y85554D02*
X1067229Y85846D01*
X1067396Y86096D01*
X1067479Y86429D01*
X1067396Y86721D01*
X1067229Y86929D01*
X1066979Y87096D01*
X1066688Y87138D01*
X1066438Y87096D01*
X1066188Y86929D01*
X1065979Y86679D01*
X1065896Y86388D01*
X1065979Y86054D01*
X1066229Y85763D01*
X1066604Y85596D01*
X1067021Y85554D01*
X1067563Y85638D01*
X1067854Y85763D01*
X1068146Y85971D01*
X1068354Y86263D01*
X1068396Y86554D01*
X1068313Y86846D01*
X1068104Y87054D01*
G01X1070396Y73113D02*
X1072896D01*
Y74154D01*
X1072771Y74488D01*
X1072604Y74696D01*
X1072271Y74779D01*
X1071938Y74696D01*
X1071729Y74446D01*
X1071604Y74154D01*
Y73113D01*
G01Y74154D02*
X1070396Y74779D01*
G01X1072479Y76254D02*
X1072729Y76504D01*
X1072854Y76796D01*
X1072896Y77129D01*
X1072813Y77546D01*
X1072604Y77838D01*
X1072354Y77921D01*
X1072104Y77879D01*
X1071896Y77713D01*
X1071479Y76879D01*
X1071188Y76504D01*
X1070771Y76254D01*
X1070396Y76171D01*
Y77921D01*
G01X1070688Y79438D02*
X1070479Y79729D01*
X1070396Y80063D01*
X1070479Y80396D01*
X1070729Y80688D01*
X1071104Y80896D01*
X1071479Y80979D01*
X1071938D01*
X1072313Y80896D01*
X1072646Y80688D01*
X1072813Y80438D01*
X1072896Y80146D01*
X1072813Y79813D01*
X1072646Y79563D01*
X1072396Y79396D01*
X1072063Y79313D01*
X1071771Y79396D01*
X1071479Y79604D01*
X1071313Y79854D01*
X1071271Y80146D01*
X1071354Y80479D01*
X1071563Y80729D01*
X1071938Y80979D01*
G01X1071438Y82454D02*
X1071729Y82746D01*
X1071896Y82996D01*
X1071979Y83329D01*
X1071896Y83621D01*
X1071729Y83829D01*
X1071479Y83996D01*
X1071188Y84038D01*
X1070938Y83996D01*
X1070688Y83829D01*
X1070479Y83579D01*
X1070396Y83288D01*
X1070479Y82954D01*
X1070729Y82663D01*
X1071104Y82496D01*
X1071521Y82454D01*
X1072063Y82538D01*
X1072354Y82663D01*
X1072646Y82871D01*
X1072854Y83163D01*
X1072896Y83454D01*
X1072813Y83746D01*
X1072604Y83954D01*
G01X1070396Y86263D02*
X1070938Y86346D01*
X1071396Y86471D01*
X1071813Y86638D01*
X1072271Y86846D01*
X1072896Y87179D01*
Y85513D01*
G01X1055946Y66390D02*
Y70390D01*
X1063346D01*
G01X1055946Y70400D02*
Y74400D01*
X1063346D01*
G01X1059342Y70394D02*
X1063342D01*
Y62994D01*
G01X1067475Y46873D02*
X1063475D01*
Y54273D01*
G01X1063342Y70396D02*
X1059342D01*
Y77796D01*
G01X1049184Y94217D02*
X1051684D01*
Y95258D01*
X1051559Y95592D01*
X1051392Y95800D01*
X1051059Y95883D01*
X1050726Y95800D01*
X1050517Y95550D01*
X1050392Y95258D01*
Y94217D01*
G01Y95258D02*
X1049184Y95883D01*
G01Y98067D02*
X1049726Y98150D01*
X1050184Y98275D01*
X1050601Y98442D01*
X1051059Y98650D01*
X1051684Y98983D01*
Y97317D01*
G01X1049184Y101167D02*
X1049726Y101250D01*
X1050184Y101375D01*
X1050601Y101542D01*
X1051059Y101750D01*
X1051684Y102083D01*
Y100417D01*
G01X1050226Y103558D02*
X1050517Y103850D01*
X1050684Y104100D01*
X1050767Y104433D01*
X1050684Y104725D01*
X1050517Y104933D01*
X1050267Y105100D01*
X1049976Y105142D01*
X1049726Y105100D01*
X1049476Y104933D01*
X1049267Y104683D01*
X1049184Y104392D01*
X1049267Y104058D01*
X1049517Y103767D01*
X1049892Y103600D01*
X1050309Y103558D01*
X1050851Y103642D01*
X1051142Y103767D01*
X1051434Y103975D01*
X1051642Y104267D01*
X1051684Y104558D01*
X1051601Y104850D01*
X1051392Y105058D01*
G01X1045184Y94217D02*
X1047684D01*
Y95258D01*
X1047559Y95592D01*
X1047392Y95800D01*
X1047059Y95883D01*
X1046726Y95800D01*
X1046517Y95550D01*
X1046392Y95258D01*
Y94217D01*
G01Y95258D02*
X1045184Y95883D01*
G01Y98067D02*
X1045726Y98150D01*
X1046184Y98275D01*
X1046601Y98442D01*
X1047059Y98650D01*
X1047684Y98983D01*
Y97317D01*
G01X1045184Y101167D02*
X1045726Y101250D01*
X1046184Y101375D01*
X1046601Y101542D01*
X1047059Y101750D01*
X1047684Y102083D01*
Y100417D01*
G01X1045559Y103433D02*
X1045351Y103683D01*
X1045226Y103975D01*
X1045184Y104350D01*
X1045267Y104725D01*
X1045434Y105017D01*
X1045726Y105225D01*
X1046059Y105267D01*
X1046392Y105183D01*
X1046601Y104975D01*
X1046767Y104683D01*
X1046809Y104392D01*
X1046767Y104100D01*
X1046601Y103725D01*
X1047684Y103850D01*
Y104975D01*
G01X1061890Y94432D02*
X1064390D01*
Y95473D01*
X1064265Y95807D01*
X1064098Y96015D01*
X1063765Y96098D01*
X1063432Y96015D01*
X1063223Y95765D01*
X1063098Y95473D01*
Y94432D01*
G01Y95473D02*
X1061890Y96098D01*
G01Y98282D02*
X1062432Y98365D01*
X1062890Y98490D01*
X1063307Y98657D01*
X1063765Y98865D01*
X1064390Y99198D01*
Y97532D01*
G01X1061890Y101382D02*
X1062432Y101465D01*
X1062890Y101590D01*
X1063307Y101757D01*
X1063765Y101965D01*
X1064390Y102298D01*
Y100632D01*
G01X1063973Y103773D02*
X1064223Y104023D01*
X1064348Y104315D01*
X1064390Y104648D01*
X1064307Y105065D01*
X1064098Y105357D01*
X1063848Y105440D01*
X1063598Y105398D01*
X1063390Y105232D01*
X1062973Y104398D01*
X1062682Y104023D01*
X1062265Y103773D01*
X1061890Y103690D01*
Y105440D01*
G01X1057790Y94432D02*
X1060290D01*
Y95473D01*
X1060165Y95807D01*
X1059998Y96015D01*
X1059665Y96098D01*
X1059332Y96015D01*
X1059123Y95765D01*
X1058998Y95473D01*
Y94432D01*
G01Y95473D02*
X1057790Y96098D01*
G01Y98282D02*
X1058332Y98365D01*
X1058790Y98490D01*
X1059207Y98657D01*
X1059665Y98865D01*
X1060290Y99198D01*
Y97532D01*
G01X1058832Y100673D02*
X1059123Y100965D01*
X1059290Y101215D01*
X1059373Y101548D01*
X1059290Y101840D01*
X1059123Y102048D01*
X1058873Y102215D01*
X1058582Y102257D01*
X1058332Y102215D01*
X1058082Y102048D01*
X1057873Y101798D01*
X1057790Y101507D01*
X1057873Y101173D01*
X1058123Y100882D01*
X1058498Y100715D01*
X1058915Y100673D01*
X1059457Y100757D01*
X1059748Y100882D01*
X1060040Y101090D01*
X1060248Y101382D01*
X1060290Y101673D01*
X1060207Y101965D01*
X1059998Y102173D01*
G01X1060290Y104565D02*
X1060207Y104232D01*
X1059998Y103982D01*
X1059748Y103815D01*
X1059415Y103690D01*
X1059040Y103648D01*
X1058665Y103690D01*
X1058332Y103815D01*
X1058082Y103982D01*
X1057873Y104232D01*
X1057790Y104565D01*
X1057873Y104898D01*
X1058082Y105148D01*
X1058332Y105315D01*
X1058665Y105440D01*
X1059040Y105482D01*
X1059415Y105440D01*
X1059748Y105315D01*
X1059998Y105148D01*
X1060207Y104898D01*
X1060290Y104565D01*
G01X1053490Y97532D02*
X1055990D01*
Y98573D01*
X1055865Y98907D01*
X1055698Y99115D01*
X1055365Y99198D01*
X1055032Y99115D01*
X1054823Y98865D01*
X1054698Y98573D01*
Y97532D01*
G01Y98573D02*
X1053490Y99198D01*
G01Y101465D02*
X1055990D01*
X1055490Y100965D01*
G01X1053490D02*
Y101965D01*
G01X1063996Y82335D02*
Y84835D01*
X1062955D01*
X1062621Y84710D01*
X1062413Y84543D01*
X1062330Y84210D01*
X1062413Y83877D01*
X1062663Y83668D01*
X1062955Y83543D01*
X1063996D01*
G01X1062955D02*
X1062330Y82335D01*
G01X1060146D02*
X1060063Y82877D01*
X1059938Y83335D01*
X1059771Y83752D01*
X1059563Y84210D01*
X1059230Y84835D01*
X1060896D01*
G01X1057755Y84418D02*
X1057505Y84668D01*
X1057213Y84793D01*
X1056880Y84835D01*
X1056463Y84752D01*
X1056171Y84543D01*
X1056088Y84293D01*
X1056130Y84043D01*
X1056296Y83835D01*
X1057130Y83418D01*
X1057505Y83127D01*
X1057755Y82710D01*
X1057838Y82335D01*
X1056088D01*
G01X1053363D02*
Y84835D01*
X1054905Y83043D01*
X1052821D01*
G01X1085968Y82335D02*
Y84835D01*
X1084927D01*
X1084593Y84710D01*
X1084385Y84543D01*
X1084302Y84210D01*
X1084385Y83877D01*
X1084635Y83668D01*
X1084927Y83543D01*
X1085968D01*
G01X1084927D02*
X1084302Y82335D01*
G01X1082118D02*
X1082035Y82877D01*
X1081910Y83335D01*
X1081743Y83752D01*
X1081535Y84210D01*
X1081202Y84835D01*
X1082868D01*
G01X1079727Y84418D02*
X1079477Y84668D01*
X1079185Y84793D01*
X1078852Y84835D01*
X1078435Y84752D01*
X1078143Y84543D01*
X1078060Y84293D01*
X1078102Y84043D01*
X1078268Y83835D01*
X1079102Y83418D01*
X1079477Y83127D01*
X1079727Y82710D01*
X1079810Y82335D01*
X1078060D01*
G01X1076752Y82710D02*
X1076502Y82502D01*
X1076210Y82377D01*
X1075835Y82335D01*
X1075460Y82418D01*
X1075168Y82585D01*
X1074960Y82877D01*
X1074918Y83210D01*
X1075002Y83543D01*
X1075210Y83752D01*
X1075502Y83918D01*
X1075793Y83960D01*
X1076085Y83918D01*
X1076460Y83752D01*
X1076335Y84835D01*
X1075210D01*
G01X1081602Y137791D02*
X1081852Y137916D01*
X1082144Y137999D01*
X1082477D01*
X1082852Y137874D01*
X1083144Y137666D01*
X1083352Y137416D01*
X1083519Y136999D01*
X1083561Y136624D01*
X1083477Y136249D01*
X1083352Y135999D01*
X1083102Y135749D01*
X1082811Y135582D01*
X1082519Y135499D01*
X1082227D01*
X1081936Y135582D01*
X1081686Y135707D01*
X1081477Y135874D01*
G01X1080211Y136541D02*
X1079919Y136832D01*
X1079669Y136999D01*
X1079336Y137082D01*
X1079044Y136999D01*
X1078836Y136832D01*
X1078669Y136582D01*
X1078627Y136291D01*
X1078669Y136041D01*
X1078836Y135791D01*
X1079086Y135582D01*
X1079377Y135499D01*
X1079711Y135582D01*
X1080002Y135832D01*
X1080169Y136207D01*
X1080211Y136624D01*
X1080127Y137166D01*
X1080002Y137457D01*
X1079794Y137749D01*
X1079502Y137957D01*
X1079211Y137999D01*
X1078919Y137916D01*
X1078711Y137707D01*
G01X1076319Y137999D02*
X1076652Y137916D01*
X1076902Y137707D01*
X1077069Y137457D01*
X1077194Y137124D01*
X1077236Y136749D01*
X1077194Y136374D01*
X1077069Y136041D01*
X1076902Y135791D01*
X1076652Y135582D01*
X1076319Y135499D01*
X1075986Y135582D01*
X1075736Y135791D01*
X1075569Y136041D01*
X1075444Y136374D01*
X1075402Y136749D01*
X1075444Y137124D01*
X1075569Y137457D01*
X1075736Y137707D01*
X1075986Y137916D01*
X1076319Y137999D01*
G01X1074011Y136541D02*
X1073719Y136832D01*
X1073469Y136999D01*
X1073136Y137082D01*
X1072844Y136999D01*
X1072636Y136832D01*
X1072469Y136582D01*
X1072427Y136291D01*
X1072469Y136041D01*
X1072636Y135791D01*
X1072886Y135582D01*
X1073177Y135499D01*
X1073511Y135582D01*
X1073802Y135832D01*
X1073969Y136207D01*
X1074011Y136624D01*
X1073927Y137166D01*
X1073802Y137457D01*
X1073594Y137749D01*
X1073302Y137957D01*
X1073011Y137999D01*
X1072719Y137916D01*
X1072511Y137707D01*
G01X1081311Y141657D02*
X1081561Y141782D01*
X1081853Y141865D01*
X1082186D01*
X1082561Y141740D01*
X1082853Y141532D01*
X1083061Y141282D01*
X1083228Y140865D01*
X1083270Y140490D01*
X1083186Y140115D01*
X1083061Y139865D01*
X1082811Y139615D01*
X1082520Y139448D01*
X1082228Y139365D01*
X1081936D01*
X1081645Y139448D01*
X1081395Y139573D01*
X1081186Y139740D01*
G01X1080045D02*
X1079795Y139532D01*
X1079503Y139407D01*
X1079128Y139365D01*
X1078753Y139448D01*
X1078461Y139615D01*
X1078253Y139907D01*
X1078211Y140240D01*
X1078295Y140573D01*
X1078503Y140782D01*
X1078795Y140948D01*
X1079086Y140990D01*
X1079378Y140948D01*
X1079753Y140782D01*
X1079628Y141865D01*
X1078503D01*
G01X1076945Y139740D02*
X1076695Y139532D01*
X1076403Y139407D01*
X1076028Y139365D01*
X1075653Y139448D01*
X1075361Y139615D01*
X1075153Y139907D01*
X1075111Y140240D01*
X1075195Y140573D01*
X1075403Y140782D01*
X1075695Y140948D01*
X1075986Y140990D01*
X1076278Y140948D01*
X1076653Y140782D01*
X1076528Y141865D01*
X1075403D01*
G01X1073845Y139740D02*
X1073595Y139532D01*
X1073303Y139407D01*
X1072928Y139365D01*
X1072553Y139448D01*
X1072261Y139615D01*
X1072053Y139907D01*
X1072011Y140240D01*
X1072095Y140573D01*
X1072303Y140782D01*
X1072595Y140948D01*
X1072886Y140990D01*
X1073178Y140948D01*
X1073553Y140782D01*
X1073428Y141865D01*
X1072303D01*
G01X1081311Y145557D02*
X1081561Y145682D01*
X1081853Y145765D01*
X1082186D01*
X1082561Y145640D01*
X1082853Y145432D01*
X1083061Y145182D01*
X1083228Y144765D01*
X1083270Y144390D01*
X1083186Y144015D01*
X1083061Y143765D01*
X1082811Y143515D01*
X1082520Y143348D01*
X1082228Y143265D01*
X1081936D01*
X1081645Y143348D01*
X1081395Y143473D01*
X1081186Y143640D01*
G01X1080045D02*
X1079795Y143432D01*
X1079503Y143307D01*
X1079128Y143265D01*
X1078753Y143348D01*
X1078461Y143515D01*
X1078253Y143807D01*
X1078211Y144140D01*
X1078295Y144473D01*
X1078503Y144682D01*
X1078795Y144848D01*
X1079086Y144890D01*
X1079378Y144848D01*
X1079753Y144682D01*
X1079628Y145765D01*
X1078503D01*
G01X1076736Y143557D02*
X1076445Y143348D01*
X1076111Y143265D01*
X1075778Y143348D01*
X1075486Y143598D01*
X1075278Y143973D01*
X1075195Y144348D01*
Y144807D01*
X1075278Y145182D01*
X1075486Y145515D01*
X1075736Y145682D01*
X1076028Y145765D01*
X1076361Y145682D01*
X1076611Y145515D01*
X1076778Y145265D01*
X1076861Y144932D01*
X1076778Y144640D01*
X1076570Y144348D01*
X1076320Y144182D01*
X1076028Y144140D01*
X1075695Y144223D01*
X1075445Y144432D01*
X1075195Y144807D01*
G01X1073845Y143765D02*
X1073595Y143473D01*
X1073261Y143307D01*
X1072886Y143265D01*
X1072553Y143307D01*
X1072220Y143515D01*
X1072011Y143765D01*
X1071970Y144015D01*
X1072053Y144307D01*
X1072345Y144515D01*
X1072636Y144598D01*
X1073011D01*
G01X1072636D02*
X1072386Y144723D01*
X1072178Y144932D01*
X1072095Y145182D01*
X1072178Y145432D01*
X1072386Y145640D01*
X1072761Y145765D01*
X1073136Y145723D01*
X1073511Y145557D01*
G01X1081311Y149507D02*
X1081561Y149632D01*
X1081853Y149715D01*
X1082186D01*
X1082561Y149590D01*
X1082853Y149382D01*
X1083061Y149132D01*
X1083228Y148715D01*
X1083270Y148340D01*
X1083186Y147965D01*
X1083061Y147715D01*
X1082811Y147465D01*
X1082520Y147298D01*
X1082228Y147215D01*
X1081936D01*
X1081645Y147298D01*
X1081395Y147423D01*
X1081186Y147590D01*
G01X1080045D02*
X1079795Y147382D01*
X1079503Y147257D01*
X1079128Y147215D01*
X1078753Y147298D01*
X1078461Y147465D01*
X1078253Y147757D01*
X1078211Y148090D01*
X1078295Y148423D01*
X1078503Y148632D01*
X1078795Y148798D01*
X1079086Y148840D01*
X1079378Y148798D01*
X1079753Y148632D01*
X1079628Y149715D01*
X1078503D01*
G01X1076736Y147507D02*
X1076445Y147298D01*
X1076111Y147215D01*
X1075778Y147298D01*
X1075486Y147548D01*
X1075278Y147923D01*
X1075195Y148298D01*
Y148757D01*
X1075278Y149132D01*
X1075486Y149465D01*
X1075736Y149632D01*
X1076028Y149715D01*
X1076361Y149632D01*
X1076611Y149465D01*
X1076778Y149215D01*
X1076861Y148882D01*
X1076778Y148590D01*
X1076570Y148298D01*
X1076320Y148132D01*
X1076028Y148090D01*
X1075695Y148173D01*
X1075445Y148382D01*
X1075195Y148757D01*
G01X1073720Y149298D02*
X1073470Y149548D01*
X1073178Y149673D01*
X1072845Y149715D01*
X1072428Y149632D01*
X1072136Y149423D01*
X1072053Y149173D01*
X1072095Y148923D01*
X1072261Y148715D01*
X1073095Y148298D01*
X1073470Y148007D01*
X1073720Y147590D01*
X1073803Y147215D01*
X1072053D01*
G01X1074258Y153892D02*
X1074508Y154017D01*
X1074800Y154100D01*
X1075133D01*
X1075508Y153975D01*
X1075800Y153767D01*
X1076008Y153517D01*
X1076175Y153100D01*
X1076217Y152725D01*
X1076133Y152350D01*
X1076008Y152100D01*
X1075758Y151850D01*
X1075467Y151683D01*
X1075175Y151600D01*
X1074883D01*
X1074592Y151683D01*
X1074342Y151808D01*
X1074133Y151975D01*
G01X1072992D02*
X1072742Y151767D01*
X1072450Y151642D01*
X1072075Y151600D01*
X1071700Y151683D01*
X1071408Y151850D01*
X1071200Y152142D01*
X1071158Y152475D01*
X1071242Y152808D01*
X1071450Y153017D01*
X1071742Y153183D01*
X1072033Y153225D01*
X1072325Y153183D01*
X1072700Y153017D01*
X1072575Y154100D01*
X1071450D01*
G01X1069683Y151892D02*
X1069392Y151683D01*
X1069058Y151600D01*
X1068725Y151683D01*
X1068433Y151933D01*
X1068225Y152308D01*
X1068142Y152683D01*
Y153142D01*
X1068225Y153517D01*
X1068433Y153850D01*
X1068683Y154017D01*
X1068975Y154100D01*
X1069308Y154017D01*
X1069558Y153850D01*
X1069725Y153600D01*
X1069808Y153267D01*
X1069725Y152975D01*
X1069517Y152683D01*
X1069267Y152517D01*
X1068975Y152475D01*
X1068642Y152558D01*
X1068392Y152767D01*
X1068142Y153142D01*
G01X1065875Y151600D02*
Y154100D01*
X1066375Y153600D01*
G01Y151600D02*
X1065375D01*
G01X1080451Y157782D02*
X1080701Y157907D01*
X1080993Y157990D01*
X1081326D01*
X1081701Y157865D01*
X1081993Y157657D01*
X1082201Y157407D01*
X1082368Y156990D01*
X1082410Y156615D01*
X1082326Y156240D01*
X1082201Y155990D01*
X1081951Y155740D01*
X1081660Y155573D01*
X1081368Y155490D01*
X1081076D01*
X1080785Y155573D01*
X1080535Y155698D01*
X1080326Y155865D01*
G01X1079185D02*
X1078935Y155657D01*
X1078643Y155532D01*
X1078268Y155490D01*
X1077893Y155573D01*
X1077601Y155740D01*
X1077393Y156032D01*
X1077351Y156365D01*
X1077435Y156698D01*
X1077643Y156907D01*
X1077935Y157073D01*
X1078226Y157115D01*
X1078518Y157073D01*
X1078893Y156907D01*
X1078768Y157990D01*
X1077643D01*
G01X1075876Y155782D02*
X1075585Y155573D01*
X1075251Y155490D01*
X1074918Y155573D01*
X1074626Y155823D01*
X1074418Y156198D01*
X1074335Y156573D01*
Y157032D01*
X1074418Y157407D01*
X1074626Y157740D01*
X1074876Y157907D01*
X1075168Y157990D01*
X1075501Y157907D01*
X1075751Y157740D01*
X1075918Y157490D01*
X1076001Y157157D01*
X1075918Y156865D01*
X1075710Y156573D01*
X1075460Y156407D01*
X1075168Y156365D01*
X1074835Y156448D01*
X1074585Y156657D01*
X1074335Y157032D01*
G01X1072068Y157990D02*
X1072401Y157907D01*
X1072651Y157698D01*
X1072818Y157448D01*
X1072943Y157115D01*
X1072985Y156740D01*
X1072943Y156365D01*
X1072818Y156032D01*
X1072651Y155782D01*
X1072401Y155573D01*
X1072068Y155490D01*
X1071735Y155573D01*
X1071485Y155782D01*
X1071318Y156032D01*
X1071193Y156365D01*
X1071151Y156740D01*
X1071193Y157115D01*
X1071318Y157448D01*
X1071485Y157698D01*
X1071735Y157907D01*
X1072068Y157990D01*
G01X1055679Y162738D02*
X1055929Y162863D01*
X1056221Y162946D01*
X1056554D01*
X1056929Y162821D01*
X1057221Y162613D01*
X1057429Y162363D01*
X1057596Y161946D01*
X1057638Y161571D01*
X1057554Y161196D01*
X1057429Y160946D01*
X1057179Y160696D01*
X1056888Y160529D01*
X1056596Y160446D01*
X1056304D01*
X1056013Y160529D01*
X1055763Y160654D01*
X1055554Y160821D01*
G01X1052996Y160446D02*
Y162946D01*
X1054538Y161154D01*
X1052454D01*
G01X1050396Y160446D02*
X1050104Y160488D01*
X1049771Y160613D01*
X1049563Y160821D01*
X1049479Y161113D01*
X1049563Y161404D01*
X1049813Y161654D01*
X1050188Y161779D01*
X1050604D01*
X1050854Y161863D01*
X1051063Y162071D01*
X1051146Y162363D01*
X1051021Y162654D01*
X1050729Y162863D01*
X1050396Y162946D01*
X1050063Y162863D01*
X1049771Y162654D01*
X1049646Y162363D01*
X1049729Y162071D01*
X1049938Y161863D01*
X1050188Y161779D01*
X1050604D01*
X1050979Y161654D01*
X1051229Y161404D01*
X1051313Y161113D01*
X1051229Y160821D01*
X1051021Y160613D01*
X1050688Y160488D01*
X1050396Y160446D01*
G01X1046796D02*
Y162946D01*
X1048338Y161154D01*
X1046254D01*
G01X1059042Y149556D02*
X1059292Y149681D01*
X1059584Y149764D01*
X1059917D01*
X1060292Y149639D01*
X1060584Y149431D01*
X1060792Y149181D01*
X1060959Y148764D01*
X1061001Y148389D01*
X1060917Y148014D01*
X1060792Y147764D01*
X1060542Y147514D01*
X1060251Y147347D01*
X1059959Y147264D01*
X1059667D01*
X1059376Y147347D01*
X1059126Y147472D01*
X1058917Y147639D01*
G01X1056359Y147264D02*
Y149764D01*
X1057901Y147972D01*
X1055817D01*
G01X1053759Y147264D02*
X1053467Y147306D01*
X1053134Y147431D01*
X1052926Y147639D01*
X1052842Y147931D01*
X1052926Y148222D01*
X1053176Y148472D01*
X1053551Y148597D01*
X1053967D01*
X1054217Y148681D01*
X1054426Y148889D01*
X1054509Y149181D01*
X1054384Y149472D01*
X1054092Y149681D01*
X1053759Y149764D01*
X1053426Y149681D01*
X1053134Y149472D01*
X1053009Y149181D01*
X1053092Y148889D01*
X1053301Y148681D01*
X1053551Y148597D01*
X1053967D01*
X1054342Y148472D01*
X1054592Y148222D01*
X1054676Y147931D01*
X1054592Y147639D01*
X1054384Y147431D01*
X1054051Y147306D01*
X1053759Y147264D01*
G01X1051576Y147764D02*
X1051326Y147472D01*
X1050992Y147306D01*
X1050617Y147264D01*
X1050284Y147306D01*
X1049951Y147514D01*
X1049742Y147764D01*
X1049701Y148014D01*
X1049784Y148306D01*
X1050076Y148514D01*
X1050367Y148597D01*
X1050742D01*
G01X1050367D02*
X1050117Y148722D01*
X1049909Y148931D01*
X1049826Y149181D01*
X1049909Y149431D01*
X1050117Y149639D01*
X1050492Y149764D01*
X1050867Y149722D01*
X1051242Y149556D01*
G01X1069205Y145429D02*
Y142929D01*
G01X1070163Y145429D02*
X1068247D01*
G01X1066938Y142929D02*
Y145429D01*
X1065938D01*
X1065605Y145304D01*
X1065355Y145012D01*
X1065272Y144679D01*
X1065355Y144346D01*
X1065563Y144096D01*
X1065938Y143971D01*
X1066938D01*
G01X1063797Y145012D02*
X1063547Y145262D01*
X1063255Y145387D01*
X1062922Y145429D01*
X1062505Y145346D01*
X1062213Y145137D01*
X1062130Y144887D01*
X1062172Y144637D01*
X1062338Y144429D01*
X1063172Y144012D01*
X1063547Y143721D01*
X1063797Y143304D01*
X1063880Y142929D01*
X1062130D01*
G01X1060613Y143221D02*
X1060322Y143012D01*
X1059988Y142929D01*
X1059655Y143012D01*
X1059363Y143262D01*
X1059155Y143637D01*
X1059072Y144012D01*
Y144471D01*
X1059155Y144846D01*
X1059363Y145179D01*
X1059613Y145346D01*
X1059905Y145429D01*
X1060238Y145346D01*
X1060488Y145179D01*
X1060655Y144929D01*
X1060738Y144596D01*
X1060655Y144304D01*
X1060447Y144012D01*
X1060197Y143846D01*
X1059905Y143804D01*
X1059572Y143887D01*
X1059322Y144096D01*
X1059072Y144471D01*
G01X1056888Y142929D02*
X1056805Y143471D01*
X1056680Y143929D01*
X1056513Y144346D01*
X1056305Y144804D01*
X1055972Y145429D01*
X1057638D01*
G01X1072743Y162681D02*
Y160181D01*
G01X1073701Y162681D02*
X1071785D01*
G01X1070476Y160181D02*
Y162681D01*
X1069476D01*
X1069143Y162556D01*
X1068893Y162264D01*
X1068810Y161931D01*
X1068893Y161598D01*
X1069101Y161348D01*
X1069476Y161223D01*
X1070476D01*
G01X1067335Y162264D02*
X1067085Y162514D01*
X1066793Y162639D01*
X1066460Y162681D01*
X1066043Y162598D01*
X1065751Y162389D01*
X1065668Y162139D01*
X1065710Y161889D01*
X1065876Y161681D01*
X1066710Y161264D01*
X1067085Y160973D01*
X1067335Y160556D01*
X1067418Y160181D01*
X1065668D01*
G01X1063443D02*
X1063151Y160223D01*
X1062818Y160348D01*
X1062610Y160556D01*
X1062526Y160848D01*
X1062610Y161139D01*
X1062860Y161389D01*
X1063235Y161514D01*
X1063651D01*
X1063901Y161598D01*
X1064110Y161806D01*
X1064193Y162098D01*
X1064068Y162389D01*
X1063776Y162598D01*
X1063443Y162681D01*
X1063110Y162598D01*
X1062818Y162389D01*
X1062693Y162098D01*
X1062776Y161806D01*
X1062985Y161598D01*
X1063235Y161514D01*
X1063651D01*
X1064026Y161389D01*
X1064276Y161139D01*
X1064360Y160848D01*
X1064276Y160556D01*
X1064068Y160348D01*
X1063735Y160223D01*
X1063443Y160181D01*
G01X1060343D02*
X1060051Y160223D01*
X1059718Y160348D01*
X1059510Y160556D01*
X1059426Y160848D01*
X1059510Y161139D01*
X1059760Y161389D01*
X1060135Y161514D01*
X1060551D01*
X1060801Y161598D01*
X1061010Y161806D01*
X1061093Y162098D01*
X1060968Y162389D01*
X1060676Y162598D01*
X1060343Y162681D01*
X1060010Y162598D01*
X1059718Y162389D01*
X1059593Y162098D01*
X1059676Y161806D01*
X1059885Y161598D01*
X1060135Y161514D01*
X1060551D01*
X1060926Y161389D01*
X1061176Y161139D01*
X1061260Y160848D01*
X1061176Y160556D01*
X1060968Y160348D01*
X1060635Y160223D01*
X1060343Y160181D01*
G01X1062437Y154055D02*
Y151555D01*
G01X1063395Y154055D02*
X1061479D01*
G01X1060170Y151555D02*
Y154055D01*
X1059170D01*
X1058837Y153930D01*
X1058587Y153638D01*
X1058504Y153305D01*
X1058587Y152972D01*
X1058795Y152722D01*
X1059170Y152597D01*
X1060170D01*
G01X1057029Y153638D02*
X1056779Y153888D01*
X1056487Y154013D01*
X1056154Y154055D01*
X1055737Y153972D01*
X1055445Y153763D01*
X1055362Y153513D01*
X1055404Y153263D01*
X1055570Y153055D01*
X1056404Y152638D01*
X1056779Y152347D01*
X1057029Y151930D01*
X1057112Y151555D01*
X1055362D01*
G01X1053137D02*
X1052845Y151597D01*
X1052512Y151722D01*
X1052304Y151930D01*
X1052220Y152222D01*
X1052304Y152513D01*
X1052554Y152763D01*
X1052929Y152888D01*
X1053345D01*
X1053595Y152972D01*
X1053804Y153180D01*
X1053887Y153472D01*
X1053762Y153763D01*
X1053470Y153972D01*
X1053137Y154055D01*
X1052804Y153972D01*
X1052512Y153763D01*
X1052387Y153472D01*
X1052470Y153180D01*
X1052679Y152972D01*
X1052929Y152888D01*
X1053345D01*
X1053720Y152763D01*
X1053970Y152513D01*
X1054054Y152222D01*
X1053970Y151930D01*
X1053762Y151722D01*
X1053429Y151597D01*
X1053137Y151555D01*
G01X1050037D02*
Y154055D01*
X1050537Y153555D01*
G01Y151555D02*
X1049537D01*
G01X1057128Y158522D02*
Y156022D01*
G01X1058086Y158522D02*
X1056170D01*
G01X1054861Y156022D02*
Y158522D01*
X1053861D01*
X1053528Y158397D01*
X1053278Y158105D01*
X1053195Y157772D01*
X1053278Y157439D01*
X1053486Y157189D01*
X1053861Y157064D01*
X1054861D01*
G01X1051720Y158105D02*
X1051470Y158355D01*
X1051178Y158480D01*
X1050845Y158522D01*
X1050428Y158439D01*
X1050136Y158230D01*
X1050053Y157980D01*
X1050095Y157730D01*
X1050261Y157522D01*
X1051095Y157105D01*
X1051470Y156814D01*
X1051720Y156397D01*
X1051803Y156022D01*
X1050053D01*
G01X1047828Y158522D02*
X1048161Y158439D01*
X1048411Y158230D01*
X1048578Y157980D01*
X1048703Y157647D01*
X1048745Y157272D01*
X1048703Y156897D01*
X1048578Y156564D01*
X1048411Y156314D01*
X1048161Y156105D01*
X1047828Y156022D01*
X1047495Y156105D01*
X1047245Y156314D01*
X1047078Y156564D01*
X1046953Y156897D01*
X1046911Y157272D01*
X1046953Y157647D01*
X1047078Y157980D01*
X1047245Y158230D01*
X1047495Y158439D01*
X1047828Y158522D01*
G01X1045436Y156314D02*
X1045145Y156105D01*
X1044811Y156022D01*
X1044478Y156105D01*
X1044186Y156355D01*
X1043978Y156730D01*
X1043895Y157105D01*
Y157564D01*
X1043978Y157939D01*
X1044186Y158272D01*
X1044436Y158439D01*
X1044728Y158522D01*
X1045061Y158439D01*
X1045311Y158272D01*
X1045478Y158022D01*
X1045561Y157689D01*
X1045478Y157397D01*
X1045270Y157105D01*
X1045020Y156939D01*
X1044728Y156897D01*
X1044395Y156980D01*
X1044145Y157189D01*
X1043895Y157564D01*
G01X1089110Y162680D02*
Y160180D01*
G01X1090068Y162680D02*
X1088152D01*
G01X1086843Y160180D02*
Y162680D01*
X1085843D01*
X1085510Y162555D01*
X1085260Y162263D01*
X1085177Y161930D01*
X1085260Y161597D01*
X1085468Y161347D01*
X1085843Y161222D01*
X1086843D01*
G01X1083702Y162263D02*
X1083452Y162513D01*
X1083160Y162638D01*
X1082827Y162680D01*
X1082410Y162597D01*
X1082118Y162388D01*
X1082035Y162138D01*
X1082077Y161888D01*
X1082243Y161680D01*
X1083077Y161263D01*
X1083452Y160972D01*
X1083702Y160555D01*
X1083785Y160180D01*
X1082035D01*
G01X1079810Y162680D02*
X1080143Y162597D01*
X1080393Y162388D01*
X1080560Y162138D01*
X1080685Y161805D01*
X1080727Y161430D01*
X1080685Y161055D01*
X1080560Y160722D01*
X1080393Y160472D01*
X1080143Y160263D01*
X1079810Y160180D01*
X1079477Y160263D01*
X1079227Y160472D01*
X1079060Y160722D01*
X1078935Y161055D01*
X1078893Y161430D01*
X1078935Y161805D01*
X1079060Y162138D01*
X1079227Y162388D01*
X1079477Y162597D01*
X1079810Y162680D01*
G01X1077502Y161222D02*
X1077210Y161513D01*
X1076960Y161680D01*
X1076627Y161763D01*
X1076335Y161680D01*
X1076127Y161513D01*
X1075960Y161263D01*
X1075918Y160972D01*
X1075960Y160722D01*
X1076127Y160472D01*
X1076377Y160263D01*
X1076668Y160180D01*
X1077002Y160263D01*
X1077293Y160513D01*
X1077460Y160888D01*
X1077502Y161305D01*
X1077418Y161847D01*
X1077293Y162138D01*
X1077085Y162430D01*
X1076793Y162638D01*
X1076502Y162680D01*
X1076210Y162597D01*
X1076002Y162388D01*
G01X1068570Y155683D02*
Y158183D01*
X1067529D01*
X1067195Y158058D01*
X1066987Y157891D01*
X1066904Y157558D01*
X1066987Y157225D01*
X1067237Y157016D01*
X1067529Y156891D01*
X1068570D01*
G01X1067529D02*
X1066904Y155683D01*
G01X1064137D02*
Y158183D01*
X1065679Y156391D01*
X1063595D01*
G01X1062329Y157766D02*
X1062079Y158016D01*
X1061787Y158141D01*
X1061454Y158183D01*
X1061037Y158100D01*
X1060745Y157891D01*
X1060662Y157641D01*
X1060704Y157391D01*
X1060870Y157183D01*
X1061704Y156766D01*
X1062079Y156475D01*
X1062329Y156058D01*
X1062412Y155683D01*
X1060662D01*
G01X1105033Y2300D02*
Y4800D01*
X1103992D01*
X1103658Y4675D01*
X1103450Y4508D01*
X1103367Y4175D01*
X1103450Y3842D01*
X1103700Y3633D01*
X1103992Y3508D01*
X1105033D01*
G01X1103992D02*
X1103367Y2300D01*
G01X1101892Y4383D02*
X1101642Y4633D01*
X1101350Y4758D01*
X1101017Y4800D01*
X1100600Y4717D01*
X1100308Y4508D01*
X1100225Y4258D01*
X1100267Y4008D01*
X1100433Y3800D01*
X1101267Y3383D01*
X1101642Y3092D01*
X1101892Y2675D01*
X1101975Y2300D01*
X1100225D01*
G01X1098708Y2592D02*
X1098417Y2383D01*
X1098083Y2300D01*
X1097750Y2383D01*
X1097458Y2633D01*
X1097250Y3008D01*
X1097167Y3383D01*
Y3842D01*
X1097250Y4217D01*
X1097458Y4550D01*
X1097708Y4717D01*
X1098000Y4800D01*
X1098333Y4717D01*
X1098583Y4550D01*
X1098750Y4300D01*
X1098833Y3967D01*
X1098750Y3675D01*
X1098542Y3383D01*
X1098292Y3217D01*
X1098000Y3175D01*
X1097667Y3258D01*
X1097417Y3467D01*
X1097167Y3842D01*
G01X1094900Y2300D02*
Y4800D01*
X1095400Y4300D01*
G01Y2300D02*
X1094400D01*
G01X1092717Y2800D02*
X1092467Y2508D01*
X1092133Y2342D01*
X1091758Y2300D01*
X1091425Y2342D01*
X1091092Y2550D01*
X1090883Y2800D01*
X1090842Y3050D01*
X1090925Y3342D01*
X1091217Y3550D01*
X1091508Y3633D01*
X1091883D01*
G01X1091508D02*
X1091258Y3758D01*
X1091050Y3967D01*
X1090967Y4217D01*
X1091050Y4467D01*
X1091258Y4675D01*
X1091633Y4800D01*
X1092008Y4758D01*
X1092383Y4592D01*
G01X1096233Y6900D02*
Y9400D01*
X1095192D01*
X1094858Y9275D01*
X1094650Y9108D01*
X1094567Y8775D01*
X1094650Y8442D01*
X1094900Y8233D01*
X1095192Y8108D01*
X1096233D01*
G01X1095192D02*
X1094567Y6900D01*
G01X1093092Y8983D02*
X1092842Y9233D01*
X1092550Y9358D01*
X1092217Y9400D01*
X1091800Y9317D01*
X1091508Y9108D01*
X1091425Y8858D01*
X1091467Y8608D01*
X1091633Y8400D01*
X1092467Y7983D01*
X1092842Y7692D01*
X1093092Y7275D01*
X1093175Y6900D01*
X1091425D01*
G01X1089908Y7192D02*
X1089617Y6983D01*
X1089283Y6900D01*
X1088950Y6983D01*
X1088658Y7233D01*
X1088450Y7608D01*
X1088367Y7983D01*
Y8442D01*
X1088450Y8817D01*
X1088658Y9150D01*
X1088908Y9317D01*
X1089200Y9400D01*
X1089533Y9317D01*
X1089783Y9150D01*
X1089950Y8900D01*
X1090033Y8567D01*
X1089950Y8275D01*
X1089742Y7983D01*
X1089492Y7817D01*
X1089200Y7775D01*
X1088867Y7858D01*
X1088617Y8067D01*
X1088367Y8442D01*
G01X1086100Y9400D02*
X1086433Y9317D01*
X1086683Y9108D01*
X1086850Y8858D01*
X1086975Y8525D01*
X1087017Y8150D01*
X1086975Y7775D01*
X1086850Y7442D01*
X1086683Y7192D01*
X1086433Y6983D01*
X1086100Y6900D01*
X1085767Y6983D01*
X1085517Y7192D01*
X1085350Y7442D01*
X1085225Y7775D01*
X1085183Y8150D01*
X1085225Y8525D01*
X1085350Y8858D01*
X1085517Y9108D01*
X1085767Y9317D01*
X1086100Y9400D01*
G01X1083000Y6900D02*
X1082708Y6942D01*
X1082375Y7067D01*
X1082167Y7275D01*
X1082083Y7567D01*
X1082167Y7858D01*
X1082417Y8108D01*
X1082792Y8233D01*
X1083208D01*
X1083458Y8317D01*
X1083667Y8525D01*
X1083750Y8817D01*
X1083625Y9108D01*
X1083333Y9317D01*
X1083000Y9400D01*
X1082667Y9317D01*
X1082375Y9108D01*
X1082250Y8817D01*
X1082333Y8525D01*
X1082542Y8317D01*
X1082792Y8233D01*
X1083208D01*
X1083583Y8108D01*
X1083833Y7858D01*
X1083917Y7567D01*
X1083833Y7275D01*
X1083625Y7067D01*
X1083292Y6942D01*
X1083000Y6900D01*
G01X1107228Y1562D02*
X1109728D01*
Y2603D01*
X1109603Y2937D01*
X1109436Y3145D01*
X1109103Y3228D01*
X1108770Y3145D01*
X1108561Y2895D01*
X1108436Y2603D01*
Y1562D01*
G01Y2603D02*
X1107228Y3228D01*
G01X1107728Y4578D02*
X1107436Y4828D01*
X1107270Y5162D01*
X1107228Y5537D01*
X1107270Y5870D01*
X1107478Y6203D01*
X1107728Y6412D01*
X1107978Y6453D01*
X1108270Y6370D01*
X1108478Y6078D01*
X1108561Y5787D01*
Y5412D01*
G01Y5787D02*
X1108686Y6037D01*
X1108895Y6245D01*
X1109145Y6328D01*
X1109395Y6245D01*
X1109603Y6037D01*
X1109728Y5662D01*
X1109686Y5287D01*
X1109520Y4912D01*
G01X1107228Y8595D02*
X1107270Y8887D01*
X1107395Y9220D01*
X1107603Y9428D01*
X1107895Y9512D01*
X1108186Y9428D01*
X1108436Y9178D01*
X1108561Y8803D01*
Y8387D01*
X1108645Y8137D01*
X1108853Y7928D01*
X1109145Y7845D01*
X1109436Y7970D01*
X1109645Y8262D01*
X1109728Y8595D01*
X1109645Y8928D01*
X1109436Y9220D01*
X1109145Y9345D01*
X1108853Y9262D01*
X1108645Y9053D01*
X1108561Y8803D01*
Y8387D01*
X1108436Y8012D01*
X1108186Y7762D01*
X1107895Y7678D01*
X1107603Y7762D01*
X1107395Y7970D01*
X1107270Y8303D01*
X1107228Y8595D01*
G01X1107520Y10987D02*
X1107311Y11278D01*
X1107228Y11612D01*
X1107311Y11945D01*
X1107561Y12237D01*
X1107936Y12445D01*
X1108311Y12528D01*
X1108770D01*
X1109145Y12445D01*
X1109478Y12237D01*
X1109645Y11987D01*
X1109728Y11695D01*
X1109645Y11362D01*
X1109478Y11112D01*
X1109228Y10945D01*
X1108895Y10862D01*
X1108603Y10945D01*
X1108311Y11153D01*
X1108145Y11403D01*
X1108103Y11695D01*
X1108186Y12028D01*
X1108395Y12278D01*
X1108770Y12528D01*
G01X1096333Y11700D02*
Y14200D01*
X1095292D01*
X1094958Y14075D01*
X1094750Y13908D01*
X1094667Y13575D01*
X1094750Y13242D01*
X1095000Y13033D01*
X1095292Y12908D01*
X1096333D01*
G01X1095292D02*
X1094667Y11700D01*
G01X1093192Y13783D02*
X1092942Y14033D01*
X1092650Y14158D01*
X1092317Y14200D01*
X1091900Y14117D01*
X1091608Y13908D01*
X1091525Y13658D01*
X1091567Y13408D01*
X1091733Y13200D01*
X1092567Y12783D01*
X1092942Y12492D01*
X1093192Y12075D01*
X1093275Y11700D01*
X1091525D01*
G01X1090008Y11992D02*
X1089717Y11783D01*
X1089383Y11700D01*
X1089050Y11783D01*
X1088758Y12033D01*
X1088550Y12408D01*
X1088467Y12783D01*
Y13242D01*
X1088550Y13617D01*
X1088758Y13950D01*
X1089008Y14117D01*
X1089300Y14200D01*
X1089633Y14117D01*
X1089883Y13950D01*
X1090050Y13700D01*
X1090133Y13367D01*
X1090050Y13075D01*
X1089842Y12783D01*
X1089592Y12617D01*
X1089300Y12575D01*
X1088967Y12658D01*
X1088717Y12867D01*
X1088467Y13242D01*
G01X1086200Y11700D02*
Y14200D01*
X1086700Y13700D01*
G01Y11700D02*
X1085700D01*
G01X1082600D02*
Y14200D01*
X1084142Y12408D01*
X1082058D01*
G01X1116383Y26400D02*
Y28900D01*
X1115342D01*
X1115008Y28775D01*
X1114800Y28608D01*
X1114717Y28275D01*
X1114800Y27942D01*
X1115050Y27733D01*
X1115342Y27608D01*
X1116383D01*
G01X1115342D02*
X1114717Y26400D01*
G01X1113242Y28483D02*
X1112992Y28733D01*
X1112700Y28858D01*
X1112367Y28900D01*
X1111950Y28817D01*
X1111658Y28608D01*
X1111575Y28358D01*
X1111617Y28108D01*
X1111783Y27900D01*
X1112617Y27483D01*
X1112992Y27192D01*
X1113242Y26775D01*
X1113325Y26400D01*
X1111575D01*
G01X1109433D02*
X1109350Y26942D01*
X1109225Y27400D01*
X1109058Y27817D01*
X1108850Y28275D01*
X1108517Y28900D01*
X1110183D01*
G01X1106333Y26400D02*
X1106250Y26942D01*
X1106125Y27400D01*
X1105958Y27817D01*
X1105750Y28275D01*
X1105417Y28900D01*
X1107083D01*
G01X1103433Y30700D02*
Y33200D01*
X1102392D01*
X1102058Y33075D01*
X1101850Y32908D01*
X1101767Y32575D01*
X1101850Y32242D01*
X1102100Y32033D01*
X1102392Y31908D01*
X1103433D01*
G01X1102392D02*
X1101767Y30700D01*
G01X1100292Y32783D02*
X1100042Y33033D01*
X1099750Y33158D01*
X1099417Y33200D01*
X1099000Y33117D01*
X1098708Y32908D01*
X1098625Y32658D01*
X1098667Y32408D01*
X1098833Y32200D01*
X1099667Y31783D01*
X1100042Y31492D01*
X1100292Y31075D01*
X1100375Y30700D01*
X1098625D01*
G01X1097108Y30992D02*
X1096817Y30783D01*
X1096483Y30700D01*
X1096150Y30783D01*
X1095858Y31033D01*
X1095650Y31408D01*
X1095567Y31783D01*
Y32242D01*
X1095650Y32617D01*
X1095858Y32950D01*
X1096108Y33117D01*
X1096400Y33200D01*
X1096733Y33117D01*
X1096983Y32950D01*
X1097150Y32700D01*
X1097233Y32367D01*
X1097150Y32075D01*
X1096942Y31783D01*
X1096692Y31617D01*
X1096400Y31575D01*
X1096067Y31658D01*
X1095817Y31867D01*
X1095567Y32242D01*
G01X1094092Y31742D02*
X1093800Y32033D01*
X1093550Y32200D01*
X1093217Y32283D01*
X1092925Y32200D01*
X1092717Y32033D01*
X1092550Y31783D01*
X1092508Y31492D01*
X1092550Y31242D01*
X1092717Y30992D01*
X1092967Y30783D01*
X1093258Y30700D01*
X1093592Y30783D01*
X1093883Y31033D01*
X1094050Y31408D01*
X1094092Y31825D01*
X1094008Y32367D01*
X1093883Y32658D01*
X1093675Y32950D01*
X1093383Y33158D01*
X1093092Y33200D01*
X1092800Y33117D01*
X1092592Y32908D01*
G01X1089700Y30700D02*
Y33200D01*
X1091242Y31408D01*
X1089158D01*
G01X1102933Y22500D02*
Y25000D01*
X1101892D01*
X1101558Y24875D01*
X1101350Y24708D01*
X1101267Y24375D01*
X1101350Y24042D01*
X1101600Y23833D01*
X1101892Y23708D01*
X1102933D01*
G01X1101892D02*
X1101267Y22500D01*
G01X1099792Y24583D02*
X1099542Y24833D01*
X1099250Y24958D01*
X1098917Y25000D01*
X1098500Y24917D01*
X1098208Y24708D01*
X1098125Y24458D01*
X1098167Y24208D01*
X1098333Y24000D01*
X1099167Y23583D01*
X1099542Y23292D01*
X1099792Y22875D01*
X1099875Y22500D01*
X1098125D01*
G01X1096608Y22792D02*
X1096317Y22583D01*
X1095983Y22500D01*
X1095650Y22583D01*
X1095358Y22833D01*
X1095150Y23208D01*
X1095067Y23583D01*
Y24042D01*
X1095150Y24417D01*
X1095358Y24750D01*
X1095608Y24917D01*
X1095900Y25000D01*
X1096233Y24917D01*
X1096483Y24750D01*
X1096650Y24500D01*
X1096733Y24167D01*
X1096650Y23875D01*
X1096442Y23583D01*
X1096192Y23417D01*
X1095900Y23375D01*
X1095567Y23458D01*
X1095317Y23667D01*
X1095067Y24042D01*
G01X1093592Y23542D02*
X1093300Y23833D01*
X1093050Y24000D01*
X1092717Y24083D01*
X1092425Y24000D01*
X1092217Y23833D01*
X1092050Y23583D01*
X1092008Y23292D01*
X1092050Y23042D01*
X1092217Y22792D01*
X1092467Y22583D01*
X1092758Y22500D01*
X1093092Y22583D01*
X1093383Y22833D01*
X1093550Y23208D01*
X1093592Y23625D01*
X1093508Y24167D01*
X1093383Y24458D01*
X1093175Y24750D01*
X1092883Y24958D01*
X1092592Y25000D01*
X1092300Y24917D01*
X1092092Y24708D01*
G01X1090617Y22875D02*
X1090367Y22667D01*
X1090075Y22542D01*
X1089700Y22500D01*
X1089325Y22583D01*
X1089033Y22750D01*
X1088825Y23042D01*
X1088783Y23375D01*
X1088867Y23708D01*
X1089075Y23917D01*
X1089367Y24083D01*
X1089658Y24125D01*
X1089950Y24083D01*
X1090325Y23917D01*
X1090200Y25000D01*
X1089075D01*
G01X1103433Y26700D02*
Y29200D01*
X1102392D01*
X1102058Y29075D01*
X1101850Y28908D01*
X1101767Y28575D01*
X1101850Y28242D01*
X1102100Y28033D01*
X1102392Y27908D01*
X1103433D01*
G01X1102392D02*
X1101767Y26700D01*
G01X1100292Y28783D02*
X1100042Y29033D01*
X1099750Y29158D01*
X1099417Y29200D01*
X1099000Y29117D01*
X1098708Y28908D01*
X1098625Y28658D01*
X1098667Y28408D01*
X1098833Y28200D01*
X1099667Y27783D01*
X1100042Y27492D01*
X1100292Y27075D01*
X1100375Y26700D01*
X1098625D01*
G01X1097108Y26992D02*
X1096817Y26783D01*
X1096483Y26700D01*
X1096150Y26783D01*
X1095858Y27033D01*
X1095650Y27408D01*
X1095567Y27783D01*
Y28242D01*
X1095650Y28617D01*
X1095858Y28950D01*
X1096108Y29117D01*
X1096400Y29200D01*
X1096733Y29117D01*
X1096983Y28950D01*
X1097150Y28700D01*
X1097233Y28367D01*
X1097150Y28075D01*
X1096942Y27783D01*
X1096692Y27617D01*
X1096400Y27575D01*
X1096067Y27658D01*
X1095817Y27867D01*
X1095567Y28242D01*
G01X1093383Y26700D02*
X1093300Y27242D01*
X1093175Y27700D01*
X1093008Y28117D01*
X1092800Y28575D01*
X1092467Y29200D01*
X1094133D01*
G01X1089700Y26700D02*
Y29200D01*
X1091242Y27408D01*
X1089158D01*
G01X1115628Y14145D02*
Y16645D01*
X1114587D01*
X1114253Y16520D01*
X1114045Y16353D01*
X1113962Y16020D01*
X1114045Y15687D01*
X1114295Y15478D01*
X1114587Y15353D01*
X1115628D01*
G01X1114587D02*
X1113962Y14145D01*
G01X1112487Y16228D02*
X1112237Y16478D01*
X1111945Y16603D01*
X1111612Y16645D01*
X1111195Y16562D01*
X1110903Y16353D01*
X1110820Y16103D01*
X1110862Y15853D01*
X1111028Y15645D01*
X1111862Y15228D01*
X1112237Y14937D01*
X1112487Y14520D01*
X1112570Y14145D01*
X1110820D01*
G01X1109303Y14437D02*
X1109012Y14228D01*
X1108678Y14145D01*
X1108345Y14228D01*
X1108053Y14478D01*
X1107845Y14853D01*
X1107762Y15228D01*
Y15687D01*
X1107845Y16062D01*
X1108053Y16395D01*
X1108303Y16562D01*
X1108595Y16645D01*
X1108928Y16562D01*
X1109178Y16395D01*
X1109345Y16145D01*
X1109428Y15812D01*
X1109345Y15520D01*
X1109137Y15228D01*
X1108887Y15062D01*
X1108595Y15020D01*
X1108262Y15103D01*
X1108012Y15312D01*
X1107762Y15687D01*
G01X1105578Y14145D02*
X1105495Y14687D01*
X1105370Y15145D01*
X1105203Y15562D01*
X1104995Y16020D01*
X1104662Y16645D01*
X1106328D01*
G01X1103312Y14520D02*
X1103062Y14312D01*
X1102770Y14187D01*
X1102395Y14145D01*
X1102020Y14228D01*
X1101728Y14395D01*
X1101520Y14687D01*
X1101478Y15020D01*
X1101562Y15353D01*
X1101770Y15562D01*
X1102062Y15728D01*
X1102353Y15770D01*
X1102645Y15728D01*
X1103020Y15562D01*
X1102895Y16645D01*
X1101770D01*
G01X1116083Y30600D02*
Y33100D01*
X1115042D01*
X1114708Y32975D01*
X1114500Y32808D01*
X1114417Y32475D01*
X1114500Y32142D01*
X1114750Y31933D01*
X1115042Y31808D01*
X1116083D01*
G01X1115042D02*
X1114417Y30600D01*
G01X1113067Y31100D02*
X1112817Y30808D01*
X1112483Y30642D01*
X1112108Y30600D01*
X1111775Y30642D01*
X1111442Y30850D01*
X1111233Y31100D01*
X1111192Y31350D01*
X1111275Y31642D01*
X1111567Y31850D01*
X1111858Y31933D01*
X1112233D01*
G01X1111858D02*
X1111608Y32058D01*
X1111400Y32267D01*
X1111317Y32517D01*
X1111400Y32767D01*
X1111608Y32975D01*
X1111983Y33100D01*
X1112358Y33058D01*
X1112733Y32892D01*
G01X1109050Y30600D02*
X1108758Y30642D01*
X1108425Y30767D01*
X1108217Y30975D01*
X1108133Y31267D01*
X1108217Y31558D01*
X1108467Y31808D01*
X1108842Y31933D01*
X1109258D01*
X1109508Y32017D01*
X1109717Y32225D01*
X1109800Y32517D01*
X1109675Y32808D01*
X1109383Y33017D01*
X1109050Y33100D01*
X1108717Y33017D01*
X1108425Y32808D01*
X1108300Y32517D01*
X1108383Y32225D01*
X1108592Y32017D01*
X1108842Y31933D01*
X1109258D01*
X1109633Y31808D01*
X1109883Y31558D01*
X1109967Y31267D01*
X1109883Y30975D01*
X1109675Y30767D01*
X1109342Y30642D01*
X1109050Y30600D01*
G01X1105950D02*
X1105658Y30642D01*
X1105325Y30767D01*
X1105117Y30975D01*
X1105033Y31267D01*
X1105117Y31558D01*
X1105367Y31808D01*
X1105742Y31933D01*
X1106158D01*
X1106408Y32017D01*
X1106617Y32225D01*
X1106700Y32517D01*
X1106575Y32808D01*
X1106283Y33017D01*
X1105950Y33100D01*
X1105617Y33017D01*
X1105325Y32808D01*
X1105200Y32517D01*
X1105283Y32225D01*
X1105492Y32017D01*
X1105742Y31933D01*
X1106158D01*
X1106533Y31808D01*
X1106783Y31558D01*
X1106867Y31267D01*
X1106783Y30975D01*
X1106575Y30767D01*
X1106242Y30642D01*
X1105950Y30600D01*
G01X1091600Y37617D02*
X1094100D01*
Y38658D01*
X1093975Y38992D01*
X1093808Y39200D01*
X1093475Y39283D01*
X1093142Y39200D01*
X1092933Y38950D01*
X1092808Y38658D01*
Y37617D01*
G01Y38658D02*
X1091600Y39283D01*
G01Y41467D02*
X1092142Y41550D01*
X1092600Y41675D01*
X1093017Y41842D01*
X1093475Y42050D01*
X1094100Y42383D01*
Y40717D01*
G01X1093683Y43858D02*
X1093933Y44108D01*
X1094058Y44400D01*
X1094100Y44733D01*
X1094017Y45150D01*
X1093808Y45442D01*
X1093558Y45525D01*
X1093308Y45483D01*
X1093100Y45317D01*
X1092683Y44483D01*
X1092392Y44108D01*
X1091975Y43858D01*
X1091600Y43775D01*
Y45525D01*
G01X1092100Y46833D02*
X1091808Y47083D01*
X1091642Y47417D01*
X1091600Y47792D01*
X1091642Y48125D01*
X1091850Y48458D01*
X1092100Y48667D01*
X1092350Y48708D01*
X1092642Y48625D01*
X1092850Y48333D01*
X1092933Y48042D01*
Y47667D01*
G01Y48042D02*
X1093058Y48292D01*
X1093267Y48500D01*
X1093517Y48583D01*
X1093767Y48500D01*
X1093975Y48292D01*
X1094100Y47917D01*
X1094058Y47542D01*
X1093892Y47167D01*
G01X1100329Y67499D02*
Y69999D01*
X1099288D01*
X1098954Y69874D01*
X1098746Y69707D01*
X1098663Y69374D01*
X1098746Y69041D01*
X1098996Y68832D01*
X1099288Y68707D01*
X1100329D01*
G01X1099288D02*
X1098663Y67499D01*
G01X1097188Y69582D02*
X1096938Y69832D01*
X1096646Y69957D01*
X1096313Y69999D01*
X1095896Y69916D01*
X1095604Y69707D01*
X1095521Y69457D01*
X1095563Y69207D01*
X1095729Y68999D01*
X1096563Y68582D01*
X1096938Y68291D01*
X1097188Y67874D01*
X1097271Y67499D01*
X1095521D01*
G01X1094004Y67791D02*
X1093713Y67582D01*
X1093379Y67499D01*
X1093046Y67582D01*
X1092754Y67832D01*
X1092546Y68207D01*
X1092463Y68582D01*
Y69041D01*
X1092546Y69416D01*
X1092754Y69749D01*
X1093004Y69916D01*
X1093296Y69999D01*
X1093629Y69916D01*
X1093879Y69749D01*
X1094046Y69499D01*
X1094129Y69166D01*
X1094046Y68874D01*
X1093838Y68582D01*
X1093588Y68416D01*
X1093296Y68374D01*
X1092963Y68457D01*
X1092713Y68666D01*
X1092463Y69041D01*
G01X1090279Y67499D02*
X1090196Y68041D01*
X1090071Y68499D01*
X1089904Y68916D01*
X1089696Y69374D01*
X1089363Y69999D01*
X1091029D01*
G01X1087888Y68541D02*
X1087596Y68832D01*
X1087346Y68999D01*
X1087013Y69082D01*
X1086721Y68999D01*
X1086513Y68832D01*
X1086346Y68582D01*
X1086304Y68291D01*
X1086346Y68041D01*
X1086513Y67791D01*
X1086763Y67582D01*
X1087054Y67499D01*
X1087388Y67582D01*
X1087679Y67832D01*
X1087846Y68207D01*
X1087888Y68624D01*
X1087804Y69166D01*
X1087679Y69457D01*
X1087471Y69749D01*
X1087179Y69957D01*
X1086888Y69999D01*
X1086596Y69916D01*
X1086388Y69707D01*
G01X1100269Y71912D02*
Y74412D01*
X1099228D01*
X1098894Y74287D01*
X1098686Y74120D01*
X1098603Y73787D01*
X1098686Y73454D01*
X1098936Y73245D01*
X1099228Y73120D01*
X1100269D01*
G01X1099228D02*
X1098603Y71912D01*
G01X1097128Y73995D02*
X1096878Y74245D01*
X1096586Y74370D01*
X1096253Y74412D01*
X1095836Y74329D01*
X1095544Y74120D01*
X1095461Y73870D01*
X1095503Y73620D01*
X1095669Y73412D01*
X1096503Y72995D01*
X1096878Y72704D01*
X1097128Y72287D01*
X1097211Y71912D01*
X1095461D01*
G01X1093944Y72204D02*
X1093653Y71995D01*
X1093319Y71912D01*
X1092986Y71995D01*
X1092694Y72245D01*
X1092486Y72620D01*
X1092403Y72995D01*
Y73454D01*
X1092486Y73829D01*
X1092694Y74162D01*
X1092944Y74329D01*
X1093236Y74412D01*
X1093569Y74329D01*
X1093819Y74162D01*
X1093986Y73912D01*
X1094069Y73579D01*
X1093986Y73287D01*
X1093778Y72995D01*
X1093528Y72829D01*
X1093236Y72787D01*
X1092903Y72870D01*
X1092653Y73079D01*
X1092403Y73454D01*
G01X1090219Y71912D02*
X1090136Y72454D01*
X1090011Y72912D01*
X1089844Y73329D01*
X1089636Y73787D01*
X1089303Y74412D01*
X1090969D01*
G01X1087119Y71912D02*
X1087036Y72454D01*
X1086911Y72912D01*
X1086744Y73329D01*
X1086536Y73787D01*
X1086203Y74412D01*
X1087869D01*
G01X1100183Y63300D02*
Y65800D01*
X1099142D01*
X1098808Y65675D01*
X1098600Y65508D01*
X1098517Y65175D01*
X1098600Y64842D01*
X1098850Y64633D01*
X1099142Y64508D01*
X1100183D01*
G01X1099142D02*
X1098517Y63300D01*
G01X1096333D02*
X1096250Y63842D01*
X1096125Y64300D01*
X1095958Y64717D01*
X1095750Y65175D01*
X1095417Y65800D01*
X1097083D01*
G01X1093150Y63300D02*
Y65800D01*
X1093650Y65300D01*
G01Y63300D02*
X1092650D01*
G01X1090758Y63592D02*
X1090467Y63383D01*
X1090133Y63300D01*
X1089800Y63383D01*
X1089508Y63633D01*
X1089300Y64008D01*
X1089217Y64383D01*
Y64842D01*
X1089300Y65217D01*
X1089508Y65550D01*
X1089758Y65717D01*
X1090050Y65800D01*
X1090383Y65717D01*
X1090633Y65550D01*
X1090800Y65300D01*
X1090883Y64967D01*
X1090800Y64675D01*
X1090592Y64383D01*
X1090342Y64217D01*
X1090050Y64175D01*
X1089717Y64258D01*
X1089467Y64467D01*
X1089217Y64842D01*
G01X1091500Y50617D02*
X1094000D01*
Y51658D01*
X1093875Y51992D01*
X1093708Y52200D01*
X1093375Y52283D01*
X1093042Y52200D01*
X1092833Y51950D01*
X1092708Y51658D01*
Y50617D01*
G01Y51658D02*
X1091500Y52283D01*
G01Y54467D02*
X1092042Y54550D01*
X1092500Y54675D01*
X1092917Y54842D01*
X1093375Y55050D01*
X1094000Y55383D01*
Y53717D01*
G01X1093583Y56858D02*
X1093833Y57108D01*
X1093958Y57400D01*
X1094000Y57733D01*
X1093917Y58150D01*
X1093708Y58442D01*
X1093458Y58525D01*
X1093208Y58483D01*
X1093000Y58317D01*
X1092583Y57483D01*
X1092292Y57108D01*
X1091875Y56858D01*
X1091500Y56775D01*
Y58525D01*
G01X1093583Y59958D02*
X1093833Y60208D01*
X1093958Y60500D01*
X1094000Y60833D01*
X1093917Y61250D01*
X1093708Y61542D01*
X1093458Y61625D01*
X1093208Y61583D01*
X1093000Y61417D01*
X1092583Y60583D01*
X1092292Y60208D01*
X1091875Y59958D01*
X1091500Y59875D01*
Y61625D01*
G01X1100483Y75900D02*
Y78400D01*
X1099442D01*
X1099108Y78275D01*
X1098900Y78108D01*
X1098817Y77775D01*
X1098900Y77442D01*
X1099150Y77233D01*
X1099442Y77108D01*
X1100483D01*
G01X1099442D02*
X1098817Y75900D01*
G01X1096633D02*
X1096550Y76442D01*
X1096425Y76900D01*
X1096258Y77317D01*
X1096050Y77775D01*
X1095717Y78400D01*
X1097383D01*
G01X1094242Y77983D02*
X1093992Y78233D01*
X1093700Y78358D01*
X1093367Y78400D01*
X1092950Y78317D01*
X1092658Y78108D01*
X1092575Y77858D01*
X1092617Y77608D01*
X1092783Y77400D01*
X1093617Y76983D01*
X1093992Y76692D01*
X1094242Y76275D01*
X1094325Y75900D01*
X1092575D01*
G01X1090350D02*
X1090058Y75942D01*
X1089725Y76067D01*
X1089517Y76275D01*
X1089433Y76567D01*
X1089517Y76858D01*
X1089767Y77108D01*
X1090142Y77233D01*
X1090558D01*
X1090808Y77317D01*
X1091017Y77525D01*
X1091100Y77817D01*
X1090975Y78108D01*
X1090683Y78317D01*
X1090350Y78400D01*
X1090017Y78317D01*
X1089725Y78108D01*
X1089600Y77817D01*
X1089683Y77525D01*
X1089892Y77317D01*
X1090142Y77233D01*
X1090558D01*
X1090933Y77108D01*
X1091183Y76858D01*
X1091267Y76567D01*
X1091183Y76275D01*
X1090975Y76067D01*
X1090642Y75942D01*
X1090350Y75900D01*
G01X1101555Y162495D02*
X1101805Y162620D01*
X1102097Y162703D01*
X1102430D01*
X1102805Y162578D01*
X1103097Y162370D01*
X1103305Y162120D01*
X1103472Y161703D01*
X1103514Y161328D01*
X1103430Y160953D01*
X1103305Y160703D01*
X1103055Y160453D01*
X1102764Y160286D01*
X1102472Y160203D01*
X1102180D01*
X1101889Y160286D01*
X1101639Y160411D01*
X1101430Y160578D01*
G01X1100164Y161245D02*
X1099872Y161536D01*
X1099622Y161703D01*
X1099289Y161786D01*
X1098997Y161703D01*
X1098789Y161536D01*
X1098622Y161286D01*
X1098580Y160995D01*
X1098622Y160745D01*
X1098789Y160495D01*
X1099039Y160286D01*
X1099330Y160203D01*
X1099664Y160286D01*
X1099955Y160536D01*
X1100122Y160911D01*
X1100164Y161328D01*
X1100080Y161870D01*
X1099955Y162161D01*
X1099747Y162453D01*
X1099455Y162661D01*
X1099164Y162703D01*
X1098872Y162620D01*
X1098664Y162411D01*
G01X1096272Y160203D02*
Y162703D01*
X1096772Y162203D01*
G01Y160203D02*
X1095772D01*
G01X1093964Y161245D02*
X1093672Y161536D01*
X1093422Y161703D01*
X1093089Y161786D01*
X1092797Y161703D01*
X1092589Y161536D01*
X1092422Y161286D01*
X1092380Y160995D01*
X1092422Y160745D01*
X1092589Y160495D01*
X1092839Y160286D01*
X1093130Y160203D01*
X1093464Y160286D01*
X1093755Y160536D01*
X1093922Y160911D01*
X1093964Y161328D01*
X1093880Y161870D01*
X1093755Y162161D01*
X1093547Y162453D01*
X1093255Y162661D01*
X1092964Y162703D01*
X1092672Y162620D01*
X1092464Y162411D01*
G01X1115216Y162384D02*
X1115466Y162509D01*
X1115758Y162592D01*
X1116091D01*
X1116466Y162467D01*
X1116758Y162259D01*
X1116966Y162009D01*
X1117133Y161592D01*
X1117175Y161217D01*
X1117091Y160842D01*
X1116966Y160592D01*
X1116716Y160342D01*
X1116425Y160175D01*
X1116133Y160092D01*
X1115841D01*
X1115550Y160175D01*
X1115300Y160300D01*
X1115091Y160467D01*
G01X1113950D02*
X1113700Y160259D01*
X1113408Y160134D01*
X1113033Y160092D01*
X1112658Y160175D01*
X1112366Y160342D01*
X1112158Y160634D01*
X1112116Y160967D01*
X1112200Y161300D01*
X1112408Y161509D01*
X1112700Y161675D01*
X1112991Y161717D01*
X1113283Y161675D01*
X1113658Y161509D01*
X1113533Y162592D01*
X1112408D01*
G01X1109933Y160092D02*
X1109641Y160134D01*
X1109308Y160259D01*
X1109100Y160467D01*
X1109016Y160759D01*
X1109100Y161050D01*
X1109350Y161300D01*
X1109725Y161425D01*
X1110141D01*
X1110391Y161509D01*
X1110600Y161717D01*
X1110683Y162009D01*
X1110558Y162300D01*
X1110266Y162509D01*
X1109933Y162592D01*
X1109600Y162509D01*
X1109308Y162300D01*
X1109183Y162009D01*
X1109266Y161717D01*
X1109475Y161509D01*
X1109725Y161425D01*
X1110141D01*
X1110516Y161300D01*
X1110766Y161050D01*
X1110850Y160759D01*
X1110766Y160467D01*
X1110558Y160259D01*
X1110225Y160134D01*
X1109933Y160092D01*
G01X1107541Y160384D02*
X1107250Y160175D01*
X1106916Y160092D01*
X1106583Y160175D01*
X1106291Y160425D01*
X1106083Y160800D01*
X1106000Y161175D01*
Y161634D01*
X1106083Y162009D01*
X1106291Y162342D01*
X1106541Y162509D01*
X1106833Y162592D01*
X1107166Y162509D01*
X1107416Y162342D01*
X1107583Y162092D01*
X1107666Y161759D01*
X1107583Y161467D01*
X1107375Y161175D01*
X1107125Y161009D01*
X1106833Y160967D01*
X1106500Y161050D01*
X1106250Y161259D01*
X1106000Y161634D01*
G01X1135333Y17000D02*
X1139500Y7000D01*
X1143667Y17000D01*
G01X1142167Y13500D02*
X1136833D01*
G01X1176092Y122467D02*
X1176217Y122217D01*
X1176300Y121925D01*
Y121592D01*
X1176175Y121217D01*
X1175967Y120925D01*
X1175717Y120717D01*
X1175300Y120550D01*
X1174925Y120508D01*
X1174550Y120592D01*
X1174300Y120717D01*
X1174050Y120967D01*
X1173883Y121258D01*
X1173800Y121550D01*
Y121842D01*
X1173883Y122133D01*
X1174008Y122383D01*
X1174175Y122592D01*
G01X1173800Y124650D02*
X1176300D01*
X1175800Y124150D01*
G01X1173800D02*
Y125150D01*
G01X1174300Y126833D02*
X1174008Y127083D01*
X1173842Y127417D01*
X1173800Y127792D01*
X1173842Y128125D01*
X1174050Y128458D01*
X1174300Y128667D01*
X1174550Y128708D01*
X1174842Y128625D01*
X1175050Y128333D01*
X1175133Y128042D01*
Y127667D01*
G01Y128042D02*
X1175258Y128292D01*
X1175467Y128500D01*
X1175717Y128583D01*
X1175967Y128500D01*
X1176175Y128292D01*
X1176300Y127917D01*
X1176258Y127542D01*
X1176092Y127167D01*
G01X1173800Y130850D02*
X1176300D01*
X1175800Y130350D01*
G01X1173800D02*
Y131350D01*
G01X1171392Y123667D02*
X1171517Y123417D01*
X1171600Y123125D01*
Y122792D01*
X1171475Y122417D01*
X1171267Y122125D01*
X1171017Y121917D01*
X1170600Y121750D01*
X1170225Y121708D01*
X1169850Y121792D01*
X1169600Y121917D01*
X1169350Y122167D01*
X1169183Y122458D01*
X1169100Y122750D01*
Y123042D01*
X1169183Y123333D01*
X1169308Y123583D01*
X1169475Y123792D01*
G01X1171183Y125058D02*
X1171433Y125308D01*
X1171558Y125600D01*
X1171600Y125933D01*
X1171517Y126350D01*
X1171308Y126642D01*
X1171058Y126725D01*
X1170808Y126683D01*
X1170600Y126517D01*
X1170183Y125683D01*
X1169892Y125308D01*
X1169475Y125058D01*
X1169100Y124975D01*
Y126725D01*
G01X1169475Y128033D02*
X1169267Y128283D01*
X1169142Y128575D01*
X1169100Y128950D01*
X1169183Y129325D01*
X1169350Y129617D01*
X1169642Y129825D01*
X1169975Y129867D01*
X1170308Y129783D01*
X1170517Y129575D01*
X1170683Y129283D01*
X1170725Y128992D01*
X1170683Y128700D01*
X1170517Y128325D01*
X1171600Y128450D01*
Y129575D01*
G01X1170142Y131258D02*
X1170433Y131550D01*
X1170600Y131800D01*
X1170683Y132133D01*
X1170600Y132425D01*
X1170433Y132633D01*
X1170183Y132800D01*
X1169892Y132842D01*
X1169642Y132800D01*
X1169392Y132633D01*
X1169183Y132383D01*
X1169100Y132092D01*
X1169183Y131758D01*
X1169433Y131467D01*
X1169808Y131300D01*
X1170225Y131258D01*
X1170767Y131342D01*
X1171058Y131467D01*
X1171350Y131675D01*
X1171558Y131967D01*
X1171600Y132258D01*
X1171517Y132550D01*
X1171308Y132758D01*
G01X1167492Y123367D02*
X1167617Y123117D01*
X1167700Y122825D01*
Y122492D01*
X1167575Y122117D01*
X1167367Y121825D01*
X1167117Y121617D01*
X1166700Y121450D01*
X1166325Y121408D01*
X1165950Y121492D01*
X1165700Y121617D01*
X1165450Y121867D01*
X1165283Y122158D01*
X1165200Y122450D01*
Y122742D01*
X1165283Y123033D01*
X1165408Y123283D01*
X1165575Y123492D01*
G01X1167283Y124758D02*
X1167533Y125008D01*
X1167658Y125300D01*
X1167700Y125633D01*
X1167617Y126050D01*
X1167408Y126342D01*
X1167158Y126425D01*
X1166908Y126383D01*
X1166700Y126217D01*
X1166283Y125383D01*
X1165992Y125008D01*
X1165575Y124758D01*
X1165200Y124675D01*
Y126425D01*
G01X1165575Y127733D02*
X1165367Y127983D01*
X1165242Y128275D01*
X1165200Y128650D01*
X1165283Y129025D01*
X1165450Y129317D01*
X1165742Y129525D01*
X1166075Y129567D01*
X1166408Y129483D01*
X1166617Y129275D01*
X1166783Y128983D01*
X1166825Y128692D01*
X1166783Y128400D01*
X1166617Y128025D01*
X1167700Y128150D01*
Y129275D01*
G01X1165200Y131667D02*
X1165742Y131750D01*
X1166200Y131875D01*
X1166617Y132042D01*
X1167075Y132250D01*
X1167700Y132583D01*
Y130917D01*
G01X1179792Y122167D02*
X1179917Y121917D01*
X1180000Y121625D01*
Y121292D01*
X1179875Y120917D01*
X1179667Y120625D01*
X1179417Y120417D01*
X1179000Y120250D01*
X1178625Y120208D01*
X1178250Y120292D01*
X1178000Y120417D01*
X1177750Y120667D01*
X1177583Y120958D01*
X1177500Y121250D01*
Y121542D01*
X1177583Y121833D01*
X1177708Y122083D01*
X1177875Y122292D01*
G01X1179583Y123558D02*
X1179833Y123808D01*
X1179958Y124100D01*
X1180000Y124433D01*
X1179917Y124850D01*
X1179708Y125142D01*
X1179458Y125225D01*
X1179208Y125183D01*
X1179000Y125017D01*
X1178583Y124183D01*
X1178292Y123808D01*
X1177875Y123558D01*
X1177500Y123475D01*
Y125225D01*
G01Y127367D02*
X1178042Y127450D01*
X1178500Y127575D01*
X1178917Y127742D01*
X1179375Y127950D01*
X1180000Y128283D01*
Y126617D01*
G01X1177500Y130467D02*
X1178042Y130550D01*
X1178500Y130675D01*
X1178917Y130842D01*
X1179375Y131050D01*
X1180000Y131383D01*
Y129717D01*
G01X1157531Y824600D02*
X1157781Y824725D01*
X1158073Y824808D01*
X1158406D01*
X1158781Y824683D01*
X1159073Y824475D01*
X1159281Y824225D01*
X1159448Y823808D01*
X1159490Y823433D01*
X1159406Y823058D01*
X1159281Y822808D01*
X1159031Y822558D01*
X1158740Y822391D01*
X1158448Y822308D01*
X1158156D01*
X1157865Y822391D01*
X1157615Y822516D01*
X1157406Y822683D01*
G01X1154848Y822308D02*
Y824808D01*
X1156390Y823016D01*
X1154306D01*
G01X1152248Y822308D02*
Y824808D01*
X1152748Y824308D01*
G01Y822308D02*
X1151748D01*
G01X1150065Y822683D02*
X1149815Y822475D01*
X1149523Y822350D01*
X1149148Y822308D01*
X1148773Y822391D01*
X1148481Y822558D01*
X1148273Y822850D01*
X1148231Y823183D01*
X1148315Y823516D01*
X1148523Y823725D01*
X1148815Y823891D01*
X1149106Y823933D01*
X1149398Y823891D01*
X1149773Y823725D01*
X1149648Y824808D01*
X1148523D01*
G01X1146840Y824391D02*
X1146590Y824641D01*
X1146298Y824766D01*
X1145965Y824808D01*
X1145548Y824725D01*
X1145256Y824516D01*
X1145173Y824266D01*
X1145215Y824016D01*
X1145381Y823808D01*
X1146215Y823391D01*
X1146590Y823100D01*
X1146840Y822683D01*
X1146923Y822308D01*
X1145173D01*
G01X1184833Y11667D02*
X1185500Y11167D01*
X1186000Y10334D01*
X1186333Y9167D01*
X1186000Y8167D01*
X1185333Y7500D01*
X1184167Y7000D01*
X1179667D01*
Y17000D01*
X1185167D01*
X1186333Y16333D01*
X1187000Y15333D01*
X1187333Y14167D01*
X1187000Y13000D01*
X1186000Y12000D01*
X1184833Y11667D01*
X1179667D01*
G01X1207201Y143421D02*
X1207326Y143171D01*
X1207409Y142879D01*
Y142546D01*
X1207284Y142171D01*
X1207076Y141879D01*
X1206826Y141671D01*
X1206409Y141504D01*
X1206034Y141462D01*
X1205659Y141546D01*
X1205409Y141671D01*
X1205159Y141921D01*
X1204992Y142212D01*
X1204909Y142504D01*
Y142796D01*
X1204992Y143087D01*
X1205117Y143337D01*
X1205284Y143546D01*
G01X1204909Y145604D02*
X1207409D01*
X1206909Y145104D01*
G01X1204909D02*
Y146104D01*
G01X1205409Y147787D02*
X1205117Y148037D01*
X1204951Y148371D01*
X1204909Y148746D01*
X1204951Y149079D01*
X1205159Y149412D01*
X1205409Y149621D01*
X1205659Y149662D01*
X1205951Y149579D01*
X1206159Y149287D01*
X1206242Y148996D01*
Y148621D01*
G01Y148996D02*
X1206367Y149246D01*
X1206576Y149454D01*
X1206826Y149537D01*
X1207076Y149454D01*
X1207284Y149246D01*
X1207409Y148871D01*
X1207367Y148496D01*
X1207201Y148121D01*
G01X1204909Y152304D02*
X1207409D01*
X1205617Y150762D01*
Y152846D01*
G01X1211201Y143421D02*
X1211326Y143171D01*
X1211409Y142879D01*
Y142546D01*
X1211284Y142171D01*
X1211076Y141879D01*
X1210826Y141671D01*
X1210409Y141504D01*
X1210034Y141462D01*
X1209659Y141546D01*
X1209409Y141671D01*
X1209159Y141921D01*
X1208992Y142212D01*
X1208909Y142504D01*
Y142796D01*
X1208992Y143087D01*
X1209117Y143337D01*
X1209284Y143546D01*
G01X1210992Y144812D02*
X1211242Y145062D01*
X1211367Y145354D01*
X1211409Y145687D01*
X1211326Y146104D01*
X1211117Y146396D01*
X1210867Y146479D01*
X1210617Y146437D01*
X1210409Y146271D01*
X1209992Y145437D01*
X1209701Y145062D01*
X1209284Y144812D01*
X1208909Y144729D01*
Y146479D01*
G01X1209409Y147787D02*
X1209117Y148037D01*
X1208951Y148371D01*
X1208909Y148746D01*
X1208951Y149079D01*
X1209159Y149412D01*
X1209409Y149621D01*
X1209659Y149662D01*
X1209951Y149579D01*
X1210159Y149287D01*
X1210242Y148996D01*
Y148621D01*
G01Y148996D02*
X1210367Y149246D01*
X1210576Y149454D01*
X1210826Y149537D01*
X1211076Y149454D01*
X1211284Y149246D01*
X1211409Y148871D01*
X1211367Y148496D01*
X1211201Y148121D01*
G01X1211409Y151804D02*
X1211326Y151471D01*
X1211117Y151221D01*
X1210867Y151054D01*
X1210534Y150929D01*
X1210159Y150887D01*
X1209784Y150929D01*
X1209451Y151054D01*
X1209201Y151221D01*
X1208992Y151471D01*
X1208909Y151804D01*
X1208992Y152137D01*
X1209201Y152387D01*
X1209451Y152554D01*
X1209784Y152679D01*
X1210159Y152721D01*
X1210534Y152679D01*
X1210867Y152554D01*
X1211117Y152387D01*
X1211326Y152137D01*
X1211409Y151804D01*
G01X1227667Y7833D02*
X1226667Y7333D01*
X1225500Y7000D01*
X1224167D01*
X1222666Y7500D01*
X1221500Y8333D01*
X1220667Y9333D01*
X1220000Y11000D01*
X1219833Y12500D01*
X1220167Y14000D01*
X1220667Y15000D01*
X1221667Y16000D01*
X1222833Y16667D01*
X1224000Y17000D01*
X1225167D01*
X1226333Y16667D01*
X1227333Y16167D01*
X1228167Y15500D01*
G01X1240391Y155238D02*
X1240516Y154988D01*
X1240599Y154696D01*
Y154363D01*
X1240474Y153988D01*
X1240266Y153696D01*
X1240016Y153488D01*
X1239599Y153321D01*
X1239224Y153279D01*
X1238849Y153363D01*
X1238599Y153488D01*
X1238349Y153738D01*
X1238182Y154029D01*
X1238099Y154321D01*
Y154613D01*
X1238182Y154904D01*
X1238307Y155154D01*
X1238474Y155363D01*
G01X1240182Y156629D02*
X1240432Y156879D01*
X1240557Y157171D01*
X1240599Y157504D01*
X1240516Y157921D01*
X1240307Y158213D01*
X1240057Y158296D01*
X1239807Y158254D01*
X1239599Y158088D01*
X1239182Y157254D01*
X1238891Y156879D01*
X1238474Y156629D01*
X1238099Y156546D01*
Y158296D01*
G01X1238599Y159604D02*
X1238307Y159854D01*
X1238141Y160188D01*
X1238099Y160563D01*
X1238141Y160896D01*
X1238349Y161229D01*
X1238599Y161438D01*
X1238849Y161479D01*
X1239141Y161396D01*
X1239349Y161104D01*
X1239432Y160813D01*
Y160438D01*
G01Y160813D02*
X1239557Y161063D01*
X1239766Y161271D01*
X1240016Y161354D01*
X1240266Y161271D01*
X1240474Y161063D01*
X1240599Y160688D01*
X1240557Y160313D01*
X1240391Y159938D01*
G01X1238099Y163621D02*
X1240599D01*
X1240099Y163121D01*
G01X1238099D02*
Y164121D01*
G01X1236391Y155238D02*
X1236516Y154988D01*
X1236599Y154696D01*
Y154363D01*
X1236474Y153988D01*
X1236266Y153696D01*
X1236016Y153488D01*
X1235599Y153321D01*
X1235224Y153279D01*
X1234849Y153363D01*
X1234599Y153488D01*
X1234349Y153738D01*
X1234182Y154029D01*
X1234099Y154321D01*
Y154613D01*
X1234182Y154904D01*
X1234307Y155154D01*
X1234474Y155363D01*
G01X1236182Y156629D02*
X1236432Y156879D01*
X1236557Y157171D01*
X1236599Y157504D01*
X1236516Y157921D01*
X1236307Y158213D01*
X1236057Y158296D01*
X1235807Y158254D01*
X1235599Y158088D01*
X1235182Y157254D01*
X1234891Y156879D01*
X1234474Y156629D01*
X1234099Y156546D01*
Y158296D01*
G01Y160438D02*
X1234641Y160521D01*
X1235099Y160646D01*
X1235516Y160813D01*
X1235974Y161021D01*
X1236599Y161354D01*
Y159688D01*
G01X1234099Y163621D02*
X1234141Y163913D01*
X1234266Y164246D01*
X1234474Y164454D01*
X1234766Y164538D01*
X1235057Y164454D01*
X1235307Y164204D01*
X1235432Y163829D01*
Y163413D01*
X1235516Y163163D01*
X1235724Y162954D01*
X1236016Y162871D01*
X1236307Y162996D01*
X1236516Y163288D01*
X1236599Y163621D01*
X1236516Y163954D01*
X1236307Y164246D01*
X1236016Y164371D01*
X1235724Y164288D01*
X1235516Y164079D01*
X1235432Y163829D01*
Y163413D01*
X1235307Y163038D01*
X1235057Y162788D01*
X1234766Y162704D01*
X1234474Y162788D01*
X1234266Y162996D01*
X1234141Y163329D01*
X1234099Y163621D01*
G01X1223355Y273171D02*
Y275671D01*
X1222355D01*
X1222022Y275546D01*
X1221772Y275254D01*
X1221689Y274921D01*
X1221772Y274588D01*
X1221980Y274338D01*
X1222355Y274213D01*
X1223355D01*
G01X1219172Y274421D02*
X1218339D01*
Y273671D01*
X1218589Y273421D01*
X1218880Y273254D01*
X1219297Y273171D01*
X1219714Y273254D01*
X1220005Y273421D01*
X1220255Y273671D01*
X1220422Y273963D01*
X1220505Y274296D01*
Y274588D01*
X1220422Y274838D01*
X1220255Y275129D01*
X1220005Y275379D01*
X1219755Y275546D01*
X1219422Y275671D01*
X1219130D01*
X1218797Y275588D01*
X1218547Y275421D01*
G01X1217114Y274213D02*
X1216822Y274504D01*
X1216572Y274671D01*
X1216239Y274754D01*
X1215947Y274671D01*
X1215739Y274504D01*
X1215572Y274254D01*
X1215530Y273963D01*
X1215572Y273713D01*
X1215739Y273463D01*
X1215989Y273254D01*
X1216280Y273171D01*
X1216614Y273254D01*
X1216905Y273504D01*
X1217072Y273879D01*
X1217114Y274296D01*
X1217030Y274838D01*
X1216905Y275129D01*
X1216697Y275421D01*
X1216405Y275629D01*
X1216114Y275671D01*
X1215822Y275588D01*
X1215614Y275379D01*
G01X1213222Y273171D02*
Y275671D01*
X1213722Y275171D01*
G01Y273171D02*
X1212722D01*
G01X1223355Y277171D02*
Y279671D01*
X1222355D01*
X1222022Y279546D01*
X1221772Y279254D01*
X1221689Y278921D01*
X1221772Y278588D01*
X1221980Y278338D01*
X1222355Y278213D01*
X1223355D01*
G01X1219172Y278421D02*
X1218339D01*
Y277671D01*
X1218589Y277421D01*
X1218880Y277254D01*
X1219297Y277171D01*
X1219714Y277254D01*
X1220005Y277421D01*
X1220255Y277671D01*
X1220422Y277963D01*
X1220505Y278296D01*
Y278588D01*
X1220422Y278838D01*
X1220255Y279129D01*
X1220005Y279379D01*
X1219755Y279546D01*
X1219422Y279671D01*
X1219130D01*
X1218797Y279588D01*
X1218547Y279421D01*
G01X1217239Y277671D02*
X1216989Y277379D01*
X1216655Y277213D01*
X1216280Y277171D01*
X1215947Y277213D01*
X1215614Y277421D01*
X1215405Y277671D01*
X1215364Y277921D01*
X1215447Y278213D01*
X1215739Y278421D01*
X1216030Y278504D01*
X1216405D01*
G01X1216030D02*
X1215780Y278629D01*
X1215572Y278838D01*
X1215489Y279088D01*
X1215572Y279338D01*
X1215780Y279546D01*
X1216155Y279671D01*
X1216530Y279629D01*
X1216905Y279463D01*
G01X1213222Y277171D02*
X1212930Y277213D01*
X1212597Y277338D01*
X1212389Y277546D01*
X1212305Y277838D01*
X1212389Y278129D01*
X1212639Y278379D01*
X1213014Y278504D01*
X1213430D01*
X1213680Y278588D01*
X1213889Y278796D01*
X1213972Y279088D01*
X1213847Y279379D01*
X1213555Y279588D01*
X1213222Y279671D01*
X1212889Y279588D01*
X1212597Y279379D01*
X1212472Y279088D01*
X1212555Y278796D01*
X1212764Y278588D01*
X1213014Y278504D01*
X1213430D01*
X1213805Y278379D01*
X1214055Y278129D01*
X1214139Y277838D01*
X1214055Y277546D01*
X1213847Y277338D01*
X1213514Y277213D01*
X1213222Y277171D01*
G01X1223355Y297171D02*
Y299671D01*
X1222355D01*
X1222022Y299546D01*
X1221772Y299254D01*
X1221689Y298921D01*
X1221772Y298588D01*
X1221980Y298338D01*
X1222355Y298213D01*
X1223355D01*
G01X1219172Y298421D02*
X1218339D01*
Y297671D01*
X1218589Y297421D01*
X1218880Y297254D01*
X1219297Y297171D01*
X1219714Y297254D01*
X1220005Y297421D01*
X1220255Y297671D01*
X1220422Y297963D01*
X1220505Y298296D01*
Y298588D01*
X1220422Y298838D01*
X1220255Y299129D01*
X1220005Y299379D01*
X1219755Y299546D01*
X1219422Y299671D01*
X1219130D01*
X1218797Y299588D01*
X1218547Y299421D01*
G01X1217114Y298213D02*
X1216822Y298504D01*
X1216572Y298671D01*
X1216239Y298754D01*
X1215947Y298671D01*
X1215739Y298504D01*
X1215572Y298254D01*
X1215530Y297963D01*
X1215572Y297713D01*
X1215739Y297463D01*
X1215989Y297254D01*
X1216280Y297171D01*
X1216614Y297254D01*
X1216905Y297504D01*
X1217072Y297879D01*
X1217114Y298296D01*
X1217030Y298838D01*
X1216905Y299129D01*
X1216697Y299421D01*
X1216405Y299629D01*
X1216114Y299671D01*
X1215822Y299588D01*
X1215614Y299379D01*
G01X1214139Y297671D02*
X1213889Y297379D01*
X1213555Y297213D01*
X1213180Y297171D01*
X1212847Y297213D01*
X1212514Y297421D01*
X1212305Y297671D01*
X1212264Y297921D01*
X1212347Y298213D01*
X1212639Y298421D01*
X1212930Y298504D01*
X1213305D01*
G01X1212930D02*
X1212680Y298629D01*
X1212472Y298838D01*
X1212389Y299088D01*
X1212472Y299338D01*
X1212680Y299546D01*
X1213055Y299671D01*
X1213430Y299629D01*
X1213805Y299463D01*
G01X1223355Y301171D02*
Y303671D01*
X1222355D01*
X1222022Y303546D01*
X1221772Y303254D01*
X1221689Y302921D01*
X1221772Y302588D01*
X1221980Y302338D01*
X1222355Y302213D01*
X1223355D01*
G01X1219172Y302421D02*
X1218339D01*
Y301671D01*
X1218589Y301421D01*
X1218880Y301254D01*
X1219297Y301171D01*
X1219714Y301254D01*
X1220005Y301421D01*
X1220255Y301671D01*
X1220422Y301963D01*
X1220505Y302296D01*
Y302588D01*
X1220422Y302838D01*
X1220255Y303129D01*
X1220005Y303379D01*
X1219755Y303546D01*
X1219422Y303671D01*
X1219130D01*
X1218797Y303588D01*
X1218547Y303421D01*
G01X1217114Y302213D02*
X1216822Y302504D01*
X1216572Y302671D01*
X1216239Y302754D01*
X1215947Y302671D01*
X1215739Y302504D01*
X1215572Y302254D01*
X1215530Y301963D01*
X1215572Y301713D01*
X1215739Y301463D01*
X1215989Y301254D01*
X1216280Y301171D01*
X1216614Y301254D01*
X1216905Y301504D01*
X1217072Y301879D01*
X1217114Y302296D01*
X1217030Y302838D01*
X1216905Y303129D01*
X1216697Y303421D01*
X1216405Y303629D01*
X1216114Y303671D01*
X1215822Y303588D01*
X1215614Y303379D01*
G01X1214014Y303254D02*
X1213764Y303504D01*
X1213472Y303629D01*
X1213139Y303671D01*
X1212722Y303588D01*
X1212430Y303379D01*
X1212347Y303129D01*
X1212389Y302879D01*
X1212555Y302671D01*
X1213389Y302254D01*
X1213764Y301963D01*
X1214014Y301546D01*
X1214097Y301171D01*
X1212347D01*
G01X1223355Y293171D02*
Y295671D01*
X1222355D01*
X1222022Y295546D01*
X1221772Y295254D01*
X1221689Y294921D01*
X1221772Y294588D01*
X1221980Y294338D01*
X1222355Y294213D01*
X1223355D01*
G01X1219172Y294421D02*
X1218339D01*
Y293671D01*
X1218589Y293421D01*
X1218880Y293254D01*
X1219297Y293171D01*
X1219714Y293254D01*
X1220005Y293421D01*
X1220255Y293671D01*
X1220422Y293963D01*
X1220505Y294296D01*
Y294588D01*
X1220422Y294838D01*
X1220255Y295129D01*
X1220005Y295379D01*
X1219755Y295546D01*
X1219422Y295671D01*
X1219130D01*
X1218797Y295588D01*
X1218547Y295421D01*
G01X1217239Y293546D02*
X1216989Y293338D01*
X1216697Y293213D01*
X1216322Y293171D01*
X1215947Y293254D01*
X1215655Y293421D01*
X1215447Y293713D01*
X1215405Y294046D01*
X1215489Y294379D01*
X1215697Y294588D01*
X1215989Y294754D01*
X1216280Y294796D01*
X1216572Y294754D01*
X1216947Y294588D01*
X1216822Y295671D01*
X1215697D01*
G01X1213222Y293171D02*
X1212930Y293213D01*
X1212597Y293338D01*
X1212389Y293546D01*
X1212305Y293838D01*
X1212389Y294129D01*
X1212639Y294379D01*
X1213014Y294504D01*
X1213430D01*
X1213680Y294588D01*
X1213889Y294796D01*
X1213972Y295088D01*
X1213847Y295379D01*
X1213555Y295588D01*
X1213222Y295671D01*
X1212889Y295588D01*
X1212597Y295379D01*
X1212472Y295088D01*
X1212555Y294796D01*
X1212764Y294588D01*
X1213014Y294504D01*
X1213430D01*
X1213805Y294379D01*
X1214055Y294129D01*
X1214139Y293838D01*
X1214055Y293546D01*
X1213847Y293338D01*
X1213514Y293213D01*
X1213222Y293171D01*
G01X1223355Y305171D02*
Y307671D01*
X1222355D01*
X1222022Y307546D01*
X1221772Y307254D01*
X1221689Y306921D01*
X1221772Y306588D01*
X1221980Y306338D01*
X1222355Y306213D01*
X1223355D01*
G01X1219172Y306421D02*
X1218339D01*
Y305671D01*
X1218589Y305421D01*
X1218880Y305254D01*
X1219297Y305171D01*
X1219714Y305254D01*
X1220005Y305421D01*
X1220255Y305671D01*
X1220422Y305963D01*
X1220505Y306296D01*
Y306588D01*
X1220422Y306838D01*
X1220255Y307129D01*
X1220005Y307379D01*
X1219755Y307546D01*
X1219422Y307671D01*
X1219130D01*
X1218797Y307588D01*
X1218547Y307421D01*
G01X1217239Y305546D02*
X1216989Y305338D01*
X1216697Y305213D01*
X1216322Y305171D01*
X1215947Y305254D01*
X1215655Y305421D01*
X1215447Y305713D01*
X1215405Y306046D01*
X1215489Y306379D01*
X1215697Y306588D01*
X1215989Y306754D01*
X1216280Y306796D01*
X1216572Y306754D01*
X1216947Y306588D01*
X1216822Y307671D01*
X1215697D01*
G01X1212722Y305171D02*
Y307671D01*
X1214264Y305879D01*
X1212180D01*
G01X1223355Y309171D02*
Y311671D01*
X1222355D01*
X1222022Y311546D01*
X1221772Y311254D01*
X1221689Y310921D01*
X1221772Y310588D01*
X1221980Y310338D01*
X1222355Y310213D01*
X1223355D01*
G01X1219172Y310421D02*
X1218339D01*
Y309671D01*
X1218589Y309421D01*
X1218880Y309254D01*
X1219297Y309171D01*
X1219714Y309254D01*
X1220005Y309421D01*
X1220255Y309671D01*
X1220422Y309963D01*
X1220505Y310296D01*
Y310588D01*
X1220422Y310838D01*
X1220255Y311129D01*
X1220005Y311379D01*
X1219755Y311546D01*
X1219422Y311671D01*
X1219130D01*
X1218797Y311588D01*
X1218547Y311421D01*
G01X1217239Y309546D02*
X1216989Y309338D01*
X1216697Y309213D01*
X1216322Y309171D01*
X1215947Y309254D01*
X1215655Y309421D01*
X1215447Y309713D01*
X1215405Y310046D01*
X1215489Y310379D01*
X1215697Y310588D01*
X1215989Y310754D01*
X1216280Y310796D01*
X1216572Y310754D01*
X1216947Y310588D01*
X1216822Y311671D01*
X1215697D01*
G01X1214139Y309671D02*
X1213889Y309379D01*
X1213555Y309213D01*
X1213180Y309171D01*
X1212847Y309213D01*
X1212514Y309421D01*
X1212305Y309671D01*
X1212264Y309921D01*
X1212347Y310213D01*
X1212639Y310421D01*
X1212930Y310504D01*
X1213305D01*
G01X1212930D02*
X1212680Y310629D01*
X1212472Y310838D01*
X1212389Y311088D01*
X1212472Y311338D01*
X1212680Y311546D01*
X1213055Y311671D01*
X1213430Y311629D01*
X1213805Y311463D01*
G01X1223355Y289171D02*
Y291671D01*
X1222355D01*
X1222022Y291546D01*
X1221772Y291254D01*
X1221689Y290921D01*
X1221772Y290588D01*
X1221980Y290338D01*
X1222355Y290213D01*
X1223355D01*
G01X1219172Y290421D02*
X1218339D01*
Y289671D01*
X1218589Y289421D01*
X1218880Y289254D01*
X1219297Y289171D01*
X1219714Y289254D01*
X1220005Y289421D01*
X1220255Y289671D01*
X1220422Y289963D01*
X1220505Y290296D01*
Y290588D01*
X1220422Y290838D01*
X1220255Y291129D01*
X1220005Y291379D01*
X1219755Y291546D01*
X1219422Y291671D01*
X1219130D01*
X1218797Y291588D01*
X1218547Y291421D01*
G01X1215822Y289171D02*
Y291671D01*
X1217364Y289879D01*
X1215280D01*
G01X1213222Y289171D02*
Y291671D01*
X1213722Y291171D01*
G01Y289171D02*
X1212722D01*
G01X1223355Y285171D02*
Y287671D01*
X1222355D01*
X1222022Y287546D01*
X1221772Y287254D01*
X1221689Y286921D01*
X1221772Y286588D01*
X1221980Y286338D01*
X1222355Y286213D01*
X1223355D01*
G01X1219172Y286421D02*
X1218339D01*
Y285671D01*
X1218589Y285421D01*
X1218880Y285254D01*
X1219297Y285171D01*
X1219714Y285254D01*
X1220005Y285421D01*
X1220255Y285671D01*
X1220422Y285963D01*
X1220505Y286296D01*
Y286588D01*
X1220422Y286838D01*
X1220255Y287129D01*
X1220005Y287379D01*
X1219755Y287546D01*
X1219422Y287671D01*
X1219130D01*
X1218797Y287588D01*
X1218547Y287421D01*
G01X1215822Y285171D02*
Y287671D01*
X1217364Y285879D01*
X1215280D01*
G01X1213222Y287671D02*
X1213555Y287588D01*
X1213805Y287379D01*
X1213972Y287129D01*
X1214097Y286796D01*
X1214139Y286421D01*
X1214097Y286046D01*
X1213972Y285713D01*
X1213805Y285463D01*
X1213555Y285254D01*
X1213222Y285171D01*
X1212889Y285254D01*
X1212639Y285463D01*
X1212472Y285713D01*
X1212347Y286046D01*
X1212305Y286421D01*
X1212347Y286796D01*
X1212472Y287129D01*
X1212639Y287379D01*
X1212889Y287588D01*
X1213222Y287671D01*
G01X1223355Y281171D02*
Y283671D01*
X1222355D01*
X1222022Y283546D01*
X1221772Y283254D01*
X1221689Y282921D01*
X1221772Y282588D01*
X1221980Y282338D01*
X1222355Y282213D01*
X1223355D01*
G01X1219172Y282421D02*
X1218339D01*
Y281671D01*
X1218589Y281421D01*
X1218880Y281254D01*
X1219297Y281171D01*
X1219714Y281254D01*
X1220005Y281421D01*
X1220255Y281671D01*
X1220422Y281963D01*
X1220505Y282296D01*
Y282588D01*
X1220422Y282838D01*
X1220255Y283129D01*
X1220005Y283379D01*
X1219755Y283546D01*
X1219422Y283671D01*
X1219130D01*
X1218797Y283588D01*
X1218547Y283421D01*
G01X1217239Y281671D02*
X1216989Y281379D01*
X1216655Y281213D01*
X1216280Y281171D01*
X1215947Y281213D01*
X1215614Y281421D01*
X1215405Y281671D01*
X1215364Y281921D01*
X1215447Y282213D01*
X1215739Y282421D01*
X1216030Y282504D01*
X1216405D01*
G01X1216030D02*
X1215780Y282629D01*
X1215572Y282838D01*
X1215489Y283088D01*
X1215572Y283338D01*
X1215780Y283546D01*
X1216155Y283671D01*
X1216530Y283629D01*
X1216905Y283463D01*
G01X1213930Y281463D02*
X1213639Y281254D01*
X1213305Y281171D01*
X1212972Y281254D01*
X1212680Y281504D01*
X1212472Y281879D01*
X1212389Y282254D01*
Y282713D01*
X1212472Y283088D01*
X1212680Y283421D01*
X1212930Y283588D01*
X1213222Y283671D01*
X1213555Y283588D01*
X1213805Y283421D01*
X1213972Y283171D01*
X1214055Y282838D01*
X1213972Y282546D01*
X1213764Y282254D01*
X1213514Y282088D01*
X1213222Y282046D01*
X1212889Y282129D01*
X1212639Y282338D01*
X1212389Y282713D01*
G01X1223355Y325171D02*
Y327671D01*
X1222355D01*
X1222022Y327546D01*
X1221772Y327254D01*
X1221689Y326921D01*
X1221772Y326588D01*
X1221980Y326338D01*
X1222355Y326213D01*
X1223355D01*
G01X1219172Y326421D02*
X1218339D01*
Y325671D01*
X1218589Y325421D01*
X1218880Y325254D01*
X1219297Y325171D01*
X1219714Y325254D01*
X1220005Y325421D01*
X1220255Y325671D01*
X1220422Y325963D01*
X1220505Y326296D01*
Y326588D01*
X1220422Y326838D01*
X1220255Y327129D01*
X1220005Y327379D01*
X1219755Y327546D01*
X1219422Y327671D01*
X1219130D01*
X1218797Y327588D01*
X1218547Y327421D01*
G01X1217114Y326213D02*
X1216822Y326504D01*
X1216572Y326671D01*
X1216239Y326754D01*
X1215947Y326671D01*
X1215739Y326504D01*
X1215572Y326254D01*
X1215530Y325963D01*
X1215572Y325713D01*
X1215739Y325463D01*
X1215989Y325254D01*
X1216280Y325171D01*
X1216614Y325254D01*
X1216905Y325504D01*
X1217072Y325879D01*
X1217114Y326296D01*
X1217030Y326838D01*
X1216905Y327129D01*
X1216697Y327421D01*
X1216405Y327629D01*
X1216114Y327671D01*
X1215822Y327588D01*
X1215614Y327379D01*
G01X1213305Y325171D02*
X1213222Y325713D01*
X1213097Y326171D01*
X1212930Y326588D01*
X1212722Y327046D01*
X1212389Y327671D01*
X1214055D01*
G01X1223355Y321171D02*
Y323671D01*
X1222355D01*
X1222022Y323546D01*
X1221772Y323254D01*
X1221689Y322921D01*
X1221772Y322588D01*
X1221980Y322338D01*
X1222355Y322213D01*
X1223355D01*
G01X1219172Y322421D02*
X1218339D01*
Y321671D01*
X1218589Y321421D01*
X1218880Y321254D01*
X1219297Y321171D01*
X1219714Y321254D01*
X1220005Y321421D01*
X1220255Y321671D01*
X1220422Y321963D01*
X1220505Y322296D01*
Y322588D01*
X1220422Y322838D01*
X1220255Y323129D01*
X1220005Y323379D01*
X1219755Y323546D01*
X1219422Y323671D01*
X1219130D01*
X1218797Y323588D01*
X1218547Y323421D01*
G01X1217114Y322213D02*
X1216822Y322504D01*
X1216572Y322671D01*
X1216239Y322754D01*
X1215947Y322671D01*
X1215739Y322504D01*
X1215572Y322254D01*
X1215530Y321963D01*
X1215572Y321713D01*
X1215739Y321463D01*
X1215989Y321254D01*
X1216280Y321171D01*
X1216614Y321254D01*
X1216905Y321504D01*
X1217072Y321879D01*
X1217114Y322296D01*
X1217030Y322838D01*
X1216905Y323129D01*
X1216697Y323421D01*
X1216405Y323629D01*
X1216114Y323671D01*
X1215822Y323588D01*
X1215614Y323379D01*
G01X1214014Y322213D02*
X1213722Y322504D01*
X1213472Y322671D01*
X1213139Y322754D01*
X1212847Y322671D01*
X1212639Y322504D01*
X1212472Y322254D01*
X1212430Y321963D01*
X1212472Y321713D01*
X1212639Y321463D01*
X1212889Y321254D01*
X1213180Y321171D01*
X1213514Y321254D01*
X1213805Y321504D01*
X1213972Y321879D01*
X1214014Y322296D01*
X1213930Y322838D01*
X1213805Y323129D01*
X1213597Y323421D01*
X1213305Y323629D01*
X1213014Y323671D01*
X1212722Y323588D01*
X1212514Y323379D01*
G01X1223355Y333171D02*
Y335671D01*
X1222355D01*
X1222022Y335546D01*
X1221772Y335254D01*
X1221689Y334921D01*
X1221772Y334588D01*
X1221980Y334338D01*
X1222355Y334213D01*
X1223355D01*
G01X1219172Y334421D02*
X1218339D01*
Y333671D01*
X1218589Y333421D01*
X1218880Y333254D01*
X1219297Y333171D01*
X1219714Y333254D01*
X1220005Y333421D01*
X1220255Y333671D01*
X1220422Y333963D01*
X1220505Y334296D01*
Y334588D01*
X1220422Y334838D01*
X1220255Y335129D01*
X1220005Y335379D01*
X1219755Y335546D01*
X1219422Y335671D01*
X1219130D01*
X1218797Y335588D01*
X1218547Y335421D01*
G01X1217114Y334213D02*
X1216822Y334504D01*
X1216572Y334671D01*
X1216239Y334754D01*
X1215947Y334671D01*
X1215739Y334504D01*
X1215572Y334254D01*
X1215530Y333963D01*
X1215572Y333713D01*
X1215739Y333463D01*
X1215989Y333254D01*
X1216280Y333171D01*
X1216614Y333254D01*
X1216905Y333504D01*
X1217072Y333879D01*
X1217114Y334296D01*
X1217030Y334838D01*
X1216905Y335129D01*
X1216697Y335421D01*
X1216405Y335629D01*
X1216114Y335671D01*
X1215822Y335588D01*
X1215614Y335379D01*
G01X1212722Y333171D02*
Y335671D01*
X1214264Y333879D01*
X1212180D01*
G01X1223355Y329171D02*
Y331671D01*
X1222355D01*
X1222022Y331546D01*
X1221772Y331254D01*
X1221689Y330921D01*
X1221772Y330588D01*
X1221980Y330338D01*
X1222355Y330213D01*
X1223355D01*
G01X1219172Y330421D02*
X1218339D01*
Y329671D01*
X1218589Y329421D01*
X1218880Y329254D01*
X1219297Y329171D01*
X1219714Y329254D01*
X1220005Y329421D01*
X1220255Y329671D01*
X1220422Y329963D01*
X1220505Y330296D01*
Y330588D01*
X1220422Y330838D01*
X1220255Y331129D01*
X1220005Y331379D01*
X1219755Y331546D01*
X1219422Y331671D01*
X1219130D01*
X1218797Y331588D01*
X1218547Y331421D01*
G01X1217239Y329546D02*
X1216989Y329338D01*
X1216697Y329213D01*
X1216322Y329171D01*
X1215947Y329254D01*
X1215655Y329421D01*
X1215447Y329713D01*
X1215405Y330046D01*
X1215489Y330379D01*
X1215697Y330588D01*
X1215989Y330754D01*
X1216280Y330796D01*
X1216572Y330754D01*
X1216947Y330588D01*
X1216822Y331671D01*
X1215697D01*
G01X1214014Y330213D02*
X1213722Y330504D01*
X1213472Y330671D01*
X1213139Y330754D01*
X1212847Y330671D01*
X1212639Y330504D01*
X1212472Y330254D01*
X1212430Y329963D01*
X1212472Y329713D01*
X1212639Y329463D01*
X1212889Y329254D01*
X1213180Y329171D01*
X1213514Y329254D01*
X1213805Y329504D01*
X1213972Y329879D01*
X1214014Y330296D01*
X1213930Y330838D01*
X1213805Y331129D01*
X1213597Y331421D01*
X1213305Y331629D01*
X1213014Y331671D01*
X1212722Y331588D01*
X1212514Y331379D01*
G01X1223355Y313171D02*
Y315671D01*
X1222355D01*
X1222022Y315546D01*
X1221772Y315254D01*
X1221689Y314921D01*
X1221772Y314588D01*
X1221980Y314338D01*
X1222355Y314213D01*
X1223355D01*
G01X1219172Y314421D02*
X1218339D01*
Y313671D01*
X1218589Y313421D01*
X1218880Y313254D01*
X1219297Y313171D01*
X1219714Y313254D01*
X1220005Y313421D01*
X1220255Y313671D01*
X1220422Y313963D01*
X1220505Y314296D01*
Y314588D01*
X1220422Y314838D01*
X1220255Y315129D01*
X1220005Y315379D01*
X1219755Y315546D01*
X1219422Y315671D01*
X1219130D01*
X1218797Y315588D01*
X1218547Y315421D01*
G01X1217239Y313546D02*
X1216989Y313338D01*
X1216697Y313213D01*
X1216322Y313171D01*
X1215947Y313254D01*
X1215655Y313421D01*
X1215447Y313713D01*
X1215405Y314046D01*
X1215489Y314379D01*
X1215697Y314588D01*
X1215989Y314754D01*
X1216280Y314796D01*
X1216572Y314754D01*
X1216947Y314588D01*
X1216822Y315671D01*
X1215697D01*
G01X1214014Y315254D02*
X1213764Y315504D01*
X1213472Y315629D01*
X1213139Y315671D01*
X1212722Y315588D01*
X1212430Y315379D01*
X1212347Y315129D01*
X1212389Y314879D01*
X1212555Y314671D01*
X1213389Y314254D01*
X1213764Y313963D01*
X1214014Y313546D01*
X1214097Y313171D01*
X1212347D01*
G01X1223355Y317171D02*
Y319671D01*
X1222355D01*
X1222022Y319546D01*
X1221772Y319254D01*
X1221689Y318921D01*
X1221772Y318588D01*
X1221980Y318338D01*
X1222355Y318213D01*
X1223355D01*
G01X1219172Y318421D02*
X1218339D01*
Y317671D01*
X1218589Y317421D01*
X1218880Y317254D01*
X1219297Y317171D01*
X1219714Y317254D01*
X1220005Y317421D01*
X1220255Y317671D01*
X1220422Y317963D01*
X1220505Y318296D01*
Y318588D01*
X1220422Y318838D01*
X1220255Y319129D01*
X1220005Y319379D01*
X1219755Y319546D01*
X1219422Y319671D01*
X1219130D01*
X1218797Y319588D01*
X1218547Y319421D01*
G01X1217239Y317671D02*
X1216989Y317379D01*
X1216655Y317213D01*
X1216280Y317171D01*
X1215947Y317213D01*
X1215614Y317421D01*
X1215405Y317671D01*
X1215364Y317921D01*
X1215447Y318213D01*
X1215739Y318421D01*
X1216030Y318504D01*
X1216405D01*
G01X1216030D02*
X1215780Y318629D01*
X1215572Y318838D01*
X1215489Y319088D01*
X1215572Y319338D01*
X1215780Y319546D01*
X1216155Y319671D01*
X1216530Y319629D01*
X1216905Y319463D01*
G01X1214014Y318213D02*
X1213722Y318504D01*
X1213472Y318671D01*
X1213139Y318754D01*
X1212847Y318671D01*
X1212639Y318504D01*
X1212472Y318254D01*
X1212430Y317963D01*
X1212472Y317713D01*
X1212639Y317463D01*
X1212889Y317254D01*
X1213180Y317171D01*
X1213514Y317254D01*
X1213805Y317504D01*
X1213972Y317879D01*
X1214014Y318296D01*
X1213930Y318838D01*
X1213805Y319129D01*
X1213597Y319421D01*
X1213305Y319629D01*
X1213014Y319671D01*
X1212722Y319588D01*
X1212514Y319379D01*
G01X1265333Y17000D02*
Y7000D01*
X1268667D01*
X1270000Y7500D01*
X1271000Y8167D01*
X1271833Y9167D01*
X1272500Y10334D01*
X1272667Y12000D01*
X1272500Y13667D01*
X1271833Y14833D01*
X1271000Y15834D01*
X1270000Y16500D01*
X1268667Y17000D01*
X1265333D01*
G01X1263761Y133276D02*
X1263886Y133026D01*
X1263969Y132734D01*
Y132401D01*
X1263844Y132026D01*
X1263636Y131734D01*
X1263386Y131526D01*
X1262969Y131359D01*
X1262594Y131317D01*
X1262219Y131401D01*
X1261969Y131526D01*
X1261719Y131776D01*
X1261552Y132067D01*
X1261469Y132359D01*
Y132651D01*
X1261552Y132942D01*
X1261677Y133192D01*
X1261844Y133401D01*
G01X1263552Y134667D02*
X1263802Y134917D01*
X1263927Y135209D01*
X1263969Y135542D01*
X1263886Y135959D01*
X1263677Y136251D01*
X1263427Y136334D01*
X1263177Y136292D01*
X1262969Y136126D01*
X1262552Y135292D01*
X1262261Y134917D01*
X1261844Y134667D01*
X1261469Y134584D01*
Y136334D01*
G01X1261969Y137642D02*
X1261677Y137892D01*
X1261511Y138226D01*
X1261469Y138601D01*
X1261511Y138934D01*
X1261719Y139267D01*
X1261969Y139476D01*
X1262219Y139517D01*
X1262511Y139434D01*
X1262719Y139142D01*
X1262802Y138851D01*
Y138476D01*
G01Y138851D02*
X1262927Y139101D01*
X1263136Y139309D01*
X1263386Y139392D01*
X1263636Y139309D01*
X1263844Y139101D01*
X1263969Y138726D01*
X1263927Y138351D01*
X1263761Y137976D01*
G01X1261469Y141576D02*
X1262011Y141659D01*
X1262469Y141784D01*
X1262886Y141951D01*
X1263344Y142159D01*
X1263969Y142492D01*
Y140826D01*
G01X1259761Y133276D02*
X1259886Y133026D01*
X1259969Y132734D01*
Y132401D01*
X1259844Y132026D01*
X1259636Y131734D01*
X1259386Y131526D01*
X1258969Y131359D01*
X1258594Y131317D01*
X1258219Y131401D01*
X1257969Y131526D01*
X1257719Y131776D01*
X1257552Y132067D01*
X1257469Y132359D01*
Y132651D01*
X1257552Y132942D01*
X1257677Y133192D01*
X1257844Y133401D01*
G01X1259552Y134667D02*
X1259802Y134917D01*
X1259927Y135209D01*
X1259969Y135542D01*
X1259886Y135959D01*
X1259677Y136251D01*
X1259427Y136334D01*
X1259177Y136292D01*
X1258969Y136126D01*
X1258552Y135292D01*
X1258261Y134917D01*
X1257844Y134667D01*
X1257469Y134584D01*
Y136334D01*
G01Y139059D02*
X1259969D01*
X1258177Y137517D01*
Y139601D01*
G01X1259552Y140867D02*
X1259802Y141117D01*
X1259927Y141409D01*
X1259969Y141742D01*
X1259886Y142159D01*
X1259677Y142451D01*
X1259427Y142534D01*
X1259177Y142492D01*
X1258969Y142326D01*
X1258552Y141492D01*
X1258261Y141117D01*
X1257844Y140867D01*
X1257469Y140784D01*
Y142534D01*
G01X1259173Y150324D02*
X1259298Y150074D01*
X1259381Y149782D01*
Y149449D01*
X1259256Y149074D01*
X1259048Y148782D01*
X1258798Y148574D01*
X1258381Y148407D01*
X1258006Y148365D01*
X1257631Y148449D01*
X1257381Y148574D01*
X1257131Y148824D01*
X1256964Y149115D01*
X1256881Y149407D01*
Y149699D01*
X1256964Y149990D01*
X1257089Y150240D01*
X1257256Y150449D01*
G01X1258964Y151715D02*
X1259214Y151965D01*
X1259339Y152257D01*
X1259381Y152590D01*
X1259298Y153007D01*
X1259089Y153299D01*
X1258839Y153382D01*
X1258589Y153340D01*
X1258381Y153174D01*
X1257964Y152340D01*
X1257673Y151965D01*
X1257256Y151715D01*
X1256881Y151632D01*
Y153382D01*
G01X1257256Y154690D02*
X1257048Y154940D01*
X1256923Y155232D01*
X1256881Y155607D01*
X1256964Y155982D01*
X1257131Y156274D01*
X1257423Y156482D01*
X1257756Y156524D01*
X1258089Y156440D01*
X1258298Y156232D01*
X1258464Y155940D01*
X1258506Y155649D01*
X1258464Y155357D01*
X1258298Y154982D01*
X1259381Y155107D01*
Y156232D01*
G01X1256881Y159207D02*
X1259381D01*
X1257589Y157665D01*
Y159749D01*
G01X1263173Y150324D02*
X1263298Y150074D01*
X1263381Y149782D01*
Y149449D01*
X1263256Y149074D01*
X1263048Y148782D01*
X1262798Y148574D01*
X1262381Y148407D01*
X1262006Y148365D01*
X1261631Y148449D01*
X1261381Y148574D01*
X1261131Y148824D01*
X1260964Y149115D01*
X1260881Y149407D01*
Y149699D01*
X1260964Y149990D01*
X1261089Y150240D01*
X1261256Y150449D01*
G01X1262964Y151715D02*
X1263214Y151965D01*
X1263339Y152257D01*
X1263381Y152590D01*
X1263298Y153007D01*
X1263089Y153299D01*
X1262839Y153382D01*
X1262589Y153340D01*
X1262381Y153174D01*
X1261964Y152340D01*
X1261673Y151965D01*
X1261256Y151715D01*
X1260881Y151632D01*
Y153382D01*
G01X1261256Y154690D02*
X1261048Y154940D01*
X1260923Y155232D01*
X1260881Y155607D01*
X1260964Y155982D01*
X1261131Y156274D01*
X1261423Y156482D01*
X1261756Y156524D01*
X1262089Y156440D01*
X1262298Y156232D01*
X1262464Y155940D01*
X1262506Y155649D01*
X1262464Y155357D01*
X1262298Y154982D01*
X1263381Y155107D01*
Y156232D01*
G01X1261256Y157790D02*
X1261048Y158040D01*
X1260923Y158332D01*
X1260881Y158707D01*
X1260964Y159082D01*
X1261131Y159374D01*
X1261423Y159582D01*
X1261756Y159624D01*
X1262089Y159540D01*
X1262298Y159332D01*
X1262464Y159040D01*
X1262506Y158749D01*
X1262464Y158457D01*
X1262298Y158082D01*
X1263381Y158207D01*
Y159332D01*
G01X1267359Y212949D02*
X1269859D01*
Y213949D01*
X1269734Y214282D01*
X1269442Y214532D01*
X1269109Y214615D01*
X1268776Y214532D01*
X1268526Y214324D01*
X1268401Y213949D01*
Y212949D01*
G01X1269651Y217799D02*
X1269776Y217549D01*
X1269859Y217257D01*
Y216924D01*
X1269734Y216549D01*
X1269526Y216257D01*
X1269276Y216049D01*
X1268859Y215882D01*
X1268484Y215840D01*
X1268109Y215924D01*
X1267859Y216049D01*
X1267609Y216299D01*
X1267442Y216590D01*
X1267359Y216882D01*
Y217174D01*
X1267442Y217465D01*
X1267567Y217715D01*
X1267734Y217924D01*
G01X1267359Y219982D02*
X1269859D01*
X1269359Y219482D01*
G01X1267359D02*
Y220482D01*
G01Y223082D02*
X1267401Y223374D01*
X1267526Y223707D01*
X1267734Y223915D01*
X1268026Y223999D01*
X1268317Y223915D01*
X1268567Y223665D01*
X1268692Y223290D01*
Y222874D01*
X1268776Y222624D01*
X1268984Y222415D01*
X1269276Y222332D01*
X1269567Y222457D01*
X1269776Y222749D01*
X1269859Y223082D01*
X1269776Y223415D01*
X1269567Y223707D01*
X1269276Y223832D01*
X1268984Y223749D01*
X1268776Y223540D01*
X1268692Y223290D01*
Y222874D01*
X1268567Y222499D01*
X1268317Y222249D01*
X1268026Y222165D01*
X1267734Y222249D01*
X1267526Y222457D01*
X1267401Y222790D01*
X1267359Y223082D01*
G01X1267859Y225265D02*
X1267567Y225515D01*
X1267401Y225849D01*
X1267359Y226224D01*
X1267401Y226557D01*
X1267609Y226890D01*
X1267859Y227099D01*
X1268109Y227140D01*
X1268401Y227057D01*
X1268609Y226765D01*
X1268692Y226474D01*
Y226099D01*
G01Y226474D02*
X1268817Y226724D01*
X1269026Y226932D01*
X1269276Y227015D01*
X1269526Y226932D01*
X1269734Y226724D01*
X1269859Y226349D01*
X1269817Y225974D01*
X1269651Y225599D01*
G01X1263112Y212772D02*
X1265612D01*
Y213772D01*
X1265487Y214105D01*
X1265195Y214355D01*
X1264862Y214438D01*
X1264529Y214355D01*
X1264279Y214147D01*
X1264154Y213772D01*
Y212772D01*
G01X1265404Y217622D02*
X1265529Y217372D01*
X1265612Y217080D01*
Y216747D01*
X1265487Y216372D01*
X1265279Y216080D01*
X1265029Y215872D01*
X1264612Y215705D01*
X1264237Y215663D01*
X1263862Y215747D01*
X1263612Y215872D01*
X1263362Y216122D01*
X1263195Y216413D01*
X1263112Y216705D01*
Y216997D01*
X1263195Y217288D01*
X1263320Y217538D01*
X1263487Y217747D01*
G01X1263112Y219805D02*
X1265612D01*
X1265112Y219305D01*
G01X1263112D02*
Y220305D01*
G01Y222822D02*
X1263654Y222905D01*
X1264112Y223030D01*
X1264529Y223197D01*
X1264987Y223405D01*
X1265612Y223738D01*
Y222072D01*
G01X1263112Y226005D02*
X1263154Y226297D01*
X1263279Y226630D01*
X1263487Y226838D01*
X1263779Y226922D01*
X1264070Y226838D01*
X1264320Y226588D01*
X1264445Y226213D01*
Y225797D01*
X1264529Y225547D01*
X1264737Y225338D01*
X1265029Y225255D01*
X1265320Y225380D01*
X1265529Y225672D01*
X1265612Y226005D01*
X1265529Y226338D01*
X1265320Y226630D01*
X1265029Y226755D01*
X1264737Y226672D01*
X1264529Y226463D01*
X1264445Y226213D01*
Y225797D01*
X1264320Y225422D01*
X1264070Y225172D01*
X1263779Y225088D01*
X1263487Y225172D01*
X1263279Y225380D01*
X1263154Y225713D01*
X1263112Y226005D01*
G01X1272047Y212949D02*
X1274547D01*
Y213949D01*
X1274422Y214282D01*
X1274130Y214532D01*
X1273797Y214615D01*
X1273464Y214532D01*
X1273214Y214324D01*
X1273089Y213949D01*
Y212949D01*
G01X1274339Y217799D02*
X1274464Y217549D01*
X1274547Y217257D01*
Y216924D01*
X1274422Y216549D01*
X1274214Y216257D01*
X1273964Y216049D01*
X1273547Y215882D01*
X1273172Y215840D01*
X1272797Y215924D01*
X1272547Y216049D01*
X1272297Y216299D01*
X1272130Y216590D01*
X1272047Y216882D01*
Y217174D01*
X1272130Y217465D01*
X1272255Y217715D01*
X1272422Y217924D01*
G01X1272047Y219982D02*
X1274547D01*
X1274047Y219482D01*
G01X1272047D02*
Y220482D01*
G01Y222999D02*
X1272589Y223082D01*
X1273047Y223207D01*
X1273464Y223374D01*
X1273922Y223582D01*
X1274547Y223915D01*
Y222249D01*
G01X1272047Y226099D02*
X1272589Y226182D01*
X1273047Y226307D01*
X1273464Y226474D01*
X1273922Y226682D01*
X1274547Y227015D01*
Y225349D01*
G01X1276913Y212772D02*
X1279413D01*
Y213772D01*
X1279288Y214105D01*
X1278996Y214355D01*
X1278663Y214438D01*
X1278330Y214355D01*
X1278080Y214147D01*
X1277955Y213772D01*
Y212772D01*
G01X1279205Y217622D02*
X1279330Y217372D01*
X1279413Y217080D01*
Y216747D01*
X1279288Y216372D01*
X1279080Y216080D01*
X1278830Y215872D01*
X1278413Y215705D01*
X1278038Y215663D01*
X1277663Y215747D01*
X1277413Y215872D01*
X1277163Y216122D01*
X1276996Y216413D01*
X1276913Y216705D01*
Y216997D01*
X1276996Y217288D01*
X1277121Y217538D01*
X1277288Y217747D01*
G01X1276913Y219805D02*
X1279413D01*
X1278913Y219305D01*
G01X1276913D02*
Y220305D01*
G01Y222822D02*
X1277455Y222905D01*
X1277913Y223030D01*
X1278330Y223197D01*
X1278788Y223405D01*
X1279413Y223738D01*
Y222072D01*
G01X1277955Y225213D02*
X1278246Y225505D01*
X1278413Y225755D01*
X1278496Y226088D01*
X1278413Y226380D01*
X1278246Y226588D01*
X1277996Y226755D01*
X1277705Y226797D01*
X1277455Y226755D01*
X1277205Y226588D01*
X1276996Y226338D01*
X1276913Y226047D01*
X1276996Y225713D01*
X1277246Y225422D01*
X1277621Y225255D01*
X1278038Y225213D01*
X1278580Y225297D01*
X1278871Y225422D01*
X1279163Y225630D01*
X1279371Y225922D01*
X1279413Y226213D01*
X1279330Y226505D01*
X1279121Y226713D01*
G01X1271000Y256967D02*
X1273500D01*
Y257967D01*
X1273375Y258300D01*
X1273083Y258550D01*
X1272750Y258633D01*
X1272417Y258550D01*
X1272167Y258342D01*
X1272042Y257967D01*
Y256967D01*
G01X1273292Y261817D02*
X1273417Y261567D01*
X1273500Y261275D01*
Y260942D01*
X1273375Y260567D01*
X1273167Y260275D01*
X1272917Y260067D01*
X1272500Y259900D01*
X1272125Y259858D01*
X1271750Y259942D01*
X1271500Y260067D01*
X1271250Y260317D01*
X1271083Y260608D01*
X1271000Y260900D01*
Y261192D01*
X1271083Y261483D01*
X1271208Y261733D01*
X1271375Y261942D01*
G01X1271000Y264000D02*
X1273500D01*
X1273000Y263500D01*
G01X1271000D02*
Y264500D01*
G01Y267100D02*
X1271042Y267392D01*
X1271167Y267725D01*
X1271375Y267933D01*
X1271667Y268017D01*
X1271958Y267933D01*
X1272208Y267683D01*
X1272333Y267308D01*
Y266892D01*
X1272417Y266642D01*
X1272625Y266433D01*
X1272917Y266350D01*
X1273208Y266475D01*
X1273417Y266767D01*
X1273500Y267100D01*
X1273417Y267433D01*
X1273208Y267725D01*
X1272917Y267850D01*
X1272625Y267767D01*
X1272417Y267558D01*
X1272333Y267308D01*
Y266892D01*
X1272208Y266517D01*
X1271958Y266267D01*
X1271667Y266183D01*
X1271375Y266267D01*
X1271167Y266475D01*
X1271042Y266808D01*
X1271000Y267100D01*
G01X1273083Y269408D02*
X1273333Y269658D01*
X1273458Y269950D01*
X1273500Y270283D01*
X1273417Y270700D01*
X1273208Y270992D01*
X1272958Y271075D01*
X1272708Y271033D01*
X1272500Y270867D01*
X1272083Y270033D01*
X1271792Y269658D01*
X1271375Y269408D01*
X1271000Y269325D01*
Y271075D01*
G01X1266161Y256467D02*
X1268661D01*
Y257467D01*
X1268536Y257800D01*
X1268244Y258050D01*
X1267911Y258133D01*
X1267578Y258050D01*
X1267328Y257842D01*
X1267203Y257467D01*
Y256467D01*
G01X1268453Y261317D02*
X1268578Y261067D01*
X1268661Y260775D01*
Y260442D01*
X1268536Y260067D01*
X1268328Y259775D01*
X1268078Y259567D01*
X1267661Y259400D01*
X1267286Y259358D01*
X1266911Y259442D01*
X1266661Y259567D01*
X1266411Y259817D01*
X1266244Y260108D01*
X1266161Y260400D01*
Y260692D01*
X1266244Y260983D01*
X1266369Y261233D01*
X1266536Y261442D01*
G01X1266161Y263500D02*
X1268661D01*
X1268161Y263000D01*
G01X1266161D02*
Y264000D01*
G01Y266600D02*
X1266203Y266892D01*
X1266328Y267225D01*
X1266536Y267433D01*
X1266828Y267517D01*
X1267119Y267433D01*
X1267369Y267183D01*
X1267494Y266808D01*
Y266392D01*
X1267578Y266142D01*
X1267786Y265933D01*
X1268078Y265850D01*
X1268369Y265975D01*
X1268578Y266267D01*
X1268661Y266600D01*
X1268578Y266933D01*
X1268369Y267225D01*
X1268078Y267350D01*
X1267786Y267267D01*
X1267578Y267058D01*
X1267494Y266808D01*
Y266392D01*
X1267369Y266017D01*
X1267119Y265767D01*
X1266828Y265683D01*
X1266536Y265767D01*
X1266328Y265975D01*
X1266203Y266308D01*
X1266161Y266600D01*
G01X1268661Y269700D02*
X1268578Y269367D01*
X1268369Y269117D01*
X1268119Y268950D01*
X1267786Y268825D01*
X1267411Y268783D01*
X1267036Y268825D01*
X1266703Y268950D01*
X1266453Y269117D01*
X1266244Y269367D01*
X1266161Y269700D01*
X1266244Y270033D01*
X1266453Y270283D01*
X1266703Y270450D01*
X1267036Y270575D01*
X1267411Y270617D01*
X1267786Y270575D01*
X1268119Y270450D01*
X1268369Y270283D01*
X1268578Y270033D01*
X1268661Y269700D01*
G01X1276500Y256967D02*
X1279000D01*
Y257967D01*
X1278875Y258300D01*
X1278583Y258550D01*
X1278250Y258633D01*
X1277917Y258550D01*
X1277667Y258342D01*
X1277542Y257967D01*
Y256967D01*
G01X1278792Y261817D02*
X1278917Y261567D01*
X1279000Y261275D01*
Y260942D01*
X1278875Y260567D01*
X1278667Y260275D01*
X1278417Y260067D01*
X1278000Y259900D01*
X1277625Y259858D01*
X1277250Y259942D01*
X1277000Y260067D01*
X1276750Y260317D01*
X1276583Y260608D01*
X1276500Y260900D01*
Y261192D01*
X1276583Y261483D01*
X1276708Y261733D01*
X1276875Y261942D01*
G01X1276500Y264000D02*
X1279000D01*
X1278500Y263500D01*
G01X1276500D02*
Y264500D01*
G01Y267017D02*
X1277042Y267100D01*
X1277500Y267225D01*
X1277917Y267392D01*
X1278375Y267600D01*
X1279000Y267933D01*
Y266267D01*
G01X1276792Y269492D02*
X1276583Y269783D01*
X1276500Y270117D01*
X1276583Y270450D01*
X1276833Y270742D01*
X1277208Y270950D01*
X1277583Y271033D01*
X1278042D01*
X1278417Y270950D01*
X1278750Y270742D01*
X1278917Y270492D01*
X1279000Y270200D01*
X1278917Y269867D01*
X1278750Y269617D01*
X1278500Y269450D01*
X1278167Y269367D01*
X1277875Y269450D01*
X1277583Y269658D01*
X1277417Y269908D01*
X1277375Y270200D01*
X1277458Y270533D01*
X1277667Y270783D01*
X1278042Y271033D01*
G01X1275938Y703043D02*
X1278438D01*
Y704084D01*
X1278313Y704418D01*
X1278146Y704626D01*
X1277813Y704709D01*
X1277480Y704626D01*
X1277271Y704376D01*
X1277146Y704084D01*
Y703043D01*
G01Y704084D02*
X1275938Y704709D01*
G01X1276438Y706059D02*
X1276146Y706309D01*
X1275980Y706643D01*
X1275938Y707018D01*
X1275980Y707351D01*
X1276188Y707684D01*
X1276438Y707893D01*
X1276688Y707934D01*
X1276980Y707851D01*
X1277188Y707559D01*
X1277271Y707268D01*
Y706893D01*
G01Y707268D02*
X1277396Y707518D01*
X1277605Y707726D01*
X1277855Y707809D01*
X1278105Y707726D01*
X1278313Y707518D01*
X1278438Y707143D01*
X1278396Y706768D01*
X1278230Y706393D01*
G01X1278021Y709284D02*
X1278271Y709534D01*
X1278396Y709826D01*
X1278438Y710159D01*
X1278355Y710576D01*
X1278146Y710868D01*
X1277896Y710951D01*
X1277646Y710909D01*
X1277438Y710743D01*
X1277021Y709909D01*
X1276730Y709534D01*
X1276313Y709284D01*
X1275938Y709201D01*
Y710951D01*
G01Y713176D02*
X1278438D01*
X1277938Y712676D01*
G01X1275938D02*
Y713676D01*
G01Y716776D02*
X1278438D01*
X1276646Y715234D01*
Y717318D01*
G01X1318269Y242894D02*
Y245394D01*
X1317269D01*
X1316936Y245269D01*
X1316686Y244977D01*
X1316603Y244644D01*
X1316686Y244311D01*
X1316894Y244061D01*
X1317269Y243936D01*
X1318269D01*
G01X1313419Y245186D02*
X1313669Y245311D01*
X1313961Y245394D01*
X1314294D01*
X1314669Y245269D01*
X1314961Y245061D01*
X1315169Y244811D01*
X1315336Y244394D01*
X1315378Y244019D01*
X1315294Y243644D01*
X1315169Y243394D01*
X1314919Y243144D01*
X1314628Y242977D01*
X1314336Y242894D01*
X1314044D01*
X1313753Y242977D01*
X1313503Y243102D01*
X1313294Y243269D01*
G01X1311236Y242894D02*
Y245394D01*
X1311736Y244894D01*
G01Y242894D02*
X1310736D01*
G01X1308136D02*
X1307844Y242936D01*
X1307511Y243061D01*
X1307303Y243269D01*
X1307219Y243561D01*
X1307303Y243852D01*
X1307553Y244102D01*
X1307928Y244227D01*
X1308344D01*
X1308594Y244311D01*
X1308803Y244519D01*
X1308886Y244811D01*
X1308761Y245102D01*
X1308469Y245311D01*
X1308136Y245394D01*
X1307803Y245311D01*
X1307511Y245102D01*
X1307386Y244811D01*
X1307469Y244519D01*
X1307678Y244311D01*
X1307928Y244227D01*
X1308344D01*
X1308719Y244102D01*
X1308969Y243852D01*
X1309053Y243561D01*
X1308969Y243269D01*
X1308761Y243061D01*
X1308428Y242936D01*
X1308136Y242894D01*
G01X1305036D02*
X1304744Y242936D01*
X1304411Y243061D01*
X1304203Y243269D01*
X1304119Y243561D01*
X1304203Y243852D01*
X1304453Y244102D01*
X1304828Y244227D01*
X1305244D01*
X1305494Y244311D01*
X1305703Y244519D01*
X1305786Y244811D01*
X1305661Y245102D01*
X1305369Y245311D01*
X1305036Y245394D01*
X1304703Y245311D01*
X1304411Y245102D01*
X1304286Y244811D01*
X1304369Y244519D01*
X1304578Y244311D01*
X1304828Y244227D01*
X1305244D01*
X1305619Y244102D01*
X1305869Y243852D01*
X1305953Y243561D01*
X1305869Y243269D01*
X1305661Y243061D01*
X1305328Y242936D01*
X1305036Y242894D01*
G01X1282500Y257467D02*
X1285000D01*
Y258467D01*
X1284875Y258800D01*
X1284583Y259050D01*
X1284250Y259133D01*
X1283917Y259050D01*
X1283667Y258842D01*
X1283542Y258467D01*
Y257467D01*
G01X1284792Y262317D02*
X1284917Y262067D01*
X1285000Y261775D01*
Y261442D01*
X1284875Y261067D01*
X1284667Y260775D01*
X1284417Y260567D01*
X1284000Y260400D01*
X1283625Y260358D01*
X1283250Y260442D01*
X1283000Y260567D01*
X1282750Y260817D01*
X1282583Y261108D01*
X1282500Y261400D01*
Y261692D01*
X1282583Y261983D01*
X1282708Y262233D01*
X1282875Y262442D01*
G01X1282500Y264500D02*
X1285000D01*
X1284500Y264000D01*
G01X1282500D02*
Y265000D01*
G01Y267600D02*
X1282542Y267892D01*
X1282667Y268225D01*
X1282875Y268433D01*
X1283167Y268517D01*
X1283458Y268433D01*
X1283708Y268183D01*
X1283833Y267808D01*
Y267392D01*
X1283917Y267142D01*
X1284125Y266933D01*
X1284417Y266850D01*
X1284708Y266975D01*
X1284917Y267267D01*
X1285000Y267600D01*
X1284917Y267933D01*
X1284708Y268225D01*
X1284417Y268350D01*
X1284125Y268267D01*
X1283917Y268058D01*
X1283833Y267808D01*
Y267392D01*
X1283708Y267017D01*
X1283458Y266767D01*
X1283167Y266683D01*
X1282875Y266767D01*
X1282667Y266975D01*
X1282542Y267308D01*
X1282500Y267600D01*
G01Y270700D02*
X1285000D01*
X1284500Y270200D01*
G01X1282500D02*
Y271200D01*
G01X1288000Y257517D02*
X1290500D01*
Y258517D01*
X1290375Y258850D01*
X1290083Y259100D01*
X1289750Y259183D01*
X1289417Y259100D01*
X1289167Y258892D01*
X1289042Y258517D01*
Y257517D01*
G01X1290292Y262367D02*
X1290417Y262117D01*
X1290500Y261825D01*
Y261492D01*
X1290375Y261117D01*
X1290167Y260825D01*
X1289917Y260617D01*
X1289500Y260450D01*
X1289125Y260408D01*
X1288750Y260492D01*
X1288500Y260617D01*
X1288250Y260867D01*
X1288083Y261158D01*
X1288000Y261450D01*
Y261742D01*
X1288083Y262033D01*
X1288208Y262283D01*
X1288375Y262492D01*
G01X1288292Y263842D02*
X1288083Y264133D01*
X1288000Y264467D01*
X1288083Y264800D01*
X1288333Y265092D01*
X1288708Y265300D01*
X1289083Y265383D01*
X1289542D01*
X1289917Y265300D01*
X1290250Y265092D01*
X1290417Y264842D01*
X1290500Y264550D01*
X1290417Y264217D01*
X1290250Y263967D01*
X1290000Y263800D01*
X1289667Y263717D01*
X1289375Y263800D01*
X1289083Y264008D01*
X1288917Y264258D01*
X1288875Y264550D01*
X1288958Y264883D01*
X1289167Y265133D01*
X1289542Y265383D01*
G01X1289042Y266858D02*
X1289333Y267150D01*
X1289500Y267400D01*
X1289583Y267733D01*
X1289500Y268025D01*
X1289333Y268233D01*
X1289083Y268400D01*
X1288792Y268442D01*
X1288542Y268400D01*
X1288292Y268233D01*
X1288083Y267983D01*
X1288000Y267692D01*
X1288083Y267358D01*
X1288333Y267067D01*
X1288708Y266900D01*
X1289125Y266858D01*
X1289667Y266942D01*
X1289958Y267067D01*
X1290250Y267275D01*
X1290458Y267567D01*
X1290500Y267858D01*
X1290417Y268150D01*
X1290208Y268358D01*
G01X1305033Y250167D02*
Y252667D01*
X1304033D01*
X1303700Y252542D01*
X1303450Y252250D01*
X1303367Y251917D01*
X1303450Y251584D01*
X1303658Y251334D01*
X1304033Y251209D01*
X1305033D01*
G01X1301933Y250167D02*
Y252667D01*
X1300892D01*
X1300558Y252542D01*
X1300350Y252375D01*
X1300267Y252042D01*
X1300350Y251709D01*
X1300600Y251500D01*
X1300892Y251375D01*
X1301933D01*
G01X1300892D02*
X1300267Y250167D01*
G01X1298000D02*
Y252667D01*
X1298500Y252167D01*
G01Y250167D02*
X1297500D01*
G01X1295817Y250542D02*
X1295567Y250334D01*
X1295275Y250209D01*
X1294900Y250167D01*
X1294525Y250250D01*
X1294233Y250417D01*
X1294025Y250709D01*
X1293983Y251042D01*
X1294067Y251375D01*
X1294275Y251584D01*
X1294567Y251750D01*
X1294858Y251792D01*
X1295150Y251750D01*
X1295525Y251584D01*
X1295400Y252667D01*
X1294275D01*
G01X1291300Y250167D02*
Y252667D01*
X1292842Y250875D01*
X1290758D01*
G01X1308300Y247000D02*
X1313500D01*
G01X1308300Y254000D02*
X1316100D01*
G01X1308300Y247000D02*
Y254000D01*
G01X1323798Y276610D02*
Y279110D01*
X1322798D01*
X1322465Y278985D01*
X1322215Y278693D01*
X1322132Y278360D01*
X1322215Y278027D01*
X1322423Y277777D01*
X1322798Y277652D01*
X1323798D01*
G01X1318948Y278902D02*
X1319198Y279027D01*
X1319490Y279110D01*
X1319823D01*
X1320198Y278985D01*
X1320490Y278777D01*
X1320698Y278527D01*
X1320865Y278110D01*
X1320907Y277735D01*
X1320823Y277360D01*
X1320698Y277110D01*
X1320448Y276860D01*
X1320157Y276693D01*
X1319865Y276610D01*
X1319573D01*
X1319282Y276693D01*
X1319032Y276818D01*
X1318823Y276985D01*
G01X1316765Y276610D02*
Y279110D01*
X1317265Y278610D01*
G01Y276610D02*
X1316265D01*
G01X1313665D02*
X1313373Y276652D01*
X1313040Y276777D01*
X1312832Y276985D01*
X1312748Y277277D01*
X1312832Y277568D01*
X1313082Y277818D01*
X1313457Y277943D01*
X1313873D01*
X1314123Y278027D01*
X1314332Y278235D01*
X1314415Y278527D01*
X1314290Y278818D01*
X1313998Y279027D01*
X1313665Y279110D01*
X1313332Y279027D01*
X1313040Y278818D01*
X1312915Y278527D01*
X1312998Y278235D01*
X1313207Y278027D01*
X1313457Y277943D01*
X1313873D01*
X1314248Y277818D01*
X1314498Y277568D01*
X1314582Y277277D01*
X1314498Y276985D01*
X1314290Y276777D01*
X1313957Y276652D01*
X1313665Y276610D01*
G01X1311482Y276985D02*
X1311232Y276777D01*
X1310940Y276652D01*
X1310565Y276610D01*
X1310190Y276693D01*
X1309898Y276860D01*
X1309690Y277152D01*
X1309648Y277485D01*
X1309732Y277818D01*
X1309940Y278027D01*
X1310232Y278193D01*
X1310523Y278235D01*
X1310815Y278193D01*
X1311190Y278027D01*
X1311065Y279110D01*
X1309940D01*
G01X1295500Y272300D02*
X1291500D01*
Y279700D01*
G01X1314774Y281287D02*
Y283787D01*
X1313774D01*
X1313441Y283662D01*
X1313191Y283370D01*
X1313108Y283037D01*
X1313191Y282704D01*
X1313399Y282454D01*
X1313774Y282329D01*
X1314774D01*
G01X1311674Y281287D02*
Y283787D01*
X1310633D01*
X1310299Y283662D01*
X1310091Y283495D01*
X1310008Y283162D01*
X1310091Y282829D01*
X1310341Y282620D01*
X1310633Y282495D01*
X1311674D01*
G01X1310633D02*
X1310008Y281287D01*
G01X1308533Y283370D02*
X1308283Y283620D01*
X1307991Y283745D01*
X1307658Y283787D01*
X1307241Y283704D01*
X1306949Y283495D01*
X1306866Y283245D01*
X1306908Y282995D01*
X1307074Y282787D01*
X1307908Y282370D01*
X1308283Y282079D01*
X1308533Y281662D01*
X1308616Y281287D01*
X1306866D01*
G01X1304641D02*
Y283787D01*
X1305141Y283287D01*
G01Y281287D02*
X1304141D01*
G01X1293423Y283521D02*
X1295923D01*
Y284521D01*
X1295798Y284854D01*
X1295506Y285104D01*
X1295173Y285187D01*
X1294840Y285104D01*
X1294590Y284896D01*
X1294465Y284521D01*
Y283521D01*
G01X1293423Y286621D02*
X1295923D01*
Y287662D01*
X1295798Y287996D01*
X1295631Y288204D01*
X1295298Y288287D01*
X1294965Y288204D01*
X1294756Y287954D01*
X1294631Y287662D01*
Y286621D01*
G01Y287662D02*
X1293423Y288287D01*
G01Y290554D02*
X1295923D01*
X1295423Y290054D01*
G01X1293423D02*
Y291054D01*
G01X1293798Y292737D02*
X1293590Y292987D01*
X1293465Y293279D01*
X1293423Y293654D01*
X1293506Y294029D01*
X1293673Y294321D01*
X1293965Y294529D01*
X1294298Y294571D01*
X1294631Y294487D01*
X1294840Y294279D01*
X1295006Y293987D01*
X1295048Y293696D01*
X1295006Y293404D01*
X1294840Y293029D01*
X1295923Y293154D01*
Y294279D01*
G01X1293798Y295837D02*
X1293590Y296087D01*
X1293465Y296379D01*
X1293423Y296754D01*
X1293506Y297129D01*
X1293673Y297421D01*
X1293965Y297629D01*
X1294298Y297671D01*
X1294631Y297587D01*
X1294840Y297379D01*
X1295006Y297087D01*
X1295048Y296796D01*
X1295006Y296504D01*
X1294840Y296129D01*
X1295923Y296254D01*
Y297379D01*
G01X1289423Y283521D02*
X1291923D01*
Y284521D01*
X1291798Y284854D01*
X1291506Y285104D01*
X1291173Y285187D01*
X1290840Y285104D01*
X1290590Y284896D01*
X1290465Y284521D01*
Y283521D01*
G01X1291715Y288371D02*
X1291840Y288121D01*
X1291923Y287829D01*
Y287496D01*
X1291798Y287121D01*
X1291590Y286829D01*
X1291340Y286621D01*
X1290923Y286454D01*
X1290548Y286412D01*
X1290173Y286496D01*
X1289923Y286621D01*
X1289673Y286871D01*
X1289506Y287162D01*
X1289423Y287454D01*
Y287746D01*
X1289506Y288037D01*
X1289631Y288287D01*
X1289798Y288496D01*
G01X1289423Y290554D02*
X1291923D01*
X1291423Y290054D01*
G01X1289423D02*
Y291054D01*
G01Y293654D02*
X1289465Y293946D01*
X1289590Y294279D01*
X1289798Y294487D01*
X1290090Y294571D01*
X1290381Y294487D01*
X1290631Y294237D01*
X1290756Y293862D01*
Y293446D01*
X1290840Y293196D01*
X1291048Y292987D01*
X1291340Y292904D01*
X1291631Y293029D01*
X1291840Y293321D01*
X1291923Y293654D01*
X1291840Y293987D01*
X1291631Y294279D01*
X1291340Y294404D01*
X1291048Y294321D01*
X1290840Y294112D01*
X1290756Y293862D01*
Y293446D01*
X1290631Y293071D01*
X1290381Y292821D01*
X1290090Y292737D01*
X1289798Y292821D01*
X1289590Y293029D01*
X1289465Y293362D01*
X1289423Y293654D01*
G01X1290465Y295962D02*
X1290756Y296254D01*
X1290923Y296504D01*
X1291006Y296837D01*
X1290923Y297129D01*
X1290756Y297337D01*
X1290506Y297504D01*
X1290215Y297546D01*
X1289965Y297504D01*
X1289715Y297337D01*
X1289506Y297087D01*
X1289423Y296796D01*
X1289506Y296462D01*
X1289756Y296171D01*
X1290131Y296004D01*
X1290548Y295962D01*
X1291090Y296046D01*
X1291381Y296171D01*
X1291673Y296379D01*
X1291881Y296671D01*
X1291923Y296962D01*
X1291840Y297254D01*
X1291631Y297462D01*
G01X1293712Y660353D02*
X1296212D01*
Y661394D01*
X1296087Y661728D01*
X1295920Y661936D01*
X1295587Y662019D01*
X1295254Y661936D01*
X1295045Y661686D01*
X1294920Y661394D01*
Y660353D01*
G01Y661394D02*
X1293712Y662019D01*
G01X1294087Y663369D02*
X1293879Y663619D01*
X1293754Y663911D01*
X1293712Y664286D01*
X1293795Y664661D01*
X1293962Y664953D01*
X1294254Y665161D01*
X1294587Y665203D01*
X1294920Y665119D01*
X1295129Y664911D01*
X1295295Y664619D01*
X1295337Y664328D01*
X1295295Y664036D01*
X1295129Y663661D01*
X1296212Y663786D01*
Y664911D01*
G01X1293712Y667303D02*
X1294254Y667386D01*
X1294712Y667511D01*
X1295129Y667678D01*
X1295587Y667886D01*
X1296212Y668219D01*
Y666553D01*
G01X1293712Y670403D02*
X1294254Y670486D01*
X1294712Y670611D01*
X1295129Y670778D01*
X1295587Y670986D01*
X1296212Y671319D01*
Y669653D01*
G01X1304128Y675167D02*
X1300128D01*
Y682567D01*
G01X1298912Y660153D02*
X1301412D01*
Y661194D01*
X1301287Y661528D01*
X1301120Y661736D01*
X1300787Y661819D01*
X1300454Y661736D01*
X1300245Y661486D01*
X1300120Y661194D01*
Y660153D01*
G01Y661194D02*
X1298912Y661819D01*
G01X1299287Y663169D02*
X1299079Y663419D01*
X1298954Y663711D01*
X1298912Y664086D01*
X1298995Y664461D01*
X1299162Y664753D01*
X1299454Y664961D01*
X1299787Y665003D01*
X1300120Y664919D01*
X1300329Y664711D01*
X1300495Y664419D01*
X1300537Y664128D01*
X1300495Y663836D01*
X1300329Y663461D01*
X1301412Y663586D01*
Y664711D01*
G01X1298912Y667103D02*
X1299454Y667186D01*
X1299912Y667311D01*
X1300329Y667478D01*
X1300787Y667686D01*
X1301412Y668019D01*
Y666353D01*
G01X1299954Y669494D02*
X1300245Y669786D01*
X1300412Y670036D01*
X1300495Y670369D01*
X1300412Y670661D01*
X1300245Y670869D01*
X1299995Y671036D01*
X1299704Y671078D01*
X1299454Y671036D01*
X1299204Y670869D01*
X1298995Y670619D01*
X1298912Y670328D01*
X1298995Y669994D01*
X1299245Y669703D01*
X1299620Y669536D01*
X1300037Y669494D01*
X1300579Y669578D01*
X1300870Y669703D01*
X1301162Y669911D01*
X1301370Y670203D01*
X1301412Y670494D01*
X1301329Y670786D01*
X1301120Y670994D01*
G01X1308128Y675167D02*
X1304128D01*
Y682567D01*
G01X1302912Y658603D02*
X1305412D01*
Y659644D01*
X1305287Y659978D01*
X1305120Y660186D01*
X1304787Y660269D01*
X1304454Y660186D01*
X1304245Y659936D01*
X1304120Y659644D01*
Y658603D01*
G01Y659644D02*
X1302912Y660269D01*
G01Y663036D02*
X1305412D01*
X1303620Y661494D01*
Y663578D01*
G01X1302912Y665636D02*
X1305412D01*
X1304912Y665136D01*
G01X1302912D02*
Y666136D01*
G01X1303954Y667944D02*
X1304245Y668236D01*
X1304412Y668486D01*
X1304495Y668819D01*
X1304412Y669111D01*
X1304245Y669319D01*
X1303995Y669486D01*
X1303704Y669528D01*
X1303454Y669486D01*
X1303204Y669319D01*
X1302995Y669069D01*
X1302912Y668778D01*
X1302995Y668444D01*
X1303245Y668153D01*
X1303620Y667986D01*
X1304037Y667944D01*
X1304579Y668028D01*
X1304870Y668153D01*
X1305162Y668361D01*
X1305370Y668653D01*
X1305412Y668944D01*
X1305329Y669236D01*
X1305120Y669444D01*
G01X1303412Y670919D02*
X1303120Y671169D01*
X1302954Y671503D01*
X1302912Y671878D01*
X1302954Y672211D01*
X1303162Y672544D01*
X1303412Y672753D01*
X1303662Y672794D01*
X1303954Y672711D01*
X1304162Y672419D01*
X1304245Y672128D01*
Y671753D01*
G01Y672128D02*
X1304370Y672378D01*
X1304579Y672586D01*
X1304829Y672669D01*
X1305079Y672586D01*
X1305287Y672378D01*
X1305412Y672003D01*
X1305370Y671628D01*
X1305204Y671253D01*
G01X1308128Y682567D02*
X1312128D01*
Y675167D01*
G01X1306912Y658603D02*
X1309412D01*
Y659644D01*
X1309287Y659978D01*
X1309120Y660186D01*
X1308787Y660269D01*
X1308454Y660186D01*
X1308245Y659936D01*
X1308120Y659644D01*
Y658603D01*
G01Y659644D02*
X1306912Y660269D01*
G01Y663036D02*
X1309412D01*
X1307620Y661494D01*
Y663578D01*
G01X1306912Y665636D02*
X1309412D01*
X1308912Y665136D01*
G01X1306912D02*
Y666136D01*
G01X1307287Y667819D02*
X1307079Y668069D01*
X1306954Y668361D01*
X1306912Y668736D01*
X1306995Y669111D01*
X1307162Y669403D01*
X1307454Y669611D01*
X1307787Y669653D01*
X1308120Y669569D01*
X1308329Y669361D01*
X1308495Y669069D01*
X1308537Y668778D01*
X1308495Y668486D01*
X1308329Y668111D01*
X1309412Y668236D01*
Y669361D01*
G01X1306912Y671836D02*
X1309412D01*
X1308912Y671336D01*
G01X1306912D02*
Y672336D01*
G01X1287108Y703139D02*
X1285316D01*
X1284941Y703306D01*
X1284691Y703639D01*
X1284608Y704056D01*
X1284691Y704473D01*
X1284941Y704806D01*
X1285316Y704973D01*
X1287108D01*
G01X1285650Y706364D02*
X1285941Y706656D01*
X1286108Y706906D01*
X1286191Y707239D01*
X1286108Y707531D01*
X1285941Y707739D01*
X1285691Y707906D01*
X1285400Y707948D01*
X1285150Y707906D01*
X1284900Y707739D01*
X1284691Y707489D01*
X1284608Y707198D01*
X1284691Y706864D01*
X1284941Y706573D01*
X1285316Y706406D01*
X1285733Y706364D01*
X1286275Y706448D01*
X1286566Y706573D01*
X1286858Y706781D01*
X1287066Y707073D01*
X1287108Y707364D01*
X1287025Y707656D01*
X1286816Y707864D01*
G01X1284608Y710256D02*
X1284650Y710548D01*
X1284775Y710881D01*
X1284983Y711089D01*
X1285275Y711173D01*
X1285566Y711089D01*
X1285816Y710839D01*
X1285941Y710464D01*
Y710048D01*
X1286025Y709798D01*
X1286233Y709589D01*
X1286525Y709506D01*
X1286816Y709631D01*
X1287025Y709923D01*
X1287108Y710256D01*
X1287025Y710589D01*
X1286816Y710881D01*
X1286525Y711006D01*
X1286233Y710923D01*
X1286025Y710714D01*
X1285941Y710464D01*
Y710048D01*
X1285816Y709673D01*
X1285566Y709423D01*
X1285275Y709339D01*
X1284983Y709423D01*
X1284775Y709631D01*
X1284650Y709964D01*
X1284608Y710256D01*
G01X1305222Y696769D02*
X1315222D01*
G01X1305222Y710169D02*
Y696769D01*
G01X1315222Y710169D02*
X1305222D01*
G01X1294630Y703583D02*
X1292838D01*
X1292463Y703750D01*
X1292213Y704083D01*
X1292130Y704500D01*
X1292213Y704917D01*
X1292463Y705250D01*
X1292838Y705417D01*
X1294630D01*
G01X1292130Y707517D02*
X1292672Y707600D01*
X1293130Y707725D01*
X1293547Y707892D01*
X1294005Y708100D01*
X1294630Y708433D01*
Y706767D01*
G01X1292630Y709783D02*
X1292338Y710033D01*
X1292172Y710367D01*
X1292130Y710742D01*
X1292172Y711075D01*
X1292380Y711408D01*
X1292630Y711617D01*
X1292880Y711658D01*
X1293172Y711575D01*
X1293380Y711283D01*
X1293463Y710992D01*
Y710617D01*
G01Y710992D02*
X1293588Y711242D01*
X1293797Y711450D01*
X1294047Y711533D01*
X1294297Y711450D01*
X1294505Y711242D01*
X1294630Y710867D01*
X1294588Y710492D01*
X1294422Y710117D01*
G01X1280273Y702912D02*
X1282773D01*
Y703953D01*
X1282648Y704287D01*
X1282481Y704495D01*
X1282148Y704578D01*
X1281815Y704495D01*
X1281606Y704245D01*
X1281481Y703953D01*
Y702912D01*
G01Y703953D02*
X1280273Y704578D01*
G01Y706845D02*
X1282773D01*
X1282273Y706345D01*
G01X1280273D02*
Y707345D01*
G01Y710445D02*
X1282773D01*
X1280981Y708903D01*
Y710987D01*
G01X1280273Y713045D02*
X1282773D01*
X1282273Y712545D01*
G01X1280273D02*
Y713545D01*
G01X1300000Y708700D02*
X1304000D01*
Y701300D01*
G01X1288413Y703354D02*
X1290913D01*
Y704395D01*
X1290788Y704729D01*
X1290621Y704937D01*
X1290288Y705020D01*
X1289955Y704937D01*
X1289746Y704687D01*
X1289621Y704395D01*
Y703354D01*
G01Y704395D02*
X1288413Y705020D01*
G01X1290496Y706495D02*
X1290746Y706745D01*
X1290871Y707037D01*
X1290913Y707370D01*
X1290830Y707787D01*
X1290621Y708079D01*
X1290371Y708162D01*
X1290121Y708120D01*
X1289913Y707954D01*
X1289496Y707120D01*
X1289205Y706745D01*
X1288788Y706495D01*
X1288413Y706412D01*
Y708162D01*
G01X1290913Y710387D02*
X1290830Y710054D01*
X1290621Y709804D01*
X1290371Y709637D01*
X1290038Y709512D01*
X1289663Y709470D01*
X1289288Y709512D01*
X1288955Y709637D01*
X1288705Y709804D01*
X1288496Y710054D01*
X1288413Y710387D01*
X1288496Y710720D01*
X1288705Y710970D01*
X1288955Y711137D01*
X1289288Y711262D01*
X1289663Y711304D01*
X1290038Y711262D01*
X1290371Y711137D01*
X1290621Y710970D01*
X1290830Y710720D01*
X1290913Y710387D01*
G01X1288705Y712779D02*
X1288496Y713070D01*
X1288413Y713404D01*
X1288496Y713737D01*
X1288746Y714029D01*
X1289121Y714237D01*
X1289496Y714320D01*
X1289955D01*
X1290330Y714237D01*
X1290663Y714029D01*
X1290830Y713779D01*
X1290913Y713487D01*
X1290830Y713154D01*
X1290663Y712904D01*
X1290413Y712737D01*
X1290080Y712654D01*
X1289788Y712737D01*
X1289496Y712945D01*
X1289330Y713195D01*
X1289288Y713487D01*
X1289371Y713820D01*
X1289580Y714070D01*
X1289955Y714320D01*
G01X1296000Y712700D02*
X1300000D01*
Y705300D01*
G01X1298028Y686892D02*
X1300528D01*
Y687933D01*
X1300403Y688267D01*
X1300236Y688475D01*
X1299903Y688558D01*
X1299570Y688475D01*
X1299361Y688225D01*
X1299236Y687933D01*
Y686892D01*
G01Y687933D02*
X1298028Y688558D01*
G01X1298528Y689908D02*
X1298236Y690158D01*
X1298070Y690492D01*
X1298028Y690867D01*
X1298070Y691200D01*
X1298278Y691533D01*
X1298528Y691742D01*
X1298778Y691783D01*
X1299070Y691700D01*
X1299278Y691408D01*
X1299361Y691117D01*
Y690742D01*
G01Y691117D02*
X1299486Y691367D01*
X1299695Y691575D01*
X1299945Y691658D01*
X1300195Y691575D01*
X1300403Y691367D01*
X1300528Y690992D01*
X1300486Y690617D01*
X1300320Y690242D01*
G01X1300111Y693133D02*
X1300361Y693383D01*
X1300486Y693675D01*
X1300528Y694008D01*
X1300445Y694425D01*
X1300236Y694717D01*
X1299986Y694800D01*
X1299736Y694758D01*
X1299528Y694592D01*
X1299111Y693758D01*
X1298820Y693383D01*
X1298403Y693133D01*
X1298028Y693050D01*
Y694800D01*
G01Y697025D02*
X1300528D01*
X1300028Y696525D01*
G01X1298028D02*
Y697525D01*
G01X1298403Y699208D02*
X1298195Y699458D01*
X1298070Y699750D01*
X1298028Y700125D01*
X1298111Y700500D01*
X1298278Y700792D01*
X1298570Y701000D01*
X1298903Y701042D01*
X1299236Y700958D01*
X1299445Y700750D01*
X1299611Y700458D01*
X1299653Y700167D01*
X1299611Y699875D01*
X1299445Y699500D01*
X1300528Y699625D01*
Y700750D01*
G01X1310900Y695600D02*
X1314900D01*
Y688200D01*
G01X1312128Y682567D02*
X1316128D01*
Y675167D01*
G01X1295809Y688907D02*
X1295934Y688657D01*
X1296017Y688365D01*
Y688032D01*
X1295892Y687657D01*
X1295684Y687365D01*
X1295434Y687157D01*
X1295017Y686990D01*
X1294642Y686948D01*
X1294267Y687032D01*
X1294017Y687157D01*
X1293767Y687407D01*
X1293600Y687698D01*
X1293517Y687990D01*
Y688282D01*
X1293600Y688573D01*
X1293725Y688823D01*
X1293892Y689032D01*
G01X1294017Y690173D02*
X1293725Y690423D01*
X1293559Y690757D01*
X1293517Y691132D01*
X1293559Y691465D01*
X1293767Y691798D01*
X1294017Y692007D01*
X1294267Y692048D01*
X1294559Y691965D01*
X1294767Y691673D01*
X1294850Y691382D01*
Y691007D01*
G01Y691382D02*
X1294975Y691632D01*
X1295184Y691840D01*
X1295434Y691923D01*
X1295684Y691840D01*
X1295892Y691632D01*
X1296017Y691257D01*
X1295975Y690882D01*
X1295809Y690507D01*
G01X1295600Y693398D02*
X1295850Y693648D01*
X1295975Y693940D01*
X1296017Y694273D01*
X1295934Y694690D01*
X1295725Y694982D01*
X1295475Y695065D01*
X1295225Y695023D01*
X1295017Y694857D01*
X1294600Y694023D01*
X1294309Y693648D01*
X1293892Y693398D01*
X1293517Y693315D01*
Y695065D01*
G01Y697290D02*
X1296017D01*
X1295517Y696790D01*
G01X1293517D02*
Y697790D01*
G01Y700890D02*
X1296017D01*
X1294225Y699348D01*
Y701432D01*
G01X1300306Y716942D02*
X1302806D01*
Y717983D01*
X1302681Y718317D01*
X1302514Y718525D01*
X1302181Y718608D01*
X1301848Y718525D01*
X1301639Y718275D01*
X1301514Y717983D01*
Y716942D01*
G01Y717983D02*
X1300306Y718608D01*
G01X1300806Y719958D02*
X1300514Y720208D01*
X1300348Y720542D01*
X1300306Y720917D01*
X1300348Y721250D01*
X1300556Y721583D01*
X1300806Y721792D01*
X1301056Y721833D01*
X1301348Y721750D01*
X1301556Y721458D01*
X1301639Y721167D01*
Y720792D01*
G01Y721167D02*
X1301764Y721417D01*
X1301973Y721625D01*
X1302223Y721708D01*
X1302473Y721625D01*
X1302681Y721417D01*
X1302806Y721042D01*
X1302764Y720667D01*
X1302598Y720292D01*
G01X1302389Y723183D02*
X1302639Y723433D01*
X1302764Y723725D01*
X1302806Y724058D01*
X1302723Y724475D01*
X1302514Y724767D01*
X1302264Y724850D01*
X1302014Y724808D01*
X1301806Y724642D01*
X1301389Y723808D01*
X1301098Y723433D01*
X1300681Y723183D01*
X1300306Y723100D01*
Y724850D01*
G01Y727075D02*
X1302806D01*
X1302306Y726575D01*
G01X1300306D02*
Y727575D01*
G01X1300806Y729258D02*
X1300514Y729508D01*
X1300348Y729842D01*
X1300306Y730217D01*
X1300348Y730550D01*
X1300556Y730883D01*
X1300806Y731092D01*
X1301056Y731133D01*
X1301348Y731050D01*
X1301556Y730758D01*
X1301639Y730467D01*
Y730092D01*
G01Y730467D02*
X1301764Y730717D01*
X1301973Y730925D01*
X1302223Y731008D01*
X1302473Y730925D01*
X1302681Y730717D01*
X1302806Y730342D01*
X1302764Y729967D01*
X1302598Y729592D01*
G01X1308900Y719100D02*
X1312900D01*
Y711700D01*
G01X1303422Y737371D02*
X1305922D01*
Y738412D01*
X1305797Y738746D01*
X1305630Y738954D01*
X1305297Y739037D01*
X1304964Y738954D01*
X1304755Y738704D01*
X1304630Y738412D01*
Y737371D01*
G01Y738412D02*
X1303422Y739037D01*
G01X1303797Y740387D02*
X1303589Y740637D01*
X1303464Y740929D01*
X1303422Y741304D01*
X1303505Y741679D01*
X1303672Y741971D01*
X1303964Y742179D01*
X1304297Y742221D01*
X1304630Y742137D01*
X1304839Y741929D01*
X1305005Y741637D01*
X1305047Y741346D01*
X1305005Y741054D01*
X1304839Y740679D01*
X1305922Y740804D01*
Y741929D01*
G01X1303422Y744321D02*
X1303964Y744404D01*
X1304422Y744529D01*
X1304839Y744696D01*
X1305297Y744904D01*
X1305922Y745237D01*
Y743571D01*
G01X1303922Y746587D02*
X1303630Y746837D01*
X1303464Y747171D01*
X1303422Y747546D01*
X1303464Y747879D01*
X1303672Y748212D01*
X1303922Y748421D01*
X1304172Y748462D01*
X1304464Y748379D01*
X1304672Y748087D01*
X1304755Y747796D01*
Y747421D01*
G01Y747796D02*
X1304880Y748046D01*
X1305089Y748254D01*
X1305339Y748337D01*
X1305589Y748254D01*
X1305797Y748046D01*
X1305922Y747671D01*
X1305880Y747296D01*
X1305714Y746921D01*
G01X1308100Y731600D02*
X1312100D01*
Y724200D01*
G01X1307950Y735788D02*
X1310450D01*
Y736829D01*
X1310325Y737163D01*
X1310158Y737371D01*
X1309825Y737454D01*
X1309492Y737371D01*
X1309283Y737121D01*
X1309158Y736829D01*
Y735788D01*
G01Y736829D02*
X1307950Y737454D01*
G01Y740221D02*
X1310450D01*
X1308658Y738679D01*
Y740763D01*
G01X1307950Y742821D02*
X1310450D01*
X1309950Y742321D01*
G01X1307950D02*
Y743321D01*
G01X1308992Y745129D02*
X1309283Y745421D01*
X1309450Y745671D01*
X1309533Y746004D01*
X1309450Y746296D01*
X1309283Y746504D01*
X1309033Y746671D01*
X1308742Y746713D01*
X1308492Y746671D01*
X1308242Y746504D01*
X1308033Y746254D01*
X1307950Y745963D01*
X1308033Y745629D01*
X1308283Y745338D01*
X1308658Y745171D01*
X1309075Y745129D01*
X1309617Y745213D01*
X1309908Y745338D01*
X1310200Y745546D01*
X1310408Y745838D01*
X1310450Y746129D01*
X1310367Y746421D01*
X1310158Y746629D01*
G01X1308325Y748104D02*
X1308117Y748354D01*
X1307992Y748646D01*
X1307950Y749021D01*
X1308033Y749396D01*
X1308200Y749688D01*
X1308492Y749896D01*
X1308825Y749938D01*
X1309158Y749854D01*
X1309367Y749646D01*
X1309533Y749354D01*
X1309575Y749063D01*
X1309533Y748771D01*
X1309367Y748396D01*
X1310450Y748521D01*
Y749646D01*
G01X1298771Y720242D02*
X1298896Y719992D01*
X1298979Y719700D01*
Y719367D01*
X1298854Y718992D01*
X1298646Y718700D01*
X1298396Y718492D01*
X1297979Y718325D01*
X1297604Y718283D01*
X1297229Y718367D01*
X1296979Y718492D01*
X1296729Y718742D01*
X1296562Y719033D01*
X1296479Y719325D01*
Y719617D01*
X1296562Y719908D01*
X1296687Y720158D01*
X1296854Y720367D01*
G01X1296479Y722425D02*
X1296521Y722717D01*
X1296646Y723050D01*
X1296854Y723258D01*
X1297146Y723342D01*
X1297437Y723258D01*
X1297687Y723008D01*
X1297812Y722633D01*
Y722217D01*
X1297896Y721967D01*
X1298104Y721758D01*
X1298396Y721675D01*
X1298687Y721800D01*
X1298896Y722092D01*
X1298979Y722425D01*
X1298896Y722758D01*
X1298687Y723050D01*
X1298396Y723175D01*
X1298104Y723092D01*
X1297896Y722883D01*
X1297812Y722633D01*
Y722217D01*
X1297687Y721842D01*
X1297437Y721592D01*
X1297146Y721508D01*
X1296854Y721592D01*
X1296646Y721800D01*
X1296521Y722133D01*
X1296479Y722425D01*
G01X1298979Y725525D02*
X1298896Y725192D01*
X1298687Y724942D01*
X1298437Y724775D01*
X1298104Y724650D01*
X1297729Y724608D01*
X1297354Y724650D01*
X1297021Y724775D01*
X1296771Y724942D01*
X1296562Y725192D01*
X1296479Y725525D01*
X1296562Y725858D01*
X1296771Y726108D01*
X1297021Y726275D01*
X1297354Y726400D01*
X1297729Y726442D01*
X1298104Y726400D01*
X1298437Y726275D01*
X1298687Y726108D01*
X1298896Y725858D01*
X1298979Y725525D01*
G01X1296771Y727917D02*
X1296562Y728208D01*
X1296479Y728542D01*
X1296562Y728875D01*
X1296812Y729167D01*
X1297187Y729375D01*
X1297562Y729458D01*
X1298021D01*
X1298396Y729375D01*
X1298729Y729167D01*
X1298896Y728917D01*
X1298979Y728625D01*
X1298896Y728292D01*
X1298729Y728042D01*
X1298479Y727875D01*
X1298146Y727792D01*
X1297854Y727875D01*
X1297562Y728083D01*
X1297396Y728333D01*
X1297354Y728625D01*
X1297437Y728958D01*
X1297646Y729208D01*
X1298021Y729458D01*
G01X1296979Y730808D02*
X1296687Y731058D01*
X1296521Y731392D01*
X1296479Y731767D01*
X1296521Y732100D01*
X1296729Y732433D01*
X1296979Y732642D01*
X1297229Y732683D01*
X1297521Y732600D01*
X1297729Y732308D01*
X1297812Y732017D01*
Y731642D01*
G01Y732017D02*
X1297937Y732267D01*
X1298146Y732475D01*
X1298396Y732558D01*
X1298646Y732475D01*
X1298854Y732267D01*
X1298979Y731892D01*
X1298937Y731517D01*
X1298771Y731142D01*
G01X1316140Y818934D02*
X1316390Y819059D01*
X1316682Y819142D01*
X1317015D01*
X1317390Y819017D01*
X1317682Y818809D01*
X1317890Y818559D01*
X1318057Y818142D01*
X1318099Y817767D01*
X1318015Y817392D01*
X1317890Y817142D01*
X1317640Y816892D01*
X1317349Y816725D01*
X1317057Y816642D01*
X1316765D01*
X1316474Y816725D01*
X1316224Y816850D01*
X1316015Y817017D01*
G01X1313457Y816642D02*
Y819142D01*
X1314999Y817350D01*
X1312915D01*
G01X1310857Y816642D02*
Y819142D01*
X1311357Y818642D01*
G01Y816642D02*
X1310357D01*
G01X1308549Y817684D02*
X1308257Y817975D01*
X1308007Y818142D01*
X1307674Y818225D01*
X1307382Y818142D01*
X1307174Y817975D01*
X1307007Y817725D01*
X1306965Y817434D01*
X1307007Y817184D01*
X1307174Y816934D01*
X1307424Y816725D01*
X1307715Y816642D01*
X1308049Y816725D01*
X1308340Y816975D01*
X1308507Y817350D01*
X1308549Y817767D01*
X1308465Y818309D01*
X1308340Y818600D01*
X1308132Y818892D01*
X1307840Y819100D01*
X1307549Y819142D01*
X1307257Y819059D01*
X1307049Y818850D01*
G01X1304657Y819142D02*
X1304990Y819059D01*
X1305240Y818850D01*
X1305407Y818600D01*
X1305532Y818267D01*
X1305574Y817892D01*
X1305532Y817517D01*
X1305407Y817184D01*
X1305240Y816934D01*
X1304990Y816725D01*
X1304657Y816642D01*
X1304324Y816725D01*
X1304074Y816934D01*
X1303907Y817184D01*
X1303782Y817517D01*
X1303740Y817892D01*
X1303782Y818267D01*
X1303907Y818600D01*
X1304074Y818850D01*
X1304324Y819059D01*
X1304657Y819142D01*
G01X1348033Y228300D02*
Y230800D01*
X1347033D01*
X1346700Y230675D01*
X1346450Y230383D01*
X1346367Y230050D01*
X1346450Y229717D01*
X1346658Y229467D01*
X1347033Y229342D01*
X1348033D01*
G01X1343183Y230592D02*
X1343433Y230717D01*
X1343725Y230800D01*
X1344058D01*
X1344433Y230675D01*
X1344725Y230467D01*
X1344933Y230217D01*
X1345100Y229800D01*
X1345142Y229425D01*
X1345058Y229050D01*
X1344933Y228800D01*
X1344683Y228550D01*
X1344392Y228383D01*
X1344100Y228300D01*
X1343808D01*
X1343517Y228383D01*
X1343267Y228508D01*
X1343058Y228675D01*
G01X1341000Y228300D02*
Y230800D01*
X1341500Y230300D01*
G01Y228300D02*
X1340500D01*
G01X1337983D02*
X1337900Y228842D01*
X1337775Y229300D01*
X1337608Y229717D01*
X1337400Y230175D01*
X1337067Y230800D01*
X1338733D01*
G01X1334800D02*
X1335133Y230717D01*
X1335383Y230508D01*
X1335550Y230258D01*
X1335675Y229925D01*
X1335717Y229550D01*
X1335675Y229175D01*
X1335550Y228842D01*
X1335383Y228592D01*
X1335133Y228383D01*
X1334800Y228300D01*
X1334467Y228383D01*
X1334217Y228592D01*
X1334050Y228842D01*
X1333925Y229175D01*
X1333883Y229550D01*
X1333925Y229925D01*
X1334050Y230258D01*
X1334217Y230508D01*
X1334467Y230717D01*
X1334800Y230800D01*
G01X1348033Y232100D02*
Y234600D01*
X1347033D01*
X1346700Y234475D01*
X1346450Y234183D01*
X1346367Y233850D01*
X1346450Y233517D01*
X1346658Y233267D01*
X1347033Y233142D01*
X1348033D01*
G01X1343183Y234392D02*
X1343433Y234517D01*
X1343725Y234600D01*
X1344058D01*
X1344433Y234475D01*
X1344725Y234267D01*
X1344933Y234017D01*
X1345100Y233600D01*
X1345142Y233225D01*
X1345058Y232850D01*
X1344933Y232600D01*
X1344683Y232350D01*
X1344392Y232183D01*
X1344100Y232100D01*
X1343808D01*
X1343517Y232183D01*
X1343267Y232308D01*
X1343058Y232475D01*
G01X1341000Y232100D02*
Y234600D01*
X1341500Y234100D01*
G01Y232100D02*
X1340500D01*
G01X1337983D02*
X1337900Y232642D01*
X1337775Y233100D01*
X1337608Y233517D01*
X1337400Y233975D01*
X1337067Y234600D01*
X1338733D01*
G01X1334300Y232100D02*
Y234600D01*
X1335842Y232808D01*
X1333758D01*
G01X1321700Y247000D02*
X1313000D01*
G01X1321700Y254000D02*
Y247000D01*
G01X1315300Y254000D02*
X1321700D01*
G01X1359495Y253687D02*
Y256187D01*
X1358495D01*
X1358162Y256062D01*
X1357912Y255770D01*
X1357829Y255437D01*
X1357912Y255104D01*
X1358120Y254854D01*
X1358495Y254729D01*
X1359495D01*
G01X1356395Y253687D02*
Y256187D01*
X1355354D01*
X1355020Y256062D01*
X1354812Y255895D01*
X1354729Y255562D01*
X1354812Y255229D01*
X1355062Y255020D01*
X1355354Y254895D01*
X1356395D01*
G01X1355354D02*
X1354729Y253687D01*
G01X1352462D02*
Y256187D01*
X1352962Y255687D01*
G01Y253687D02*
X1351962D01*
G01X1350279Y254062D02*
X1350029Y253854D01*
X1349737Y253729D01*
X1349362Y253687D01*
X1348987Y253770D01*
X1348695Y253937D01*
X1348487Y254229D01*
X1348445Y254562D01*
X1348529Y254895D01*
X1348737Y255104D01*
X1349029Y255270D01*
X1349320Y255312D01*
X1349612Y255270D01*
X1349987Y255104D01*
X1349862Y256187D01*
X1348737D01*
G01X1346262D02*
X1346595Y256104D01*
X1346845Y255895D01*
X1347012Y255645D01*
X1347137Y255312D01*
X1347179Y254937D01*
X1347137Y254562D01*
X1347012Y254229D01*
X1346845Y253979D01*
X1346595Y253770D01*
X1346262Y253687D01*
X1345929Y253770D01*
X1345679Y253979D01*
X1345512Y254229D01*
X1345387Y254562D01*
X1345345Y254937D01*
X1345387Y255312D01*
X1345512Y255645D01*
X1345679Y255895D01*
X1345929Y256104D01*
X1346262Y256187D01*
G01X1336789Y659334D02*
X1339289D01*
Y660375D01*
X1339164Y660709D01*
X1338997Y660917D01*
X1338664Y661000D01*
X1338331Y660917D01*
X1338122Y660667D01*
X1337997Y660375D01*
Y659334D01*
G01Y660375D02*
X1336789Y661000D01*
G01Y663767D02*
X1339289D01*
X1337497Y662225D01*
Y664309D01*
G01X1336789Y666367D02*
X1339289D01*
X1338789Y665867D01*
G01X1336789D02*
Y666867D01*
G01X1337831Y668675D02*
X1338122Y668967D01*
X1338289Y669217D01*
X1338372Y669550D01*
X1338289Y669842D01*
X1338122Y670050D01*
X1337872Y670217D01*
X1337581Y670259D01*
X1337331Y670217D01*
X1337081Y670050D01*
X1336872Y669800D01*
X1336789Y669509D01*
X1336872Y669175D01*
X1337122Y668884D01*
X1337497Y668717D01*
X1337914Y668675D01*
X1338456Y668759D01*
X1338747Y668884D01*
X1339039Y669092D01*
X1339247Y669384D01*
X1339289Y669675D01*
X1339206Y669967D01*
X1338997Y670175D01*
G01X1336789Y672567D02*
X1339289D01*
X1338789Y672067D01*
G01X1336789D02*
Y673067D01*
G01X1336128Y682567D02*
X1340128D01*
Y675167D01*
G01X1321712Y658803D02*
X1324212D01*
Y659844D01*
X1324087Y660178D01*
X1323920Y660386D01*
X1323587Y660469D01*
X1323254Y660386D01*
X1323045Y660136D01*
X1322920Y659844D01*
Y658803D01*
G01Y659844D02*
X1321712Y660469D01*
G01Y663236D02*
X1324212D01*
X1322420Y661694D01*
Y663778D01*
G01X1321712Y665836D02*
X1324212D01*
X1323712Y665336D01*
G01X1321712D02*
Y666336D01*
G01X1322754Y668144D02*
X1323045Y668436D01*
X1323212Y668686D01*
X1323295Y669019D01*
X1323212Y669311D01*
X1323045Y669519D01*
X1322795Y669686D01*
X1322504Y669728D01*
X1322254Y669686D01*
X1322004Y669519D01*
X1321795Y669269D01*
X1321712Y668978D01*
X1321795Y668644D01*
X1322045Y668353D01*
X1322420Y668186D01*
X1322837Y668144D01*
X1323379Y668228D01*
X1323670Y668353D01*
X1323962Y668561D01*
X1324170Y668853D01*
X1324212Y669144D01*
X1324129Y669436D01*
X1323920Y669644D01*
G01X1324212Y672036D02*
X1324129Y671703D01*
X1323920Y671453D01*
X1323670Y671286D01*
X1323337Y671161D01*
X1322962Y671119D01*
X1322587Y671161D01*
X1322254Y671286D01*
X1322004Y671453D01*
X1321795Y671703D01*
X1321712Y672036D01*
X1321795Y672369D01*
X1322004Y672619D01*
X1322254Y672786D01*
X1322587Y672911D01*
X1322962Y672953D01*
X1323337Y672911D01*
X1323670Y672786D01*
X1323920Y672619D01*
X1324129Y672369D01*
X1324212Y672036D01*
G01X1328128Y682567D02*
X1332128D01*
Y675167D01*
G01X1317712Y658803D02*
X1320212D01*
Y659844D01*
X1320087Y660178D01*
X1319920Y660386D01*
X1319587Y660469D01*
X1319254Y660386D01*
X1319045Y660136D01*
X1318920Y659844D01*
Y658803D01*
G01Y659844D02*
X1317712Y660469D01*
G01Y663236D02*
X1320212D01*
X1318420Y661694D01*
Y663778D01*
G01X1317712Y665836D02*
X1320212D01*
X1319712Y665336D01*
G01X1317712D02*
Y666336D01*
G01X1318087Y668019D02*
X1317879Y668269D01*
X1317754Y668561D01*
X1317712Y668936D01*
X1317795Y669311D01*
X1317962Y669603D01*
X1318254Y669811D01*
X1318587Y669853D01*
X1318920Y669769D01*
X1319129Y669561D01*
X1319295Y669269D01*
X1319337Y668978D01*
X1319295Y668686D01*
X1319129Y668311D01*
X1320212Y668436D01*
Y669561D01*
G01X1318754Y671244D02*
X1319045Y671536D01*
X1319212Y671786D01*
X1319295Y672119D01*
X1319212Y672411D01*
X1319045Y672619D01*
X1318795Y672786D01*
X1318504Y672828D01*
X1318254Y672786D01*
X1318004Y672619D01*
X1317795Y672369D01*
X1317712Y672078D01*
X1317795Y671744D01*
X1318045Y671453D01*
X1318420Y671286D01*
X1318837Y671244D01*
X1319379Y671328D01*
X1319670Y671453D01*
X1319962Y671661D01*
X1320170Y671953D01*
X1320212Y672244D01*
X1320129Y672536D01*
X1319920Y672744D01*
G01X1324128Y682567D02*
X1328128D01*
Y675167D01*
G01X1313712Y658803D02*
X1316212D01*
Y659844D01*
X1316087Y660178D01*
X1315920Y660386D01*
X1315587Y660469D01*
X1315254Y660386D01*
X1315045Y660136D01*
X1314920Y659844D01*
Y658803D01*
G01Y659844D02*
X1313712Y660469D01*
G01Y663236D02*
X1316212D01*
X1314420Y661694D01*
Y663778D01*
G01X1313712Y665836D02*
X1316212D01*
X1315712Y665336D01*
G01X1313712D02*
Y666336D01*
G01X1314087Y668019D02*
X1313879Y668269D01*
X1313754Y668561D01*
X1313712Y668936D01*
X1313795Y669311D01*
X1313962Y669603D01*
X1314254Y669811D01*
X1314587Y669853D01*
X1314920Y669769D01*
X1315129Y669561D01*
X1315295Y669269D01*
X1315337Y668978D01*
X1315295Y668686D01*
X1315129Y668311D01*
X1316212Y668436D01*
Y669561D01*
G01X1314087Y671119D02*
X1313879Y671369D01*
X1313754Y671661D01*
X1313712Y672036D01*
X1313795Y672411D01*
X1313962Y672703D01*
X1314254Y672911D01*
X1314587Y672953D01*
X1314920Y672869D01*
X1315129Y672661D01*
X1315295Y672369D01*
X1315337Y672078D01*
X1315295Y671786D01*
X1315129Y671411D01*
X1316212Y671536D01*
Y672661D01*
G01X1320128Y682567D02*
X1324128D01*
Y675167D01*
G01X1315222Y696769D02*
Y710169D01*
G01X1339222Y697269D02*
X1349222D01*
G01X1339222Y710669D02*
Y697269D01*
G01X1349222Y710669D02*
X1339222D01*
G01X1332722Y697269D02*
Y710669D01*
G01X1322722Y697269D02*
X1332722D01*
G01X1322722Y710669D02*
Y697269D01*
G01X1332722Y710669D02*
X1322722D01*
G01X1317500Y711200D02*
X1321500D01*
Y703800D01*
G01X1334000Y707200D02*
X1338000D01*
Y699800D01*
G01X1327900Y719600D02*
X1331900D01*
Y712200D01*
G01X1323900Y719600D02*
X1327900D01*
Y712200D01*
G01X1328400Y695600D02*
X1332400D01*
Y688200D01*
G01X1338900Y719600D02*
X1342900D01*
Y712200D01*
G01X1344900Y695600D02*
X1348900D01*
Y688200D01*
G01X1346600Y721367D02*
X1349100D01*
Y722408D01*
X1348975Y722742D01*
X1348808Y722950D01*
X1348475Y723033D01*
X1348142Y722950D01*
X1347933Y722700D01*
X1347808Y722408D01*
Y721367D01*
G01Y722408D02*
X1346600Y723033D01*
G01X1347100Y724383D02*
X1346808Y724633D01*
X1346642Y724967D01*
X1346600Y725342D01*
X1346642Y725675D01*
X1346850Y726008D01*
X1347100Y726217D01*
X1347350Y726258D01*
X1347642Y726175D01*
X1347850Y725883D01*
X1347933Y725592D01*
Y725217D01*
G01Y725592D02*
X1348058Y725842D01*
X1348267Y726050D01*
X1348517Y726133D01*
X1348767Y726050D01*
X1348975Y725842D01*
X1349100Y725467D01*
X1349058Y725092D01*
X1348892Y724717D01*
G01X1348683Y727608D02*
X1348933Y727858D01*
X1349058Y728150D01*
X1349100Y728483D01*
X1349017Y728900D01*
X1348808Y729192D01*
X1348558Y729275D01*
X1348308Y729233D01*
X1348100Y729067D01*
X1347683Y728233D01*
X1347392Y727858D01*
X1346975Y727608D01*
X1346600Y727525D01*
Y729275D01*
G01X1348683Y730708D02*
X1348933Y730958D01*
X1349058Y731250D01*
X1349100Y731583D01*
X1349017Y732000D01*
X1348808Y732292D01*
X1348558Y732375D01*
X1348308Y732333D01*
X1348100Y732167D01*
X1347683Y731333D01*
X1347392Y730958D01*
X1346975Y730708D01*
X1346600Y730625D01*
Y732375D01*
G01X1346892Y733892D02*
X1346683Y734183D01*
X1346600Y734517D01*
X1346683Y734850D01*
X1346933Y735142D01*
X1347308Y735350D01*
X1347683Y735433D01*
X1348142D01*
X1348517Y735350D01*
X1348850Y735142D01*
X1349017Y734892D01*
X1349100Y734600D01*
X1349017Y734267D01*
X1348850Y734017D01*
X1348600Y733850D01*
X1348267Y733767D01*
X1347975Y733850D01*
X1347683Y734058D01*
X1347517Y734308D01*
X1347475Y734600D01*
X1347558Y734933D01*
X1347767Y735183D01*
X1348142Y735433D01*
G01X1342900Y719600D02*
X1346900D01*
Y712200D01*
G01X1316628Y724167D02*
X1312628D01*
Y731567D01*
G01X1315422Y734721D02*
X1317922D01*
Y735762D01*
X1317797Y736096D01*
X1317630Y736304D01*
X1317297Y736387D01*
X1316964Y736304D01*
X1316755Y736054D01*
X1316630Y735762D01*
Y734721D01*
G01Y735762D02*
X1315422Y736387D01*
G01Y739154D02*
X1317922D01*
X1316130Y737612D01*
Y739696D01*
G01X1315422Y741754D02*
X1317922D01*
X1317422Y741254D01*
G01X1315422D02*
Y742254D01*
G01X1315797Y743937D02*
X1315589Y744187D01*
X1315464Y744479D01*
X1315422Y744854D01*
X1315505Y745229D01*
X1315672Y745521D01*
X1315964Y745729D01*
X1316297Y745771D01*
X1316630Y745687D01*
X1316839Y745479D01*
X1317005Y745187D01*
X1317047Y744896D01*
X1317005Y744604D01*
X1316839Y744229D01*
X1317922Y744354D01*
Y745479D01*
G01X1315422Y748454D02*
X1317922D01*
X1316130Y746912D01*
Y748996D01*
G01X1327500Y724300D02*
X1323500D01*
Y731700D01*
G01X1323250Y735888D02*
X1325750D01*
Y736929D01*
X1325625Y737263D01*
X1325458Y737471D01*
X1325125Y737554D01*
X1324792Y737471D01*
X1324583Y737221D01*
X1324458Y736929D01*
Y735888D01*
G01Y736929D02*
X1323250Y737554D01*
G01Y740321D02*
X1325750D01*
X1323958Y738779D01*
Y740863D01*
G01X1323250Y742921D02*
X1325750D01*
X1325250Y742421D01*
G01X1323250D02*
Y743421D01*
G01X1323625Y745104D02*
X1323417Y745354D01*
X1323292Y745646D01*
X1323250Y746021D01*
X1323333Y746396D01*
X1323500Y746688D01*
X1323792Y746896D01*
X1324125Y746938D01*
X1324458Y746854D01*
X1324667Y746646D01*
X1324833Y746354D01*
X1324875Y746063D01*
X1324833Y745771D01*
X1324667Y745396D01*
X1325750Y745521D01*
Y746646D01*
G01X1325333Y748329D02*
X1325583Y748579D01*
X1325708Y748871D01*
X1325750Y749204D01*
X1325667Y749621D01*
X1325458Y749913D01*
X1325208Y749996D01*
X1324958Y749954D01*
X1324750Y749788D01*
X1324333Y748954D01*
X1324042Y748579D01*
X1323625Y748329D01*
X1323250Y748246D01*
Y749996D01*
G01X1336128Y724167D02*
X1332128D01*
Y731567D01*
G01X1327250Y735888D02*
X1329750D01*
Y736929D01*
X1329625Y737263D01*
X1329458Y737471D01*
X1329125Y737554D01*
X1328792Y737471D01*
X1328583Y737221D01*
X1328458Y736929D01*
Y735888D01*
G01Y736929D02*
X1327250Y737554D01*
G01Y740321D02*
X1329750D01*
X1327958Y738779D01*
Y740863D01*
G01X1327250Y742921D02*
X1329750D01*
X1329250Y742421D01*
G01X1327250D02*
Y743421D01*
G01X1327625Y745104D02*
X1327417Y745354D01*
X1327292Y745646D01*
X1327250Y746021D01*
X1327333Y746396D01*
X1327500Y746688D01*
X1327792Y746896D01*
X1328125Y746938D01*
X1328458Y746854D01*
X1328667Y746646D01*
X1328833Y746354D01*
X1328875Y746063D01*
X1328833Y745771D01*
X1328667Y745396D01*
X1329750Y745521D01*
Y746646D01*
G01Y749121D02*
X1329667Y748788D01*
X1329458Y748538D01*
X1329208Y748371D01*
X1328875Y748246D01*
X1328500Y748204D01*
X1328125Y748246D01*
X1327792Y748371D01*
X1327542Y748538D01*
X1327333Y748788D01*
X1327250Y749121D01*
X1327333Y749454D01*
X1327542Y749704D01*
X1327792Y749871D01*
X1328125Y749996D01*
X1328500Y750038D01*
X1328875Y749996D01*
X1329208Y749871D01*
X1329458Y749704D01*
X1329667Y749454D01*
X1329750Y749121D01*
G01X1340128Y724167D02*
X1336128D01*
Y731567D01*
G01X1369174Y185695D02*
Y172295D01*
G01X1379174D02*
Y185695D01*
G01X1369174Y172295D02*
X1379174D01*
G01X1376244Y163500D02*
Y166000D01*
X1375203D01*
X1374869Y165875D01*
X1374661Y165708D01*
X1374578Y165375D01*
X1374661Y165042D01*
X1374911Y164833D01*
X1375203Y164708D01*
X1376244D01*
G01X1375203D02*
X1374578Y163500D01*
G01X1372394D02*
X1372311Y164042D01*
X1372186Y164500D01*
X1372019Y164917D01*
X1371811Y165375D01*
X1371478Y166000D01*
X1373144D01*
G01X1369919Y163792D02*
X1369628Y163583D01*
X1369294Y163500D01*
X1368961Y163583D01*
X1368669Y163833D01*
X1368461Y164208D01*
X1368378Y164583D01*
Y165042D01*
X1368461Y165417D01*
X1368669Y165750D01*
X1368919Y165917D01*
X1369211Y166000D01*
X1369544Y165917D01*
X1369794Y165750D01*
X1369961Y165500D01*
X1370044Y165167D01*
X1369961Y164875D01*
X1369753Y164583D01*
X1369503Y164417D01*
X1369211Y164375D01*
X1368878Y164458D01*
X1368628Y164667D01*
X1368378Y165042D01*
G01X1366111Y166000D02*
X1366444Y165917D01*
X1366694Y165708D01*
X1366861Y165458D01*
X1366986Y165125D01*
X1367028Y164750D01*
X1366986Y164375D01*
X1366861Y164042D01*
X1366694Y163792D01*
X1366444Y163583D01*
X1366111Y163500D01*
X1365778Y163583D01*
X1365528Y163792D01*
X1365361Y164042D01*
X1365236Y164375D01*
X1365194Y164750D01*
X1365236Y165125D01*
X1365361Y165458D01*
X1365528Y165708D01*
X1365778Y165917D01*
X1366111Y166000D01*
G01X1363803Y164542D02*
X1363511Y164833D01*
X1363261Y165000D01*
X1362928Y165083D01*
X1362636Y165000D01*
X1362428Y164833D01*
X1362261Y164583D01*
X1362219Y164292D01*
X1362261Y164042D01*
X1362428Y163792D01*
X1362678Y163583D01*
X1362969Y163500D01*
X1363303Y163583D01*
X1363594Y163833D01*
X1363761Y164208D01*
X1363803Y164625D01*
X1363719Y165167D01*
X1363594Y165458D01*
X1363386Y165750D01*
X1363094Y165958D01*
X1362803Y166000D01*
X1362511Y165917D01*
X1362303Y165708D01*
G01X1372839Y167235D02*
Y171235D01*
X1380239D01*
G01X1366415Y181232D02*
Y179440D01*
X1366248Y179065D01*
X1365915Y178815D01*
X1365498Y178732D01*
X1365081Y178815D01*
X1364748Y179065D01*
X1364581Y179440D01*
Y181232D01*
G01X1361898Y178732D02*
Y181232D01*
X1363440Y179440D01*
X1361356D01*
G01X1359381Y178732D02*
X1359298Y179274D01*
X1359173Y179732D01*
X1359006Y180149D01*
X1358798Y180607D01*
X1358465Y181232D01*
X1360131D01*
G01X1379174Y185695D02*
X1369174D01*
G01X1347684Y257624D02*
X1350184D01*
Y258624D01*
X1350059Y258957D01*
X1349767Y259207D01*
X1349434Y259290D01*
X1349101Y259207D01*
X1348851Y258999D01*
X1348726Y258624D01*
Y257624D01*
G01X1349976Y262474D02*
X1350101Y262224D01*
X1350184Y261932D01*
Y261599D01*
X1350059Y261224D01*
X1349851Y260932D01*
X1349601Y260724D01*
X1349184Y260557D01*
X1348809Y260515D01*
X1348434Y260599D01*
X1348184Y260724D01*
X1347934Y260974D01*
X1347767Y261265D01*
X1347684Y261557D01*
Y261849D01*
X1347767Y262140D01*
X1347892Y262390D01*
X1348059Y262599D01*
G01X1347684Y264657D02*
X1350184D01*
X1349684Y264157D01*
G01X1347684D02*
Y265157D01*
G01Y267757D02*
X1347726Y268049D01*
X1347851Y268382D01*
X1348059Y268590D01*
X1348351Y268674D01*
X1348642Y268590D01*
X1348892Y268340D01*
X1349017Y267965D01*
Y267549D01*
X1349101Y267299D01*
X1349309Y267090D01*
X1349601Y267007D01*
X1349892Y267132D01*
X1350101Y267424D01*
X1350184Y267757D01*
X1350101Y268090D01*
X1349892Y268382D01*
X1349601Y268507D01*
X1349309Y268424D01*
X1349101Y268215D01*
X1349017Y267965D01*
Y267549D01*
X1348892Y267174D01*
X1348642Y266924D01*
X1348351Y266840D01*
X1348059Y266924D01*
X1347851Y267132D01*
X1347726Y267465D01*
X1347684Y267757D01*
G01Y271357D02*
X1350184D01*
X1348392Y269815D01*
Y271899D01*
G01X1370661Y274967D02*
X1373161D01*
Y275967D01*
X1373036Y276300D01*
X1372744Y276550D01*
X1372411Y276633D01*
X1372078Y276550D01*
X1371828Y276342D01*
X1371703Y275967D01*
Y274967D01*
G01X1370661Y278067D02*
X1373161D01*
Y279108D01*
X1373036Y279442D01*
X1372869Y279650D01*
X1372536Y279733D01*
X1372203Y279650D01*
X1371994Y279400D01*
X1371869Y279108D01*
Y278067D01*
G01Y279108D02*
X1370661Y279733D01*
G01Y282000D02*
X1373161D01*
X1372661Y281500D01*
G01X1370661D02*
Y282500D01*
G01X1371703Y284308D02*
X1371994Y284600D01*
X1372161Y284850D01*
X1372244Y285183D01*
X1372161Y285475D01*
X1371994Y285683D01*
X1371744Y285850D01*
X1371453Y285892D01*
X1371203Y285850D01*
X1370953Y285683D01*
X1370744Y285433D01*
X1370661Y285142D01*
X1370744Y284808D01*
X1370994Y284517D01*
X1371369Y284350D01*
X1371786Y284308D01*
X1372328Y284392D01*
X1372619Y284517D01*
X1372911Y284725D01*
X1373119Y285017D01*
X1373161Y285308D01*
X1373078Y285600D01*
X1372869Y285808D01*
G01X1371161Y287283D02*
X1370869Y287533D01*
X1370703Y287867D01*
X1370661Y288242D01*
X1370703Y288575D01*
X1370911Y288908D01*
X1371161Y289117D01*
X1371411Y289158D01*
X1371703Y289075D01*
X1371911Y288783D01*
X1371994Y288492D01*
Y288117D01*
G01Y288492D02*
X1372119Y288742D01*
X1372328Y288950D01*
X1372578Y289033D01*
X1372828Y288950D01*
X1373036Y288742D01*
X1373161Y288367D01*
X1373119Y287992D01*
X1372953Y287617D01*
G01X1362661Y274967D02*
X1365161D01*
Y275967D01*
X1365036Y276300D01*
X1364744Y276550D01*
X1364411Y276633D01*
X1364078Y276550D01*
X1363828Y276342D01*
X1363703Y275967D01*
Y274967D01*
G01X1362661Y278067D02*
X1365161D01*
Y279108D01*
X1365036Y279442D01*
X1364869Y279650D01*
X1364536Y279733D01*
X1364203Y279650D01*
X1363994Y279400D01*
X1363869Y279108D01*
Y278067D01*
G01Y279108D02*
X1362661Y279733D01*
G01Y282000D02*
X1365161D01*
X1364661Y281500D01*
G01X1362661D02*
Y282500D01*
G01X1363703Y284308D02*
X1363994Y284600D01*
X1364161Y284850D01*
X1364244Y285183D01*
X1364161Y285475D01*
X1363994Y285683D01*
X1363744Y285850D01*
X1363453Y285892D01*
X1363203Y285850D01*
X1362953Y285683D01*
X1362744Y285433D01*
X1362661Y285142D01*
X1362744Y284808D01*
X1362994Y284517D01*
X1363369Y284350D01*
X1363786Y284308D01*
X1364328Y284392D01*
X1364619Y284517D01*
X1364911Y284725D01*
X1365119Y285017D01*
X1365161Y285308D01*
X1365078Y285600D01*
X1364869Y285808D01*
G01X1364744Y287408D02*
X1364994Y287658D01*
X1365119Y287950D01*
X1365161Y288283D01*
X1365078Y288700D01*
X1364869Y288992D01*
X1364619Y289075D01*
X1364369Y289033D01*
X1364161Y288867D01*
X1363744Y288033D01*
X1363453Y287658D01*
X1363036Y287408D01*
X1362661Y287325D01*
Y289075D01*
G01X1366661Y278067D02*
X1369161D01*
Y279067D01*
X1369036Y279400D01*
X1368744Y279650D01*
X1368411Y279733D01*
X1368078Y279650D01*
X1367828Y279442D01*
X1367703Y279067D01*
Y278067D01*
G01X1366661Y281167D02*
X1369161D01*
Y282208D01*
X1369036Y282542D01*
X1368869Y282750D01*
X1368536Y282833D01*
X1368203Y282750D01*
X1367994Y282500D01*
X1367869Y282208D01*
Y281167D01*
G01Y282208D02*
X1366661Y282833D01*
G01X1368744Y284308D02*
X1368994Y284558D01*
X1369119Y284850D01*
X1369161Y285183D01*
X1369078Y285600D01*
X1368869Y285892D01*
X1368619Y285975D01*
X1368369Y285933D01*
X1368161Y285767D01*
X1367744Y284933D01*
X1367453Y284558D01*
X1367036Y284308D01*
X1366661Y284225D01*
Y285975D01*
G01X1357000Y277800D02*
X1353000D01*
Y285200D01*
G01X1361000Y277800D02*
X1357000D01*
Y285200D01*
G01X1353000Y277800D02*
X1349000D01*
Y285200D01*
G01X1354597Y680936D02*
X1357097D01*
Y681977D01*
X1356972Y682311D01*
X1356805Y682519D01*
X1356472Y682602D01*
X1356139Y682519D01*
X1355930Y682269D01*
X1355805Y681977D01*
Y680936D01*
G01Y681977D02*
X1354597Y682602D01*
G01X1355097Y683952D02*
X1354805Y684202D01*
X1354639Y684536D01*
X1354597Y684911D01*
X1354639Y685244D01*
X1354847Y685577D01*
X1355097Y685786D01*
X1355347Y685827D01*
X1355639Y685744D01*
X1355847Y685452D01*
X1355930Y685161D01*
Y684786D01*
G01Y685161D02*
X1356055Y685411D01*
X1356264Y685619D01*
X1356514Y685702D01*
X1356764Y685619D01*
X1356972Y685411D01*
X1357097Y685036D01*
X1357055Y684661D01*
X1356889Y684286D01*
G01X1356680Y687177D02*
X1356930Y687427D01*
X1357055Y687719D01*
X1357097Y688052D01*
X1357014Y688469D01*
X1356805Y688761D01*
X1356555Y688844D01*
X1356305Y688802D01*
X1356097Y688636D01*
X1355680Y687802D01*
X1355389Y687427D01*
X1354972Y687177D01*
X1354597Y687094D01*
Y688844D01*
G01X1355097Y690152D02*
X1354805Y690402D01*
X1354639Y690736D01*
X1354597Y691111D01*
X1354639Y691444D01*
X1354847Y691777D01*
X1355097Y691986D01*
X1355347Y692027D01*
X1355639Y691944D01*
X1355847Y691652D01*
X1355930Y691361D01*
Y690986D01*
G01Y691361D02*
X1356055Y691611D01*
X1356264Y691819D01*
X1356514Y691902D01*
X1356764Y691819D01*
X1356972Y691611D01*
X1357097Y691236D01*
X1357055Y690861D01*
X1356889Y690486D01*
G01X1357097Y694169D02*
X1357014Y693836D01*
X1356805Y693586D01*
X1356555Y693419D01*
X1356222Y693294D01*
X1355847Y693252D01*
X1355472Y693294D01*
X1355139Y693419D01*
X1354889Y693586D01*
X1354680Y693836D01*
X1354597Y694169D01*
X1354680Y694502D01*
X1354889Y694752D01*
X1355139Y694919D01*
X1355472Y695044D01*
X1355847Y695086D01*
X1356222Y695044D01*
X1356555Y694919D01*
X1356805Y694752D01*
X1357014Y694502D01*
X1357097Y694169D01*
G01X1363597Y680936D02*
X1366097D01*
Y681977D01*
X1365972Y682311D01*
X1365805Y682519D01*
X1365472Y682602D01*
X1365139Y682519D01*
X1364930Y682269D01*
X1364805Y681977D01*
Y680936D01*
G01Y681977D02*
X1363597Y682602D01*
G01X1364097Y683952D02*
X1363805Y684202D01*
X1363639Y684536D01*
X1363597Y684911D01*
X1363639Y685244D01*
X1363847Y685577D01*
X1364097Y685786D01*
X1364347Y685827D01*
X1364639Y685744D01*
X1364847Y685452D01*
X1364930Y685161D01*
Y684786D01*
G01Y685161D02*
X1365055Y685411D01*
X1365264Y685619D01*
X1365514Y685702D01*
X1365764Y685619D01*
X1365972Y685411D01*
X1366097Y685036D01*
X1366055Y684661D01*
X1365889Y684286D01*
G01X1365680Y687177D02*
X1365930Y687427D01*
X1366055Y687719D01*
X1366097Y688052D01*
X1366014Y688469D01*
X1365805Y688761D01*
X1365555Y688844D01*
X1365305Y688802D01*
X1365097Y688636D01*
X1364680Y687802D01*
X1364389Y687427D01*
X1363972Y687177D01*
X1363597Y687094D01*
Y688844D01*
G01Y691569D02*
X1366097D01*
X1364305Y690027D01*
Y692111D01*
G01X1363972Y693252D02*
X1363764Y693502D01*
X1363639Y693794D01*
X1363597Y694169D01*
X1363680Y694544D01*
X1363847Y694836D01*
X1364139Y695044D01*
X1364472Y695086D01*
X1364805Y695002D01*
X1365014Y694794D01*
X1365180Y694502D01*
X1365222Y694211D01*
X1365180Y693919D01*
X1365014Y693544D01*
X1366097Y693669D01*
Y694794D01*
G01X1352808Y682944D02*
X1352933Y682694D01*
X1353016Y682402D01*
Y682069D01*
X1352891Y681694D01*
X1352683Y681402D01*
X1352433Y681194D01*
X1352016Y681027D01*
X1351641Y680985D01*
X1351266Y681069D01*
X1351016Y681194D01*
X1350766Y681444D01*
X1350599Y681735D01*
X1350516Y682027D01*
Y682319D01*
X1350599Y682610D01*
X1350724Y682860D01*
X1350891Y683069D01*
G01X1351016Y684210D02*
X1350724Y684460D01*
X1350558Y684794D01*
X1350516Y685169D01*
X1350558Y685502D01*
X1350766Y685835D01*
X1351016Y686044D01*
X1351266Y686085D01*
X1351558Y686002D01*
X1351766Y685710D01*
X1351849Y685419D01*
Y685044D01*
G01Y685419D02*
X1351974Y685669D01*
X1352183Y685877D01*
X1352433Y685960D01*
X1352683Y685877D01*
X1352891Y685669D01*
X1353016Y685294D01*
X1352974Y684919D01*
X1352808Y684544D01*
G01X1352599Y687435D02*
X1352849Y687685D01*
X1352974Y687977D01*
X1353016Y688310D01*
X1352933Y688727D01*
X1352724Y689019D01*
X1352474Y689102D01*
X1352224Y689060D01*
X1352016Y688894D01*
X1351599Y688060D01*
X1351308Y687685D01*
X1350891Y687435D01*
X1350516Y687352D01*
Y689102D01*
G01X1353016Y691327D02*
X1352933Y690994D01*
X1352724Y690744D01*
X1352474Y690577D01*
X1352141Y690452D01*
X1351766Y690410D01*
X1351391Y690452D01*
X1351058Y690577D01*
X1350808Y690744D01*
X1350599Y690994D01*
X1350516Y691327D01*
X1350599Y691660D01*
X1350808Y691910D01*
X1351058Y692077D01*
X1351391Y692202D01*
X1351766Y692244D01*
X1352141Y692202D01*
X1352474Y692077D01*
X1352724Y691910D01*
X1352933Y691660D01*
X1353016Y691327D01*
G01X1351558Y693635D02*
X1351849Y693927D01*
X1352016Y694177D01*
X1352099Y694510D01*
X1352016Y694802D01*
X1351849Y695010D01*
X1351599Y695177D01*
X1351308Y695219D01*
X1351058Y695177D01*
X1350808Y695010D01*
X1350599Y694760D01*
X1350516Y694469D01*
X1350599Y694135D01*
X1350849Y693844D01*
X1351224Y693677D01*
X1351641Y693635D01*
X1352183Y693719D01*
X1352474Y693844D01*
X1352766Y694052D01*
X1352974Y694344D01*
X1353016Y694635D01*
X1352933Y694927D01*
X1352724Y695135D01*
G01X1361450Y682586D02*
X1361575Y682336D01*
X1361658Y682044D01*
Y681711D01*
X1361533Y681336D01*
X1361325Y681044D01*
X1361075Y680836D01*
X1360658Y680669D01*
X1360283Y680627D01*
X1359908Y680711D01*
X1359658Y680836D01*
X1359408Y681086D01*
X1359241Y681377D01*
X1359158Y681669D01*
Y681961D01*
X1359241Y682252D01*
X1359366Y682502D01*
X1359533Y682711D01*
G01X1359658Y683852D02*
X1359366Y684102D01*
X1359200Y684436D01*
X1359158Y684811D01*
X1359200Y685144D01*
X1359408Y685477D01*
X1359658Y685686D01*
X1359908Y685727D01*
X1360200Y685644D01*
X1360408Y685352D01*
X1360491Y685061D01*
Y684686D01*
G01Y685061D02*
X1360616Y685311D01*
X1360825Y685519D01*
X1361075Y685602D01*
X1361325Y685519D01*
X1361533Y685311D01*
X1361658Y684936D01*
X1361616Y684561D01*
X1361450Y684186D01*
G01X1361241Y687077D02*
X1361491Y687327D01*
X1361616Y687619D01*
X1361658Y687952D01*
X1361575Y688369D01*
X1361366Y688661D01*
X1361116Y688744D01*
X1360866Y688702D01*
X1360658Y688536D01*
X1360241Y687702D01*
X1359950Y687327D01*
X1359533Y687077D01*
X1359158Y686994D01*
Y688744D01*
G01X1361658Y690969D02*
X1361575Y690636D01*
X1361366Y690386D01*
X1361116Y690219D01*
X1360783Y690094D01*
X1360408Y690052D01*
X1360033Y690094D01*
X1359700Y690219D01*
X1359450Y690386D01*
X1359241Y690636D01*
X1359158Y690969D01*
X1359241Y691302D01*
X1359450Y691552D01*
X1359700Y691719D01*
X1360033Y691844D01*
X1360408Y691886D01*
X1360783Y691844D01*
X1361116Y691719D01*
X1361366Y691552D01*
X1361575Y691302D01*
X1361658Y690969D01*
G01X1359158Y694569D02*
X1361658D01*
X1359866Y693027D01*
Y695111D01*
G01X1362658Y700134D02*
X1360866D01*
X1360491Y700301D01*
X1360241Y700634D01*
X1360158Y701051D01*
X1360241Y701468D01*
X1360491Y701801D01*
X1360866Y701968D01*
X1362658D01*
G01X1360158Y704068D02*
X1360700Y704151D01*
X1361158Y704276D01*
X1361575Y704443D01*
X1362033Y704651D01*
X1362658Y704984D01*
Y703318D01*
G01X1360158Y707251D02*
X1360200Y707543D01*
X1360325Y707876D01*
X1360533Y708084D01*
X1360825Y708168D01*
X1361116Y708084D01*
X1361366Y707834D01*
X1361491Y707459D01*
Y707043D01*
X1361575Y706793D01*
X1361783Y706584D01*
X1362075Y706501D01*
X1362366Y706626D01*
X1362575Y706918D01*
X1362658Y707251D01*
X1362575Y707584D01*
X1362366Y707876D01*
X1362075Y708001D01*
X1361783Y707918D01*
X1361575Y707709D01*
X1361491Y707459D01*
Y707043D01*
X1361366Y706668D01*
X1361116Y706418D01*
X1360825Y706334D01*
X1360533Y706418D01*
X1360325Y706626D01*
X1360200Y706959D01*
X1360158Y707251D01*
G01X1349222Y697269D02*
Y710669D01*
G01X1354673Y699375D02*
X1357173D01*
Y700416D01*
X1357048Y700750D01*
X1356881Y700958D01*
X1356548Y701041D01*
X1356215Y700958D01*
X1356006Y700708D01*
X1355881Y700416D01*
Y699375D01*
G01Y700416D02*
X1354673Y701041D01*
G01X1356756Y702516D02*
X1357006Y702766D01*
X1357131Y703058D01*
X1357173Y703391D01*
X1357090Y703808D01*
X1356881Y704100D01*
X1356631Y704183D01*
X1356381Y704141D01*
X1356173Y703975D01*
X1355756Y703141D01*
X1355465Y702766D01*
X1355048Y702516D01*
X1354673Y702433D01*
Y704183D01*
G01Y706325D02*
X1355215Y706408D01*
X1355673Y706533D01*
X1356090Y706700D01*
X1356548Y706908D01*
X1357173Y707241D01*
Y705575D01*
G01X1355715Y708716D02*
X1356006Y709008D01*
X1356173Y709258D01*
X1356256Y709591D01*
X1356173Y709883D01*
X1356006Y710091D01*
X1355756Y710258D01*
X1355465Y710300D01*
X1355215Y710258D01*
X1354965Y710091D01*
X1354756Y709841D01*
X1354673Y709550D01*
X1354756Y709216D01*
X1355006Y708925D01*
X1355381Y708758D01*
X1355798Y708716D01*
X1356340Y708800D01*
X1356631Y708925D01*
X1356923Y709133D01*
X1357131Y709425D01*
X1357173Y709716D01*
X1357090Y710008D01*
X1356881Y710216D01*
G01X1350600Y721367D02*
X1353100D01*
Y722408D01*
X1352975Y722742D01*
X1352808Y722950D01*
X1352475Y723033D01*
X1352142Y722950D01*
X1351933Y722700D01*
X1351808Y722408D01*
Y721367D01*
G01Y722408D02*
X1350600Y723033D01*
G01X1351100Y724383D02*
X1350808Y724633D01*
X1350642Y724967D01*
X1350600Y725342D01*
X1350642Y725675D01*
X1350850Y726008D01*
X1351100Y726217D01*
X1351350Y726258D01*
X1351642Y726175D01*
X1351850Y725883D01*
X1351933Y725592D01*
Y725217D01*
G01Y725592D02*
X1352058Y725842D01*
X1352267Y726050D01*
X1352517Y726133D01*
X1352767Y726050D01*
X1352975Y725842D01*
X1353100Y725467D01*
X1353058Y725092D01*
X1352892Y724717D01*
G01X1352683Y727608D02*
X1352933Y727858D01*
X1353058Y728150D01*
X1353100Y728483D01*
X1353017Y728900D01*
X1352808Y729192D01*
X1352558Y729275D01*
X1352308Y729233D01*
X1352100Y729067D01*
X1351683Y728233D01*
X1351392Y727858D01*
X1350975Y727608D01*
X1350600Y727525D01*
Y729275D01*
G01X1352683Y730708D02*
X1352933Y730958D01*
X1353058Y731250D01*
X1353100Y731583D01*
X1353017Y732000D01*
X1352808Y732292D01*
X1352558Y732375D01*
X1352308Y732333D01*
X1352100Y732167D01*
X1351683Y731333D01*
X1351392Y730958D01*
X1350975Y730708D01*
X1350600Y730625D01*
Y732375D01*
G01Y734600D02*
X1350642Y734892D01*
X1350767Y735225D01*
X1350975Y735433D01*
X1351267Y735517D01*
X1351558Y735433D01*
X1351808Y735183D01*
X1351933Y734808D01*
Y734392D01*
X1352017Y734142D01*
X1352225Y733933D01*
X1352517Y733850D01*
X1352808Y733975D01*
X1353017Y734267D01*
X1353100Y734600D01*
X1353017Y734933D01*
X1352808Y735225D01*
X1352517Y735350D01*
X1352225Y735267D01*
X1352017Y735058D01*
X1351933Y734808D01*
Y734392D01*
X1351808Y734017D01*
X1351558Y733767D01*
X1351267Y733683D01*
X1350975Y733767D01*
X1350767Y733975D01*
X1350642Y734308D01*
X1350600Y734600D01*
G01X1359100Y721367D02*
X1361600D01*
Y722408D01*
X1361475Y722742D01*
X1361308Y722950D01*
X1360975Y723033D01*
X1360642Y722950D01*
X1360433Y722700D01*
X1360308Y722408D01*
Y721367D01*
G01Y722408D02*
X1359100Y723033D01*
G01X1359600Y724383D02*
X1359308Y724633D01*
X1359142Y724967D01*
X1359100Y725342D01*
X1359142Y725675D01*
X1359350Y726008D01*
X1359600Y726217D01*
X1359850Y726258D01*
X1360142Y726175D01*
X1360350Y725883D01*
X1360433Y725592D01*
Y725217D01*
G01Y725592D02*
X1360558Y725842D01*
X1360767Y726050D01*
X1361017Y726133D01*
X1361267Y726050D01*
X1361475Y725842D01*
X1361600Y725467D01*
X1361558Y725092D01*
X1361392Y724717D01*
G01X1361183Y727608D02*
X1361433Y727858D01*
X1361558Y728150D01*
X1361600Y728483D01*
X1361517Y728900D01*
X1361308Y729192D01*
X1361058Y729275D01*
X1360808Y729233D01*
X1360600Y729067D01*
X1360183Y728233D01*
X1359892Y727858D01*
X1359475Y727608D01*
X1359100Y727525D01*
Y729275D01*
G01Y732000D02*
X1361600D01*
X1359808Y730458D01*
Y732542D01*
G01X1359600Y733683D02*
X1359308Y733933D01*
X1359142Y734267D01*
X1359100Y734642D01*
X1359142Y734975D01*
X1359350Y735308D01*
X1359600Y735517D01*
X1359850Y735558D01*
X1360142Y735475D01*
X1360350Y735183D01*
X1360433Y734892D01*
Y734517D01*
G01Y734892D02*
X1360558Y735142D01*
X1360767Y735350D01*
X1361017Y735433D01*
X1361267Y735350D01*
X1361475Y735142D01*
X1361600Y734767D01*
X1361558Y734392D01*
X1361392Y734017D01*
G01X1355100Y721367D02*
X1357600D01*
Y722408D01*
X1357475Y722742D01*
X1357308Y722950D01*
X1356975Y723033D01*
X1356642Y722950D01*
X1356433Y722700D01*
X1356308Y722408D01*
Y721367D01*
G01Y722408D02*
X1355100Y723033D01*
G01X1355600Y724383D02*
X1355308Y724633D01*
X1355142Y724967D01*
X1355100Y725342D01*
X1355142Y725675D01*
X1355350Y726008D01*
X1355600Y726217D01*
X1355850Y726258D01*
X1356142Y726175D01*
X1356350Y725883D01*
X1356433Y725592D01*
Y725217D01*
G01Y725592D02*
X1356558Y725842D01*
X1356767Y726050D01*
X1357017Y726133D01*
X1357267Y726050D01*
X1357475Y725842D01*
X1357600Y725467D01*
X1357558Y725092D01*
X1357392Y724717D01*
G01X1357183Y727608D02*
X1357433Y727858D01*
X1357558Y728150D01*
X1357600Y728483D01*
X1357517Y728900D01*
X1357308Y729192D01*
X1357058Y729275D01*
X1356808Y729233D01*
X1356600Y729067D01*
X1356183Y728233D01*
X1355892Y727858D01*
X1355475Y727608D01*
X1355100Y727525D01*
Y729275D01*
G01Y732000D02*
X1357600D01*
X1355808Y730458D01*
Y732542D01*
G01X1355100Y735100D02*
X1357600D01*
X1355808Y733558D01*
Y735642D01*
G54D16*
G01X65500Y272100D02*
X66600D01*
G01X68200D02*
X69300D01*
G01X70200D02*
X71300D01*
G01X72900D02*
X74000D01*
G01X226600Y159000D02*
X227700D01*
G01X229300D02*
X230400D01*
G01X279500Y141400D02*
Y142500D01*
G01X278200Y156900D02*
X274200D01*
G01X283100Y146900D02*
Y150900D01*
G01X279500Y144100D02*
Y145200D01*
G01X304500Y778100D02*
Y782100D01*
G01X576434Y242470D02*
Y241370D01*
G01Y245170D02*
Y244070D01*
G01X624063Y231108D02*
Y235108D01*
G01X629563Y236208D02*
Y237308D01*
G01Y238908D02*
Y240008D01*
G01X649800Y790200D02*
Y786200D01*
G01X698000Y815300D02*
Y819300D01*
G01X719087Y203842D02*
Y202742D01*
G01Y201142D02*
Y200042D01*
G01X949400Y44900D02*
Y46000D01*
G01Y42200D02*
Y43300D01*
G01X1037500Y53500D02*
X1041500D01*
G01X1165607Y821010D02*
Y825010D01*
G01X1309500Y270600D02*
Y269500D01*
G01Y273300D02*
Y272200D01*
G01X1315900Y268500D02*
Y264500D01*
G01X1326700Y815400D02*
Y819400D01*
G01X1366300Y255300D02*
Y256400D01*
G01Y252600D02*
Y253700D01*
M02*
